(kicad_pcb
	(version 20241229)
	(generator "pcbnew")
	(generator_version "9.0")
	(general
		(thickness 1.6)
		(legacy_teardrops no)
	)
	(paper "A4")
	(title_block
		(title "GMSL Deserializer")
		(date "2025-10-09")
		(rev "1.0.4")
		(company "Antmicro Ltd")
		(comment 1 "www.antmicro.com")
	)
	(layers
		(0 "F.Cu" signal)
		(4 "In1.Cu" power)
		(6 "In2.Cu" power)
		(2 "B.Cu" signal)
		(9 "F.Adhes" user "F.Adhesive")
		(11 "B.Adhes" user "B.Adhesive")
		(13 "F.Paste" user)
		(15 "B.Paste" user)
		(5 "F.SilkS" user "F.Silkscreen")
		(7 "B.SilkS" user "B.Silkscreen")
		(1 "F.Mask" user)
		(3 "B.Mask" user)
		(17 "Dwgs.User" user "User.Drawings")
		(19 "Cmts.User" user "User.Comments")
		(21 "Eco1.User" user "User.Eco1")
		(23 "Eco2.User" user "User.Eco2")
		(25 "Edge.Cuts" user)
		(27 "Margin" user)
		(31 "F.CrtYd" user "F.Courtyard")
		(29 "B.CrtYd" user "B.Courtyard")
		(35 "F.Fab" user)
		(33 "B.Fab" user)
	)
	(setup
		(stackup
			(layer "F.SilkS"
				(type "Top Silk Screen")
				(color "White")
			)
			(layer "F.Paste"
				(type "Top Solder Paste")
			)
			(layer "F.Mask"
				(type "Top Solder Mask")
				(color "Black")
				(thickness 0.01)
			)
			(layer "F.Cu"
				(type "copper")
				(thickness 0.035)
			)
			(layer "dielectric 1"
				(type "prepreg")
				(thickness 0.12)
				(material "FR4")
				(epsilon_r 4.5)
				(loss_tangent 0.02)
			)
			(layer "In1.Cu"
				(type "copper")
				(thickness 0.035)
			)
			(layer "dielectric 2"
				(type "core")
				(thickness 1.2)
				(material "FR4")
				(epsilon_r 4.5)
				(loss_tangent 0.02)
			)
			(layer "In2.Cu"
				(type "copper")
				(thickness 0.035)
			)
			(layer "dielectric 3"
				(type "prepreg")
				(thickness 0.12)
				(material "FR4")
				(epsilon_r 4.5)
				(loss_tangent 0.02)
			)
			(layer "B.Cu"
				(type "copper")
				(thickness 0.035)
			)
			(layer "B.Mask"
				(type "Bottom Solder Mask")
				(color "Black")
				(thickness 0.01)
			)
			(layer "B.Paste"
				(type "Bottom Solder Paste")
			)
			(layer "B.SilkS"
				(type "Bottom Silk Screen")
				(color "White")
			)
			(copper_finish "None")
			(dielectric_constraints yes)
		)
		(pad_to_mask_clearance 0)
		(allow_soldermask_bridges_in_footprints no)
		(tenting front back)
		(pcbplotparams
			(layerselection 0x00000000_00000000_55555555_5755f5ff)
			(plot_on_all_layers_selection 0x00000000_00000000_00000000_00000000)
			(disableapertmacros no)
			(usegerberextensions no)
			(usegerberattributes yes)
			(usegerberadvancedattributes yes)
			(creategerberjobfile yes)
			(dashed_line_dash_ratio 12.000000)
			(dashed_line_gap_ratio 3.000000)
			(svgprecision 6)
			(plotframeref no)
			(mode 1)
			(useauxorigin no)
			(hpglpennumber 1)
			(hpglpenspeed 20)
			(hpglpendiameter 15.000000)
			(pdf_front_fp_property_popups yes)
			(pdf_back_fp_property_popups yes)
			(pdf_metadata yes)
			(pdf_single_document no)
			(dxfpolygonmode yes)
			(dxfimperialunits yes)
			(dxfusepcbnewfont yes)
			(psnegative no)
			(psa4output no)
			(plot_black_and_white yes)
			(sketchpadsonfab no)
			(plotpadnumbers no)
			(hidednponfab no)
			(sketchdnponfab yes)
			(crossoutdnponfab yes)
			(subtractmaskfromsilk no)
			(outputformat 1)
			(mirror no)
			(drillshape 1)
			(scaleselection 1)
			(outputdirectory "")
		)
	)
	(net 0 "")
	(net 1 "GND")
	(net 2 "/Connectors/DC_UNFUSED")
	(net 3 "+1V8")
	(net 4 "+12V")
	(net 5 "+5V")
	(net 6 "Net-(U4-BST)")
	(net 7 "/Power/SW_1V8")
	(net 8 "Net-(U5-BST)")
	(net 9 "/Power/SW_1V2")
	(net 10 "/Power/OUT_1V8")
	(net 11 "/Power/OUT_1V2")
	(net 12 "/Deserializer/X1")
	(net 13 "/Deserializer/SIOA_P")
	(net 14 "/Deserializer/SIOB_P")
	(net 15 "/Deserializer/SIOC_P")
	(net 16 "/Deserializer/SIOD_P")
	(net 17 "/Deserializer/X2_R")
	(net 18 "/Deserializer/SIOA_N")
	(net 19 "Net-(C32-Pad2)")
	(net 20 "/Deserializer/SIOB_N")
	(net 21 "Net-(C33-Pad2)")
	(net 22 "/Deserializer/SIOC_N")
	(net 23 "Net-(C34-Pad2)")
	(net 24 "/Deserializer/SIOD_N")
	(net 25 "Net-(C35-Pad2)")
	(net 26 "/Deserializer/VDD_1.8V")
	(net 27 "/Deserializer/VDD")
	(net 28 "/Deserializer/CAP_VDD")
	(net 29 "/Deserializer/VTERM")
	(net 30 "unconnected-(J6-Pad13)")
	(net 31 "unconnected-(J6-Pad14)")
	(net 32 "unconnected-(J6-Pad16)")
	(net 33 "unconnected-(J6-Pad17)")
	(net 34 "unconnected-(J6-Pad31)")
	(net 35 "Net-(J6-Pad32)")
	(net 36 "unconnected-(J6-Pad33)")
	(net 37 "Net-(J6-Pad34)")
	(net 38 "unconnected-(J6-Pad35)")
	(net 39 "unconnected-(J6-Pad36)")
	(net 40 "unconnected-(J6-Pad37)")
	(net 41 "unconnected-(J6-Pad38)")
	(net 42 "/Connectors/SDA_CAM1")
	(net 43 "/Connectors/SCL_CAM1")
	(net 44 "/Connectors/SDA_CAM")
	(net 45 "/Connectors/SCL_CAM")
	(net 46 "unconnected-(J6-Pad43)")
	(net 47 "unconnected-(J6-Pad44)")
	(net 48 "unconnected-(J6-Pad45)")
	(net 49 "unconnected-(J6-Pad46)")
	(net 50 "/Connectors/FFC_3V3")
	(net 51 "Net-(L1-Pad2)")
	(net 52 "Net-(L2-Pad2)")
	(net 53 "Net-(L3-Pad2)")
	(net 54 "Net-(L4-Pad2)")
	(net 55 "Net-(L5-Pad2)")
	(net 56 "Net-(L10-Pad1)")
	(net 57 "Net-(L11-Pad1)")
	(net 58 "Net-(L12-Pad1)")
	(net 59 "Net-(L13-Pad1)")
	(net 60 "Net-(L10-Pad2)")
	(net 61 "Net-(L11-Pad2)")
	(net 62 "Net-(L12-Pad2)")
	(net 63 "/Power/FFC_5V_EN")
	(net 64 "Net-(D2-C)")
	(net 65 "Net-(D12-C)")
	(net 66 "/Connectors/VSYNC_CAM1")
	(net 67 "/Connectors/VSYNC_CAM0")
	(net 68 "/Power/EN_1V2")
	(net 69 "/Power/EN_1V8")
	(net 70 "/Power/FB_1V8")
	(net 71 "/Power/FB_1V2")
	(net 72 "/Power/FFC_5V_FLG")
	(net 73 "+1V2")
	(net 74 "/Power/FFC_5V_ISET")
	(net 75 "/Deserializer/X2")
	(net 76 "/Deserializer/CFG0")
	(net 77 "/Deserializer/CFG1")
	(net 78 "/Deserializer/XRES")
	(net 79 "/Deserializer/PWDNB")
	(net 80 "/Connectors/MFP0")
	(net 81 "/Connectors/MFP1")
	(net 82 "/Connectors/MFP2")
	(net 83 "/Connectors/MFP3")
	(net 84 "/Connectors/MFP4")
	(net 85 "/Connectors/MFP5")
	(net 86 "/Connectors/MFP7")
	(net 87 "/Connectors/MFP8")
	(net 88 "/Connectors/SDA")
	(net 89 "/Connectors/CSI0.D1_N")
	(net 90 "/Connectors/CSI0.D1_P")
	(net 91 "/Connectors/CSI0.D0_N")
	(net 92 "/Connectors/CSI0.D0_P")
	(net 93 "/Connectors/CSI1.D1_N")
	(net 94 "/Connectors/CSI1.D1_P")
	(net 95 "/Connectors/CSI1.D0_N")
	(net 96 "/Connectors/CSI1.D0_P")
	(net 97 "/Connectors/CSI1.CLK_N")
	(net 98 "/Connectors/CSI1.CLK_P")
	(net 99 "/Connectors/CSI0.D3_N")
	(net 100 "/Connectors/CSI0.D3_P")
	(net 101 "/Connectors/CSI0.D2_N")
	(net 102 "/Connectors/CSI0.D2_P")
	(net 103 "/Connectors/CSI0.CLK_N")
	(net 104 "/Connectors/CSI0.CLK_P")
	(net 105 "/Connectors/CSI1.D3_N")
	(net 106 "/Connectors/CSI1.D3_P")
	(net 107 "/Connectors/CSI1.D2_N")
	(net 108 "/Connectors/CSI1.D2_P")
	(net 109 "Net-(D13-C)")
	(net 110 "Net-(D14-A)")
	(net 111 "Net-(D14-C)")
	(net 112 "Net-(D15-C)")
	(net 113 "/Connectors/FFC_5V")
	(net 114 "/Connectors/PoCA")
	(net 115 "/Connectors/PoCB")
	(net 116 "/Connectors/PoCC")
	(net 117 "/Connectors/PoCD")
	(net 118 "/Connectors/DC_IN")
	(net 119 "/Connectors/SDA_CAM0")
	(net 120 "/Connectors/SCL_CAM0")
	(net 121 "/Connectors/SCL")
	(net 122 "/Power/FB_12V")
	(net 123 "/Power/OUT_12V")
	(net 124 "/Power/SW_12V")
	(net 125 "/Power/EN_12V")
	(net 126 "Net-(Q1-G)")
	(net 127 "Net-(Q2-G)")
	(net 128 "Net-(Q3-REF)")
	(net 129 "Net-(U1-~{OE})")
	(net 130 "Net-(U1-Y)")
	(net 131 "Net-(U2-~{OE})")
	(net 132 "Net-(U2-Y)")
	(net 133 "Net-(U8-A_{1})")
	(net 134 "Net-(U8-A_{2})")
	(net 135 "Net-(U8-OE)")
	(net 136 "unconnected-(U7-CKC_P-Pad33)")
	(net 137 "unconnected-(U7-CKC_N-Pad34)")
	(net 138 "unconnected-(U7-CKF_P-Pad51)")
	(net 139 "unconnected-(U7-CKF_N-Pad52)")
	(net 140 "Net-(D16-C)")
	(net 141 "Net-(D17-C)")
	(net 142 "Net-(D18-C)")
	(net 143 "Net-(D19-C)")
	(net 144 "Net-(D19-A)")
	(net 145 "Net-(D20-C)")
	(net 146 "VDDIO")
	(net 147 "Net-(D20-A)")
	(net 148 "unconnected-(Q3-NC-Pad5)")
	(net 149 "unconnected-(Q3-NC-Pad1)")
	(footprint "antmicro-footprints:SOD-523_NP"
		(layer "F.Cu")
		(at 187.198 56.261)
		(property "Reference" "D11"
			(at 0.848 0.45 0)
			(layer "F.SilkS")
			(effects
				(font
					(size 0.7 0.7)
					(thickness 0.15)
				)
				(justify left bottom)
			)
		)
		(property "Value" "ESD5B5_0ST1G"
			(at 0 1.499 0)
			(layer "F.Fab")
			(effects
				(font
					(size 0.7 0.7)
					(thickness 0.15)
				)
				(justify left bottom)
			)
		)
		(property "Datasheet" "https://www.onsemi.com/pdf/datasheet/esd5b5.0st1-d.pdf"
			(at 0 0 0)
			(layer "F.Fab")
			(hide yes)
			(effects
				(font
					(size 1.27 1.27)
					(thickness 0.15)
				)
			)
		)
		(property "Description" "Bidirectional TVS, 30 kV,  SOD-523, 5 V, 32 pF"
			(at 0 0 0)
			(layer "F.Fab")
			(hide yes)
			(effects
				(font
					(size 1.27 1.27)
					(thickness 0.15)
				)
			)
		)
		(property "Author" "Antmicro"
			(at 0 0 0)
			(layer "F.Fab")
			(hide yes)
			(effects
				(font
					(size 1 1)
					(thickness 0.15)
				)
			)
		)
		(property "License" "Apache-2.0"
			(at 0 0 0)
			(layer "F.Fab")
			(hide yes)
			(effects
				(font
					(size 1 1)
					(thickness 0.15)
				)
			)
		)
		(property "MPN" "ESD5B5.0ST1G"
			(at 0 0 0)
			(layer "F.Fab")
			(hide yes)
			(effects
				(font
					(size 1 1)
					(thickness 0.15)
				)
			)
		)
		(property "Manufacturer" "ON Semiconductor"
			(at 0 0 0)
			(layer "F.Fab")
			(hide yes)
			(effects
				(font
					(size 1 1)
					(thickness 0.15)
				)
			)
		)
		(sheetname "/Connectors/")
		(sheetfile "connectors.kicad_sch")
		(attr smd)
		(fp_rect
			(start -1 -0.6)
			(end 1 0.6)
			(stroke
				(width 0.05)
				(type solid)
			)
			(fill no)
			(layer "F.CrtYd")
		)
		(fp_line
			(start -0.652 -0.425)
			(end 0.65 -0.425)
			(stroke
				(width 0.15)
				(type solid)
			)
			(layer "F.Fab")
		)
		(fp_line
			(start -0.652 0.423)
			(end -0.652 -0.425)
			(stroke
				(width 0.15)
				(type solid)
			)
			(layer "F.Fab")
		)
		(fp_line
			(start -0.652 0.423)
			(end 0.65 0.423)
			(stroke
				(width 0.15)
				(type solid)
			)
			(layer "F.Fab")
		)
		(fp_line
			(start 0.65 -0.425)
			(end 0.65 0.423)
			(stroke
				(width 0.15)
				(type solid)
			)
			(layer "F.Fab")
		)
		(pad "1" smd roundrect
			(at -0.701 0)
			(size 0.5 0.6)
			(layers "F.Cu" "F.Mask" "F.Paste")
			(roundrect_rratio 0.25)
			(net 1 "GND")
			(pinfunction "C")
			(pintype "passive")
		)
		(pad "2" smd roundrect
			(at 0.699 0)
			(size 0.5 0.6)
			(layers "F.Cu" "F.Mask" "F.Paste")
			(roundrect_rratio 0.25)
			(net 113 "/Connectors/FFC_5V")
			(pinfunction "A")
			(pintype "passive")
		)
	)
	(footprint "antmicro-footprints:TP_SMD_0.75mm"
		(layer "F.Cu")
		(at 136.318 76.3)
		(property "Reference" "TP5"
			(at 0 -0.6 0)
			(layer "F.SilkS")
			(hide yes)
			(effects
				(font
					(size 0.7 0.7)
					(thickness 0.15)
				)
				(justify left bottom)
			)
		)
		(property "Value" "TP_0.75mm_SMD"
			(at 0 1.2 0)
			(layer "F.Fab")
			(effects
				(font
					(size 0.7 0.7)
					(thickness 0.15)
				)
				(justify left bottom)
			)
		)
		(property "Description" "SMT test point"
			(at 0 0 0)
			(layer "F.Fab")
			(hide yes)
			(effects
				(font
					(size 1.27 1.27)
					(thickness 0.15)
				)
			)
		)
		(property "Author" "Antmicro"
			(at 0 0 0)
			(layer "F.Fab")
			(hide yes)
			(effects
				(font
					(size 1 1)
					(thickness 0.15)
				)
			)
		)
		(property "License" "Apache-2.0"
			(at 0 0 0)
			(layer "F.Fab")
			(hide yes)
			(effects
				(font
					(size 1 1)
					(thickness 0.15)
				)
			)
		)
		(property "MPN" ""
			(at 0 0 0)
			(layer "F.Fab")
			(hide yes)
			(effects
				(font
					(size 1 1)
					(thickness 0.15)
				)
			)
		)
		(property "Manufacturer" ""
			(at 0 0 0)
			(layer "F.Fab")
			(hide yes)
			(effects
				(font
					(size 1 1)
					(thickness 0.15)
				)
			)
		)
		(sheetname "/Connectors/")
		(sheetfile "connectors.kicad_sch")
		(fp_circle
			(center 0 0)
			(end 0.475 0)
			(stroke
				(width 0.05)
				(type default)
			)
			(fill no)
			(layer "F.CrtYd")
		)
		(pad "1" smd circle
			(at 0 0)
			(size 0.75 0.75)
			(layers "F.Cu" "F.Mask")
			(net 1 "GND")
			(pinfunction "1")
			(pintype "passive")
		)
	)
	(footprint "antmicro-footprints:R_0402_1005Metric"
		(layer "F.Cu")
		(at 140.89 78.8 135)
		(descr "Resistor SMD 0402")
		(tags "resistor SMD 0402")
		(property "Reference" "R50"
			(at 3.57796 -0.8457 315)
			(unlocked yes)
			(layer "F.SilkS")
			(effects
				(font
					(size 0.7 0.7)
					(thickness 0.15)
				)
				(justify left bottom)
			)
		)
		(property "Value" "R_80k6_0402"
			(at -1.011843 1.772046 135)
			(layer "F.Fab")
			(effects
				(font
					(size 0.7 0.7)
					(thickness 0.15)
				)
				(justify left bottom)
			)
		)
		(property "Datasheet" "https://www.bourns.com/docs/product-datasheets/cr.pdf"
			(at 0 0 135)
			(layer "F.Fab")
			(hide yes)
			(effects
				(font
					(size 1.27 1.27)
					(thickness 0.15)
				)
			)
		)
		(property "Description" "SMD Chip Resistor, 80.6 kohm, ± 1%, 100 mW, 0402 [1005 Metric], Thick Film, Precision"
			(at 0 0 135)
			(layer "F.Fab")
			(hide yes)
			(effects
				(font
					(size 1.27 1.27)
					(thickness 0.15)
				)
			)
		)
		(property "Author" "Antmicro"
			(at 296.328431 34.736745 0)
			(layer "F.Fab")
			(hide yes)
			(effects
				(font
					(size 1 1)
					(thickness 0.15)
				)
			)
		)
		(property "License" "Apache-2.0"
			(at 296.328431 34.736745 0)
			(layer "F.Fab")
			(hide yes)
			(effects
				(font
					(size 1 1)
					(thickness 0.15)
				)
			)
		)
		(property "MPN" "CR0402-FX-8062GLF"
			(at 296.328431 34.736745 0)
			(layer "F.Fab")
			(hide yes)
			(effects
				(font
					(size 1 1)
					(thickness 0.15)
				)
			)
		)
		(property "Manufacturer" "Bourns"
			(at 296.328431 34.736745 0)
			(layer "F.Fab")
			(hide yes)
			(effects
				(font
					(size 1 1)
					(thickness 0.15)
				)
			)
		)
		(property "Tolerance" "1%"
			(at 296.328431 34.736745 0)
			(layer "F.Fab")
			(hide yes)
			(effects
				(font
					(size 1 1)
					(thickness 0.15)
				)
			)
		)
		(property "Val" "80k6"
			(at 296.328431 34.736745 0)
			(layer "F.Fab")
			(hide yes)
			(effects
				(font
					(size 1 1)
					(thickness 0.15)
				)
			)
		)
		(sheetname "/Deserializer/")
		(sheetfile "deserializer.kicad_sch")
		(attr smd exclude_from_pos_files exclude_from_bom dnp)
		(fp_poly
			(pts
				(xy -0.925 -0.47) (xy 0.925 -0.47) (xy 0.925 0.47) (xy -0.925 0.47)
			)
			(stroke
				(width 0.05)
				(type default)
			)
			(fill no)
			(layer "F.CrtYd")
		)
		(fp_poly
			(pts
				(xy -0.5 -0.25) (xy 0.5 -0.25) (xy 0.5 0.25) (xy -0.5 0.25)
			)
			(stroke
				(width 0.15)
				(type solid)
			)
			(fill no)
			(layer "F.Fab")
		)
		(pad "1" smd roundrect
			(at -0.48 0 135)
			(size 0.59 0.64)
			(layers "F.Cu" "F.Mask" "F.Paste")
			(roundrect_rratio 0.25)
			(net 77 "/Deserializer/CFG1")
			(pintype "passive")
		)
		(pad "2" smd roundrect
			(at 0.48 0 135)
			(size 0.59 0.64)
			(layers "F.Cu" "F.Mask" "F.Paste")
			(roundrect_rratio 0.25)
			(net 146 "VDDIO")
			(pintype "passive")
		)
	)
	(footprint "antmicro-footprints:R_0402_1005Metric"
		(layer "F.Cu")
		(at 179.832 58.674 180)
		(descr "Resistor SMD 0402")
		(tags "resistor SMD 0402")
		(property "Reference" "R17"
			(at -3.041644 -0.307453 0)
			(layer "F.SilkS")
			(effects
				(font
					(size 0.7 0.7)
					(thickness 0.15)
				)
				(justify right bottom)
			)
		)
		(property "Value" "R_100k_0402"
			(at -1.011843 1.772047 0)
			(layer "F.Fab")
			(effects
				(font
					(size 0.7 0.7)
					(thickness 0.15)
				)
				(justify right bottom)
			)
		)
		(property "Datasheet" "https://www.bourns.com/docs/product-datasheets/cr.pdf"
			(at 0 0 180)
			(layer "F.Fab")
			(hide yes)
			(effects
				(font
					(size 1.27 1.27)
					(thickness 0.15)
				)
			)
		)
		(property "Description" "SMD Chip Resistor, 100 kohm, ± 1%, 62.5 mW, 0402 [1005 Metric], Thick Film, General Purpose"
			(at 0 0 180)
			(layer "F.Fab")
			(hide yes)
			(effects
				(font
					(size 1.27 1.27)
					(thickness 0.15)
				)
			)
		)
		(property "Author" "Antmicro"
			(at 359.664 117.348 0)
			(layer "F.Fab")
			(hide yes)
			(effects
				(font
					(size 1 1)
					(thickness 0.15)
				)
			)
		)
		(property "License" "Apache-2.0"
			(at 359.664 117.348 0)
			(layer "F.Fab")
			(hide yes)
			(effects
				(font
					(size 1 1)
					(thickness 0.15)
				)
			)
		)
		(property "MPN" "CR0402-FX-1003GLF"
			(at 359.664 117.348 0)
			(layer "F.Fab")
			(hide yes)
			(effects
				(font
					(size 1 1)
					(thickness 0.15)
				)
			)
		)
		(property "Manufacturer" "Bourns"
			(at 359.664 117.348 0)
			(layer "F.Fab")
			(hide yes)
			(effects
				(font
					(size 1 1)
					(thickness 0.15)
				)
			)
		)
		(property "Tolerance" "1%"
			(at 359.664 117.348 0)
			(layer "F.Fab")
			(hide yes)
			(effects
				(font
					(size 1 1)
					(thickness 0.15)
				)
			)
		)
		(property "Val" "100k"
			(at 359.664 117.348 0)
			(layer "F.Fab")
			(hide yes)
			(effects
				(font
					(size 1 1)
					(thickness 0.15)
				)
			)
		)
		(sheetname "/Power/")
		(sheetfile "power.kicad_sch")
		(attr smd)
		(fp_rect
			(start -0.925 -0.47)
			(end 0.925 0.47)
			(stroke
				(width 0.05)
				(type default)
			)
			(fill no)
			(layer "F.CrtYd")
		)
		(fp_rect
			(start -0.5 -0.25)
			(end 0.5 0.25)
			(stroke
				(width 0.15)
				(type solid)
			)
			(fill no)
			(layer "F.Fab")
		)
		(pad "1" smd roundrect
			(at -0.48 0 180)
			(size 0.59 0.64)
			(layers "F.Cu" "F.Mask" "F.Paste")
			(roundrect_rratio 0.25)
			(net 1 "GND")
			(pintype "passive")
		)
		(pad "2" smd roundrect
			(at 0.48 0 180)
			(size 0.59 0.64)
			(layers "F.Cu" "F.Mask" "F.Paste")
			(roundrect_rratio 0.25)
			(net 128 "Net-(Q3-REF)")
			(pintype "passive")
		)
	)
	(footprint "antmicro-footprints:R_0402_1005Metric"
		(layer "F.Cu")
		(at 153.416 73.914 45)
		(descr "Resistor SMD 0402")
		(tags "resistor SMD 0402")
		(property "Reference" "R45"
			(at 4.003639 0.193747 45)
			(layer "F.SilkS")
			(effects
				(font
					(size 0.7 0.7)
					(thickness 0.15)
				)
				(justify left bottom)
			)
		)
		(property "Value" "R_49R9_0402"
			(at -1.011843 1.772046 45)
			(layer "F.Fab")
			(effects
				(font
					(size 0.7 0.7)
					(thickness 0.15)
				)
				(justify left bottom)
			)
		)
		(property "Datasheet" "https://www.bourns.com/docs/product-datasheets/cr.pdf"
			(at 0 0 45)
			(layer "F.Fab")
			(hide yes)
			(effects
				(font
					(size 1.27 1.27)
					(thickness 0.15)
				)
			)
		)
		(property "Description" "SMD Chip Resistor, 49.9 ohm, ± 1%, 62.5 mW, 0402 [1005 Metric], Thick Film, General Purpose"
			(at 0 0 45)
			(layer "F.Fab")
			(hide yes)
			(effects
				(font
					(size 1.27 1.27)
					(thickness 0.15)
				)
			)
		)
		(property "Author" "Antmicro"
			(at 97.199597 -86.832584 0)
			(layer "F.Fab")
			(hide yes)
			(effects
				(font
					(size 1 1)
					(thickness 0.15)
				)
			)
		)
		(property "License" "Apache-2.0"
			(at 97.199597 -86.832584 0)
			(layer "F.Fab")
			(hide yes)
			(effects
				(font
					(size 1 1)
					(thickness 0.15)
				)
			)
		)
		(property "MPN" "CR0402-FX-49R9GLF"
			(at 97.199597 -86.832584 0)
			(layer "F.Fab")
			(hide yes)
			(effects
				(font
					(size 1 1)
					(thickness 0.15)
				)
			)
		)
		(property "Manufacturer" "Bourns"
			(at 97.199597 -86.832584 0)
			(layer "F.Fab")
			(hide yes)
			(effects
				(font
					(size 1 1)
					(thickness 0.15)
				)
			)
		)
		(property "Tolerance" "1%"
			(at 97.199597 -86.832584 0)
			(layer "F.Fab")
			(hide yes)
			(effects
				(font
					(size 1 1)
					(thickness 0.15)
				)
			)
		)
		(property "Val" "49R9"
			(at 97.199597 -86.832584 0)
			(layer "F.Fab")
			(hide yes)
			(effects
				(font
					(size 1 1)
					(thickness 0.15)
				)
			)
		)
		(sheetname "/Deserializer/")
		(sheetfile "deserializer.kicad_sch")
		(attr smd)
		(fp_poly
			(pts
				(xy -0.925 -0.47) (xy 0.925 -0.47) (xy 0.925 0.47) (xy -0.925 0.47)
			)
			(stroke
				(width 0.05)
				(type default)
			)
			(fill no)
			(layer "F.CrtYd")
		)
		(fp_poly
			(pts
				(xy -0.5 -0.25) (xy 0.5 -0.25) (xy 0.5 0.25) (xy -0.5 0.25)
			)
			(stroke
				(width 0.15)
				(type solid)
			)
			(fill no)
			(layer "F.Fab")
		)
		(pad "1" smd roundrect
			(at -0.48 0 45)
			(size 0.59 0.64)
			(layers "F.Cu" "F.Mask" "F.Paste")
			(roundrect_rratio 0.25)
			(net 23 "Net-(C34-Pad2)")
			(pintype "passive")
		)
		(pad "2" smd roundrect
			(at 0.48 0 45)
			(size 0.59 0.64)
			(layers "F.Cu" "F.Mask" "F.Paste")
			(roundrect_rratio 0.25)
			(net 1 "GND")
			(pintype "passive")
		)
	)
	(footprint "antmicro-footprints:C_0402_1005Metric"
		(layer "F.Cu")
		(at 169.431 57.785 -90)
		(descr "Capacitor SMD 0402")
		(tags "capacitor SMD 0402")
		(property "Reference" "C4"
			(at -0.281 -1.177 90)
			(layer "F.SilkS")
			(effects
				(font
					(size 0.7 0.7)
					(thickness 0.15)
				)
				(justify right bottom)
			)
		)
		(property "Value" "C_100n_0402"
			(at -1.022927 2.155213 90)
			(layer "F.Fab")
			(effects
				(font
					(size 0.7 0.7)
					(thickness 0.15)
				)
				(justify right bottom)
			)
		)
		(property "Datasheet" "https://www.murata.com/products/productdetail?partno=GRM155R61H104KE14%23"
			(at 0 0 270)
			(layer "F.Fab")
			(hide yes)
			(effects
				(font
					(size 1.27 1.27)
					(thickness 0.15)
				)
			)
		)
		(property "Description" "SMD Multilayer Ceramic Capacitor, 0.1 µF, 50 V, 0402 [1005 Metric], ± 10%, X5R, GRM Series"
			(at 0 0 270)
			(layer "F.Fab")
			(hide yes)
			(effects
				(font
					(size 1.27 1.27)
					(thickness 0.15)
				)
			)
		)
		(property "Author" "Antmicro"
			(at 111.646 227.216 0)
			(layer "F.Fab")
			(hide yes)
			(effects
				(font
					(size 1 1)
					(thickness 0.15)
				)
			)
		)
		(property "Dielectric" "X5R"
			(at 111.646 227.216 0)
			(layer "F.Fab")
			(hide yes)
			(effects
				(font
					(size 1 1)
					(thickness 0.15)
				)
			)
		)
		(property "License" "Apache-2.0"
			(at 111.646 227.216 0)
			(layer "F.Fab")
			(hide yes)
			(effects
				(font
					(size 1 1)
					(thickness 0.15)
				)
			)
		)
		(property "MPN" "GRM155R61H104KE14D"
			(at 111.646 227.216 0)
			(layer "F.Fab")
			(hide yes)
			(effects
				(font
					(size 1 1)
					(thickness 0.15)
				)
			)
		)
		(property "Manufacturer" "Murata"
			(at 111.646 227.216 0)
			(layer "F.Fab")
			(hide yes)
			(effects
				(font
					(size 1 1)
					(thickness 0.15)
				)
			)
		)
		(property "Val" "100n"
			(at 111.646 227.216 0)
			(layer "F.Fab")
			(hide yes)
			(effects
				(font
					(size 1 1)
					(thickness 0.15)
				)
			)
		)
		(property "Voltage" "50V"
			(at 111.646 227.216 0)
			(layer "F.Fab")
			(hide yes)
			(effects
				(font
					(size 1 1)
					(thickness 0.15)
				)
			)
		)
		(sheetname "/Connectors/")
		(sheetfile "connectors.kicad_sch")
		(attr smd)
		(fp_rect
			(start -0.925 -0.47)
			(end 0.925 0.47)
			(stroke
				(width 0.05)
				(type default)
			)
			(fill no)
			(layer "F.CrtYd")
		)
		(fp_line
			(start -0.494 0.248)
			(end -0.494 -0.25)
			(stroke
				(width 0.15)
				(type solid)
			)
			(layer "F.Fab")
		)
		(fp_line
			(start 0.504 0.248)
			(end -0.494 0.248)
			(stroke
				(width 0.15)
				(type solid)
			)
			(layer "F.Fab")
		)
		(fp_line
			(start -0.494 -0.25)
			(end 0.504 -0.25)
			(stroke
				(width 0.15)
				(type solid)
			)
			(layer "F.Fab")
		)
		(fp_line
			(start 0.504 -0.25)
			(end 0.504 0.248)
			(stroke
				(width 0.15)
				(type solid)
			)
			(layer "F.Fab")
		)
		(pad "1" smd roundrect
			(at -0.48 0 270)
			(size 0.59 0.64)
			(layers "F.Cu" "F.Mask" "F.Paste")
			(roundrect_rratio 0.25)
			(net 1 "GND")
			(pintype "passive")
		)
		(pad "2" smd roundrect
			(at 0.48 0 270)
			(size 0.59 0.64)
			(layers "F.Cu" "F.Mask" "F.Paste")
			(roundrect_rratio 0.25)
			(net 3 "+1V8")
			(pintype "passive")
		)
	)
	(footprint "antmicro-footprints:R_0402_1005Metric"
		(layer "F.Cu")
		(at 127.262 56.642 90)
		(descr "Resistor SMD 0402")
		(tags "resistor SMD 0402")
		(property "Reference" "R24"
			(at -1.122484 1.262 90)
			(layer "F.SilkS")
			(effects
				(font
					(size 0.7 0.7)
					(thickness 0.15)
				)
				(justify left bottom)
			)
		)
		(property "Value" "R_5k1_0402"
			(at -1.011843 1.772047 90)
			(layer "F.Fab")
			(effects
				(font
					(size 0.7 0.7)
					(thickness 0.15)
				)
				(justify left bottom)
			)
		)
		(property "Datasheet" "https://www.bourns.com/docs/product-datasheets/cr.pdf"
			(at 0 0 90)
			(layer "F.Fab")
			(hide yes)
			(effects
				(font
					(size 1.27 1.27)
					(thickness 0.15)
				)
			)
		)
		(property "Description" "SMD Chip Resistor, 5.1 kohm, ± 1%, 63 mW, 0402 [1005 Metric], Thick Film, General Purpose"
			(at 0 0 90)
			(layer "F.Fab")
			(hide yes)
			(effects
				(font
					(size 1.27 1.27)
					(thickness 0.15)
				)
			)
		)
		(property "Author" "Antmicro"
			(at 183.904 -70.62 0)
			(layer "F.Fab")
			(hide yes)
			(effects
				(font
					(size 1 1)
					(thickness 0.15)
				)
			)
		)
		(property "License" "Apache-2.0"
			(at 183.904 -70.62 0)
			(layer "F.Fab")
			(hide yes)
			(effects
				(font
					(size 1 1)
					(thickness 0.15)
				)
			)
		)
		(property "MPN" "CR0402-FX-5101GLF"
			(at 183.904 -70.62 0)
			(layer "F.Fab")
			(hide yes)
			(effects
				(font
					(size 1 1)
					(thickness 0.15)
				)
			)
		)
		(property "Manufacturer" "Bourns"
			(at 183.904 -70.62 0)
			(layer "F.Fab")
			(hide yes)
			(effects
				(font
					(size 1 1)
					(thickness 0.15)
				)
			)
		)
		(property "Tolerance" "1%"
			(at 183.904 -70.62 0)
			(layer "F.Fab")
			(hide yes)
			(effects
				(font
					(size 1 1)
					(thickness 0.15)
				)
			)
		)
		(property "Val" "5k1"
			(at 183.904 -70.62 0)
			(layer "F.Fab")
			(hide yes)
			(effects
				(font
					(size 1 1)
					(thickness 0.15)
				)
			)
		)
		(sheetname "/Power/")
		(sheetfile "power.kicad_sch")
		(attr smd)
		(fp_rect
			(start -0.925 -0.47)
			(end 0.925 0.47)
			(stroke
				(width 0.05)
				(type default)
			)
			(fill no)
			(layer "F.CrtYd")
		)
		(fp_rect
			(start -0.5 -0.25)
			(end 0.5 0.25)
			(stroke
				(width 0.15)
				(type solid)
			)
			(fill no)
			(layer "F.Fab")
		)
		(pad "1" smd roundrect
			(at -0.48 0 90)
			(size 0.59 0.64)
			(layers "F.Cu" "F.Mask" "F.Paste")
			(roundrect_rratio 0.25)
			(net 51 "Net-(L1-Pad2)")
			(pintype "passive")
		)
		(pad "2" smd roundrect
			(at 0.48 0 90)
			(size 0.59 0.64)
			(layers "F.Cu" "F.Mask" "F.Paste")
			(roundrect_rratio 0.25)
			(net 55 "Net-(L5-Pad2)")
			(pintype "passive")
		)
	)
	(footprint "antmicro-footprints:C_0402_1005Metric"
		(layer "F.Cu")
		(at 153.416 76.962 45)
		(descr "Capacitor SMD 0402")
		(tags "capacitor SMD 0402")
		(property "Reference" "C30"
			(at 3.970405 0.160513 45)
			(layer "F.SilkS")
			(effects
				(font
					(size 0.7 0.7)
					(thickness 0.15)
				)
				(justify left bottom)
			)
		)
		(property "Value" "C_100n_0402"
			(at -1.022927 2.155213 45)
			(layer "F.Fab")
			(effects
				(font
					(size 0.7 0.7)
					(thickness 0.15)
				)
				(justify left bottom)
			)
		)
		(property "Datasheet" "https://www.murata.com/products/productdetail?partno=GRM155R61H104KE14%23"
			(at 0 0 45)
			(layer "F.Fab")
			(hide yes)
			(effects
				(font
					(size 1.27 1.27)
					(thickness 0.15)
				)
			)
		)
		(property "Description" "SMD Multilayer Ceramic Capacitor, 0.1 µF, 50 V, 0402 [1005 Metric], ± 10%, X5R, GRM Series"
			(at 0 0 45)
			(layer "F.Fab")
			(hide yes)
			(effects
				(font
					(size 1.27 1.27)
					(thickness 0.15)
				)
			)
		)
		(property "Author" "Antmicro"
			(at 99.354858 -85.939846 0)
			(layer "F.Fab")
			(hide yes)
			(effects
				(font
					(size 1 1)
					(thickness 0.15)
				)
			)
		)
		(property "Dielectric" "X5R"
			(at 99.354858 -85.939846 0)
			(layer "F.Fab")
			(hide yes)
			(effects
				(font
					(size 1 1)
					(thickness 0.15)
				)
			)
		)
		(property "License" "Apache-2.0"
			(at 99.354858 -85.939846 0)
			(layer "F.Fab")
			(hide yes)
			(effects
				(font
					(size 1 1)
					(thickness 0.15)
				)
			)
		)
		(property "MPN" "GRM155R61H104KE14D"
			(at 99.354858 -85.939846 0)
			(layer "F.Fab")
			(hide yes)
			(effects
				(font
					(size 1 1)
					(thickness 0.15)
				)
			)
		)
		(property "Manufacturer" "Murata"
			(at 99.354858 -85.939846 0)
			(layer "F.Fab")
			(hide yes)
			(effects
				(font
					(size 1 1)
					(thickness 0.15)
				)
			)
		)
		(property "Val" "100n"
			(at 99.354858 -85.939846 0)
			(layer "F.Fab")
			(hide yes)
			(effects
				(font
					(size 1 1)
					(thickness 0.15)
				)
			)
		)
		(property "Voltage" "50V"
			(at 99.354858 -85.939846 0)
			(layer "F.Fab")
			(hide yes)
			(effects
				(font
					(size 1 1)
					(thickness 0.15)
				)
			)
		)
		(sheetname "/Deserializer/")
		(sheetfile "deserializer.kicad_sch")
		(attr smd)
		(fp_poly
			(pts
				(xy -0.925 -0.47) (xy 0.925 -0.47) (xy 0.925 0.47) (xy -0.925 0.47)
			)
			(stroke
				(width 0.05)
				(type default)
			)
			(fill no)
			(layer "F.CrtYd")
		)
		(fp_line
			(start -0.494 -0.25)
			(end 0.504 -0.25)
			(stroke
				(width 0.15)
				(type solid)
			)
			(layer "F.Fab")
		)
		(fp_line
			(start -0.494 0.248)
			(end -0.494 -0.25)
			(stroke
				(width 0.15)
				(type solid)
			)
			(layer "F.Fab")
		)
		(fp_line
			(start 0.504 -0.25)
			(end 0.504 0.248)
			(stroke
				(width 0.15)
				(type solid)
			)
			(layer "F.Fab")
		)
		(fp_line
			(start 0.504 0.248)
			(end -0.494 0.248)
			(stroke
				(width 0.15)
				(type solid)
			)
			(layer "F.Fab")
		)
		(pad "1" smd roundrect
			(at -0.48 0 45)
			(size 0.59 0.64)
			(layers "F.Cu" "F.Mask" "F.Paste")
			(roundrect_rratio 0.25)
			(net 16 "/Deserializer/SIOD_P")
			(pintype "passive")
		)
		(pad "2" smd roundrect
			(at 0.48 0 45)
			(size 0.59 0.64)
			(layers "F.Cu" "F.Mask" "F.Paste")
			(roundrect_rratio 0.25)
			(net 117 "/Connectors/PoCD")
			(pintype "passive")
		)
	)
	(footprint "antmicro-footprints:L_Coilcraft-PFL1609"
		(layer "F.Cu")
		(at 125.984 53.594)
		(property "Reference" "L9"
			(at -2.667 0.381 0)
			(layer "F.SilkS")
			(effects
				(font
					(size 0.7 0.7)
					(thickness 0.15)
				)
				(justify left bottom)
			)
		)
		(property "Value" "L_470n_1A_Coilcraft-PFL1609"
			(at 0 2 0)
			(layer "F.Fab")
			(effects
				(font
					(size 0.7 0.7)
					(thickness 0.15)
				)
				(justify left bottom)
			)
		)
		(property "Datasheet" "https://www.coilcraft.com/getmedia/2f4cd442-d64d-4413-a518-12fcfd03318d/pfl1609.pdf"
			(at 0 0 0)
			(layer "F.Fab")
			(hide yes)
			(effects
				(font
					(size 1.27 1.27)
					(thickness 0.15)
				)
			)
		)
		(property "Description" "Power Inductor (SMT), 6.8 µH, 9.2 A, Shielded, 12.8 A, XAL7070"
			(at 0 0 0)
			(layer "F.Fab")
			(hide yes)
			(effects
				(font
					(size 1.27 1.27)
					(thickness 0.15)
				)
			)
		)
		(property "Author" "Antmicro"
			(at 0 0 0)
			(layer "F.Fab")
			(hide yes)
			(effects
				(font
					(size 1 1)
					(thickness 0.15)
				)
			)
		)
		(property "IMax" "1 A"
			(at 0 0 0)
			(layer "F.Fab")
			(hide yes)
			(effects
				(font
					(size 1 1)
					(thickness 0.15)
				)
			)
		)
		(property "ISat" "0.99 A"
			(at 0 0 0)
			(layer "F.Fab")
			(hide yes)
			(effects
				(font
					(size 1 1)
					(thickness 0.15)
				)
			)
		)
		(property "License" "Apache-2.0"
			(at 0 0 0)
			(layer "F.Fab")
			(hide yes)
			(effects
				(font
					(size 1 1)
					(thickness 0.15)
				)
			)
		)
		(property "MPN" "PFL1609-471"
			(at 0 0 0)
			(layer "F.Fab")
			(hide yes)
			(effects
				(font
					(size 1 1)
					(thickness 0.15)
				)
			)
		)
		(property "Manufacturer" "Coilcraft"
			(at 0 0 0)
			(layer "F.Fab")
			(hide yes)
			(effects
				(font
					(size 1 1)
					(thickness 0.15)
				)
			)
		)
		(property "Size" "1.07x1.8"
			(at 0 0 0)
			(layer "F.Fab")
			(hide yes)
			(effects
				(font
					(size 1 1)
					(thickness 0.15)
				)
			)
		)
		(property "Val" "470n/0.99A"
			(at 0 0 0)
			(layer "F.Fab")
			(hide yes)
			(effects
				(font
					(size 1 1)
					(thickness 0.15)
				)
			)
		)
		(sheetname "/Power/")
		(sheetfile "power.kicad_sch")
		(attr smd)
		(fp_line
			(start -0.23 -0.45)
			(end 0.23 -0.45)
			(stroke
				(width 0.15)
				(type solid)
			)
			(layer "F.SilkS")
		)
		(fp_line
			(start -0.23 0.45)
			(end 0.23 0.45)
			(stroke
				(width 0.15)
				(type solid)
			)
			(layer "F.SilkS")
		)
		(fp_rect
			(start -1.2 -0.84)
			(end 1.2 0.84)
			(stroke
				(width 0.05)
				(type solid)
			)
			(fill no)
			(layer "F.CrtYd")
		)
		(fp_rect
			(start -0.9 -0.535)
			(end 0.9 0.535)
			(stroke
				(width 0.15)
				(type solid)
			)
			(fill no)
			(layer "F.Fab")
		)
		(pad "1" smd roundrect
			(at -0.635 0)
			(size 0.64 1.02)
			(layers "F.Cu" "F.Mask" "F.Paste")
			(roundrect_rratio 0.15)
			(net 55 "Net-(L5-Pad2)")
			(pintype "passive")
		)
		(pad "2" smd roundrect
			(at 0.635 0)
			(size 0.64 1.02)
			(layers "F.Cu" "F.Mask" "F.Paste")
			(roundrect_rratio 0.15)
			(net 59 "Net-(L13-Pad1)")
			(pintype "passive")
		)
	)
	(footprint "antmicro-footprints:L_Coilcraft-PFL1609"
		(layer "F.Cu")
		(at 137.668 53.594)
		(property "Reference" "L10"
			(at -3.147 0.381 0)
			(layer "F.SilkS")
			(effects
				(font
					(size 0.7 0.7)
					(thickness 0.15)
				)
				(justify left bottom)
			)
		)
		(property "Value" "L_470n_1A_Coilcraft-PFL1609"
			(at 0 2 0)
			(layer "F.Fab")
			(effects
				(font
					(size 0.7 0.7)
					(thickness 0.15)
				)
				(justify left bottom)
			)
		)
		(property "Datasheet" "https://www.coilcraft.com/getmedia/2f4cd442-d64d-4413-a518-12fcfd03318d/pfl1609.pdf"
			(at 0 0 0)
			(layer "F.Fab")
			(hide yes)
			(effects
				(font
					(size 1.27 1.27)
					(thickness 0.15)
				)
			)
		)
		(property "Description" "Power Inductor (SMT), 6.8 µH, 9.2 A, Shielded, 12.8 A, XAL7070"
			(at 0 0 0)
			(layer "F.Fab")
			(hide yes)
			(effects
				(font
					(size 1.27 1.27)
					(thickness 0.15)
				)
			)
		)
		(property "Author" "Antmicro"
			(at 0 0 0)
			(layer "F.Fab")
			(hide yes)
			(effects
				(font
					(size 1 1)
					(thickness 0.15)
				)
			)
		)
		(property "IMax" "1 A"
			(at 0 0 0)
			(layer "F.Fab")
			(hide yes)
			(effects
				(font
					(size 1 1)
					(thickness 0.15)
				)
			)
		)
		(property "ISat" "0.99 A"
			(at 0 0 0)
			(layer "F.Fab")
			(hide yes)
			(effects
				(font
					(size 1 1)
					(thickness 0.15)
				)
			)
		)
		(property "License" "Apache-2.0"
			(at 0 0 0)
			(layer "F.Fab")
			(hide yes)
			(effects
				(font
					(size 1 1)
					(thickness 0.15)
				)
			)
		)
		(property "MPN" "PFL1609-471"
			(at 0 0 0)
			(layer "F.Fab")
			(hide yes)
			(effects
				(font
					(size 1 1)
					(thickness 0.15)
				)
			)
		)
		(property "Manufacturer" "Coilcraft"
			(at 0 0 0)
			(layer "F.Fab")
			(hide yes)
			(effects
				(font
					(size 1 1)
					(thickness 0.15)
				)
			)
		)
		(property "Size" "1.07x1.8"
			(at 0 0 0)
			(layer "F.Fab")
			(hide yes)
			(effects
				(font
					(size 1 1)
					(thickness 0.15)
				)
			)
		)
		(property "Val" "470n/0.99A"
			(at 0 0 0)
			(layer "F.Fab")
			(hide yes)
			(effects
				(font
					(size 1 1)
					(thickness 0.15)
				)
			)
		)
		(sheetname "/Power/")
		(sheetfile "power.kicad_sch")
		(attr smd)
		(fp_line
			(start -0.23 -0.45)
			(end 0.23 -0.45)
			(stroke
				(width 0.15)
				(type solid)
			)
			(layer "F.SilkS")
		)
		(fp_line
			(start -0.23 0.45)
			(end 0.23 0.45)
			(stroke
				(width 0.15)
				(type solid)
			)
			(layer "F.SilkS")
		)
		(fp_rect
			(start -1.2 -0.84)
			(end 1.2 0.84)
			(stroke
				(width 0.05)
				(type solid)
			)
			(fill no)
			(layer "F.CrtYd")
		)
		(fp_rect
			(start -0.9 -0.535)
			(end 0.9 0.535)
			(stroke
				(width 0.15)
				(type solid)
			)
			(fill no)
			(layer "F.Fab")
		)
		(pad "1" smd roundrect
			(at -0.635 0)
			(size 0.64 1.02)
			(layers "F.Cu" "F.Mask" "F.Paste")
			(roundrect_rratio 0.15)
			(net 56 "Net-(L10-Pad1)")
			(pintype "passive")
		)
		(pad "2" smd roundrect
			(at 0.635 0)
			(size 0.64 1.02)
			(layers "F.Cu" "F.Mask" "F.Paste")
			(roundrect_rratio 0.15)
			(net 60 "Net-(L10-Pad2)")
			(pintype "passive")
		)
	)
	(footprint "antmicro-footprints:C_0402_1005Metric"
		(layer "F.Cu")
		(at 172.212 62.103 -90)
		(descr "Capacitor SMD 0402")
		(tags "capacitor SMD 0402")
		(property "Reference" "C3"
			(at -0.903 -1.288 90)
			(layer "F.SilkS")
			(effects
				(font
					(size 0.7 0.7)
					(thickness 0.15)
				)
				(justify right bottom)
			)
		)
		(property "Value" "C_100n_0402"
			(at -1.022927 2.155213 90)
			(layer "F.Fab")
			(effects
				(font
					(size 0.7 0.7)
					(thickness 0.15)
				)
				(justify right bottom)
			)
		)
		(property "Datasheet" "https://www.murata.com/products/productdetail?partno=GRM155R61H104KE14%23"
			(at 0 0 270)
			(layer "F.Fab")
			(hide yes)
			(effects
				(font
					(size 1.27 1.27)
					(thickness 0.15)
				)
			)
		)
		(property "Description" "SMD Multilayer Ceramic Capacitor, 0.1 µF, 50 V, 0402 [1005 Metric], ± 10%, X5R, GRM Series"
			(at 0 0 270)
			(layer "F.Fab")
			(hide yes)
			(effects
				(font
					(size 1.27 1.27)
					(thickness 0.15)
				)
			)
		)
		(property "Author" "Antmicro"
			(at 110.109 234.315 0)
			(layer "F.Fab")
			(hide yes)
			(effects
				(font
					(size 1 1)
					(thickness 0.15)
				)
			)
		)
		(property "Dielectric" "X5R"
			(at 110.109 234.315 0)
			(layer "F.Fab")
			(hide yes)
			(effects
				(font
					(size 1 1)
					(thickness 0.15)
				)
			)
		)
		(property "License" "Apache-2.0"
			(at 110.109 234.315 0)
			(layer "F.Fab")
			(hide yes)
			(effects
				(font
					(size 1 1)
					(thickness 0.15)
				)
			)
		)
		(property "MPN" "GRM155R61H104KE14D"
			(at 110.109 234.315 0)
			(layer "F.Fab")
			(hide yes)
			(effects
				(font
					(size 1 1)
					(thickness 0.15)
				)
			)
		)
		(property "Manufacturer" "Murata"
			(at 110.109 234.315 0)
			(layer "F.Fab")
			(hide yes)
			(effects
				(font
					(size 1 1)
					(thickness 0.15)
				)
			)
		)
		(property "Val" "100n"
			(at 110.109 234.315 0)
			(layer "F.Fab")
			(hide yes)
			(effects
				(font
					(size 1 1)
					(thickness 0.15)
				)
			)
		)
		(property "Voltage" "50V"
			(at 110.109 234.315 0)
			(layer "F.Fab")
			(hide yes)
			(effects
				(font
					(size 1 1)
					(thickness 0.15)
				)
			)
		)
		(sheetname "/Connectors/")
		(sheetfile "connectors.kicad_sch")
		(attr smd)
		(fp_rect
			(start -0.925 -0.47)
			(end 0.925 0.47)
			(stroke
				(width 0.05)
				(type default)
			)
			(fill no)
			(layer "F.CrtYd")
		)
		(fp_line
			(start -0.494 0.248)
			(end -0.494 -0.25)
			(stroke
				(width 0.15)
				(type solid)
			)
			(layer "F.Fab")
		)
		(fp_line
			(start 0.504 0.248)
			(end -0.494 0.248)
			(stroke
				(width 0.15)
				(type solid)
			)
			(layer "F.Fab")
		)
		(fp_line
			(start -0.494 -0.25)
			(end 0.504 -0.25)
			(stroke
				(width 0.15)
				(type solid)
			)
			(layer "F.Fab")
		)
		(fp_line
			(start 0.504 -0.25)
			(end 0.504 0.248)
			(stroke
				(width 0.15)
				(type solid)
			)
			(layer "F.Fab")
		)
		(pad "1" smd roundrect
			(at -0.48 0 270)
			(size 0.59 0.64)
			(layers "F.Cu" "F.Mask" "F.Paste")
			(roundrect_rratio 0.25)
			(net 1 "GND")
			(pintype "passive")
		)
		(pad "2" smd roundrect
			(at 0.48 0 270)
			(size 0.59 0.64)
			(layers "F.Cu" "F.Mask" "F.Paste")
			(roundrect_rratio 0.25)
			(net 3 "+1V8")
			(pintype "passive")
		)
	)
	(footprint "antmicro-footprints:R_0603_1608Metric"
		(layer "F.Cu")
		(at 131.725 90.538 90)
		(descr "Resistor SMD 0603")
		(tags "resistor SMD 0603")
		(property "Reference" "R40"
			(at -1.016 -0.9 90)
			(layer "F.SilkS")
			(effects
				(font
					(size 0.7 0.7)
					(thickness 0.15)
				)
				(justify left bottom)
			)
		)
		(property "Value" "R_0R_22.4A_0603"
			(at -5.1615 1.6 90)
			(layer "F.Fab")
			(effects
				(font
					(size 0.7 0.7)
					(thickness 0.15)
				)
				(justify left bottom)
			)
		)
		(property "Datasheet" "https://fscdn.rohm.com/en/products/databook/datasheet/passive/resistor/chip_resistor/pmr-jpw-e.pdf"
			(at 0 0 90)
			(layer "F.Fab")
			(hide yes)
			(effects
				(font
					(size 1.27 1.27)
					(thickness 0.15)
				)
			)
		)
		(property "Description" "SMD Chip Resistor"
			(at 0 0 90)
			(layer "F.Fab")
			(hide yes)
			(effects
				(font
					(size 1.27 1.27)
					(thickness 0.15)
				)
			)
		)
		(property "Author" "Antmicro"
			(at 222.263 -41.187 0)
			(layer "F.Fab")
			(hide yes)
			(effects
				(font
					(size 1 1)
					(thickness 0.15)
				)
			)
		)
		(property "License" "Apache-2.0"
			(at 222.263 -41.187 0)
			(layer "F.Fab")
			(hide yes)
			(effects
				(font
					(size 1 1)
					(thickness 0.15)
				)
			)
		)
		(property "MPN" "PMR03EZPJ000"
			(at 222.263 -41.187 0)
			(layer "F.Fab")
			(hide yes)
			(effects
				(font
					(size 1 1)
					(thickness 0.15)
				)
			)
		)
		(property "Manufacturer" "ROHM Semiconductor"
			(at 222.263 -41.187 0)
			(layer "F.Fab")
			(hide yes)
			(effects
				(font
					(size 1 1)
					(thickness 0.15)
				)
			)
		)
		(property "Max. Curr." "22.4A"
			(at 222.263 -41.187 0)
			(layer "F.Fab")
			(hide yes)
			(effects
				(font
					(size 1 1)
					(thickness 0.15)
				)
			)
		)
		(property "Tolerance" "template_tolerance"
			(at 222.263 -41.187 0)
			(layer "F.Fab")
			(hide yes)
			(effects
				(font
					(size 1 1)
					(thickness 0.15)
				)
			)
		)
		(property "Val" "0R"
			(at 222.263 -41.187 0)
			(layer "F.Fab")
			(hide yes)
			(effects
				(font
					(size 1 1)
					(thickness 0.15)
				)
			)
		)
		(sheetname "/Power/")
		(sheetfile "power.kicad_sch")
		(attr smd)
		(fp_line
			(start -0.15 -0.4)
			(end 0.15 -0.4)
			(stroke
				(width 0.15)
				(type solid)
			)
			(layer "F.SilkS")
		)
		(fp_line
			(start -0.15 0.4)
			(end 0.15 0.4)
			(stroke
				(width 0.15)
				(type solid)
			)
			(layer "F.SilkS")
		)
		(fp_rect
			(start -1.25 -0.65)
			(end 1.25 0.65)
			(stroke
				(width 0.05)
				(type solid)
			)
			(fill no)
			(layer "F.CrtYd")
		)
		(fp_rect
			(start -0.8 -0.4)
			(end 0.8 0.4)
			(stroke
				(width 0.15)
				(type solid)
			)
			(fill no)
			(layer "F.Fab")
		)
		(pad "1" smd roundrect
			(at -0.7 0 90)
			(size 0.8 1)
			(layers "F.Cu" "F.Mask" "F.Paste")
			(roundrect_rratio 0.2)
			(net 10 "/Power/OUT_1V8")
			(pintype "passive")
		)
		(pad "2" smd roundrect
			(at 0.7 0 90)
			(size 0.8 1)
			(layers "F.Cu" "F.Mask" "F.Paste")
			(roundrect_rratio 0.2)
			(net 3 "+1V8")
			(pintype "passive")
		)
	)
	(footprint "antmicro-footprints:L_Coilcraft-1210POC"
		(layer "F.Cu")
		(at 159.766 56.642 90)
		(property "Reference" "L8"
			(at -0.635 -1.7 90)
			(layer "F.SilkS")
			(effects
				(font
					(size 0.7 0.7)
					(thickness 0.15)
				)
				(justify left bottom)
			)
		)
		(property "Value" "L_6u8_1A_Coilcraft-1210POC"
			(at 0 2.4 90)
			(layer "F.Fab")
			(effects
				(font
					(size 0.7 0.7)
					(thickness 0.15)
				)
				(justify left bottom)
			)
		)
		(property "Datasheet" "https://www.coilcraft.com/getmedia/5e8de018-68c5-4442-84ce-d5212c44660c/1210poc.pdf"
			(at 0 0 90)
			(layer "F.Fab")
			(hide yes)
			(effects
				(font
					(size 1.27 1.27)
					(thickness 0.15)
				)
			)
		)
		(property "Description" "Power Inductor (SMT), 6.8 µH, 9.2 A, Shielded, 12.8 A, XAL7070"
			(at 0 0 90)
			(layer "F.Fab")
			(hide yes)
			(effects
				(font
					(size 1.27 1.27)
					(thickness 0.15)
				)
			)
		)
		(property "Author" "Antmicro"
			(at 216.408 -103.124 0)
			(layer "F.Fab")
			(hide yes)
			(effects
				(font
					(size 1 1)
					(thickness 0.15)
				)
			)
		)
		(property "IMax" "1.36 A"
			(at 216.408 -103.124 0)
			(layer "F.Fab")
			(hide yes)
			(effects
				(font
					(size 1 1)
					(thickness 0.15)
				)
			)
		)
		(property "ISat" "1 A"
			(at 216.408 -103.124 0)
			(layer "F.Fab")
			(hide yes)
			(effects
				(font
					(size 1 1)
					(thickness 0.15)
				)
			)
		)
		(property "License" "Apache-2.0"
			(at 216.408 -103.124 0)
			(layer "F.Fab")
			(hide yes)
			(effects
				(font
					(size 1 1)
					(thickness 0.15)
				)
			)
		)
		(property "MPN" "1210POC-682"
			(at 216.408 -103.124 0)
			(layer "F.Fab")
			(hide yes)
			(effects
				(font
					(size 1 1)
					(thickness 0.15)
				)
			)
		)
		(property "Manufacturer" "Coilcraft"
			(at 216.408 -103.124 0)
			(layer "F.Fab")
			(hide yes)
			(effects
				(font
					(size 1 1)
					(thickness 0.15)
				)
			)
		)
		(property "Size" "2.67x3.3"
			(at 216.408 -103.124 0)
			(layer "F.Fab")
			(hide yes)
			(effects
				(font
					(size 1 1)
					(thickness 0.15)
				)
			)
		)
		(property "Val" "6u8/1A"
			(at 216.408 -103.124 0)
			(layer "F.Fab")
			(hide yes)
			(effects
				(font
					(size 1 1)
					(thickness 0.15)
				)
			)
		)
		(sheetname "/Power/")
		(sheetfile "power.kicad_sch")
		(attr smd)
		(fp_line
			(start -0.7 -1.4)
			(end 0.7 -1.4)
			(stroke
				(width 0.15)
				(type solid)
			)
			(layer "F.SilkS")
		)
		(fp_line
			(start -0.7 1.4)
			(end 0.7 1.4)
			(stroke
				(width 0.15)
				(type solid)
			)
			(layer "F.SilkS")
		)
		(fp_rect
			(start -1.9 -1.585)
			(end 1.9 1.585)
			(stroke
				(width 0.05)
				(type solid)
			)
			(fill no)
			(layer "F.CrtYd")
		)
		(fp_line
			(start 1.65 -1.335)
			(end -1.65 -1.335)
			(stroke
				(width 0.15)
				(type solid)
			)
			(layer "F.Fab")
		)
		(fp_line
			(start 1.65 1.335)
			(end 1.65 -1.335)
			(stroke
				(width 0.15)
				(type solid)
			)
			(layer "F.Fab")
		)
		(fp_line
			(start 1.65 1.335)
			(end -1.65 1.335)
			(stroke
				(width 0.15)
				(type solid)
			)
			(layer "F.Fab")
		)
		(fp_line
			(start -1.65 1.335)
			(end -1.65 -1.335)
			(stroke
				(width 0.15)
				(type solid)
			)
			(layer "F.Fab")
		)
		(pad "1" smd rect
			(at -1.27 0 90)
			(size 0.65 2.65)
			(layers "F.Cu" "F.Mask" "F.Paste")
			(net 54 "Net-(L4-Pad2)")
			(pintype "passive")
		)
		(pad "2" smd rect
			(at 1.27 0 90)
			(size 0.65 2.65)
			(layers "F.Cu" "F.Mask" "F.Paste")
			(net 58 "Net-(L12-Pad1)")
			(pintype "passive")
		)
	)
	(footprint "antmicro-footprints:QFN-56-1EP_8x8mm_P0.5mm_EP4.8x4.8mm"
		(layer "F.Cu")
		(at 146.558 81.620528 -135)
		(descr "T5688Y+6C")
		(tags "QFN")
		(property "Reference" "U7"
			(at -4.228023 -5.434732 225)
			(layer "F.SilkS")
			(effects
				(font
					(size 0.7 0.7)
					(thickness 0.15)
				)
				(justify right bottom)
			)
		)
		(property "Value" "MAX96724GTN_VY+"
			(at 0 5.32 45)
			(layer "F.Fab")
			(effects
				(font
					(size 0.7 0.7)
					(thickness 0.15)
				)
				(justify right bottom)
			)
		)
		(property "Datasheet" "https://www.mouser.com/datasheet/2/609/max96724-3135154.pdf"
			(at 0 0 225)
			(layer "F.Fab")
			(hide yes)
			(effects
				(font
					(size 1.27 1.27)
					(thickness 0.15)
				)
			)
		)
		(property "Description" "ADI GMSL2/1 Tunneling Quad Deserializer 6GHz with 2x4 or 4x2 MIPI DPHY/CPHY Outputs"
			(at 0 0 225)
			(layer "F.Fab")
			(hide yes)
			(effects
				(font
					(size 1.27 1.27)
					(thickness 0.15)
				)
			)
		)
		(property "Author" "Antmicro"
			(at 192.475727 242.967112 0)
			(layer "F.Fab")
			(hide yes)
			(effects
				(font
					(size 1 1)
					(thickness 0.15)
				)
			)
		)
		(property "License" "Apache-2.0"
			(at 192.475727 242.967112 0)
			(layer "F.Fab")
			(hide yes)
			(effects
				(font
					(size 1 1)
					(thickness 0.15)
				)
			)
		)
		(property "MPN" "MAX96724GTN/VY+"
			(at 192.475727 242.967112 0)
			(layer "F.Fab")
			(hide yes)
			(effects
				(font
					(size 1 1)
					(thickness 0.15)
				)
			)
		)
		(property "Manufacturer" "Analog Devices"
			(at 192.475727 242.967112 0)
			(layer "F.Fab")
			(hide yes)
			(effects
				(font
					(size 1 1)
					(thickness 0.15)
				)
			)
		)
		(sheetname "/Deserializer/")
		(sheetfile "deserializer.kicad_sch")
		(attr smd)
		(fp_line
			(start 4.11 4.11)
			(end 4.11 3.634)
			(stroke
				(width 0.15)
				(type solid)
			)
			(layer "F.SilkS")
		)
		(fp_line
			(start 3.634 4.11)
			(end 4.11 4.11)
			(stroke
				(width 0.15)
				(type solid)
			)
			(layer "F.SilkS")
		)
		(fp_line
			(start -3.635 4.11)
			(end -4.111 4.11)
			(stroke
				(width 0.15)
				(type solid)
			)
			(layer "F.SilkS")
		)
		(fp_line
			(start -4.111 4.11)
			(end -4.111 3.634)
			(stroke
				(width 0.15)
				(type solid)
			)
			(layer "F.SilkS")
		)
		(fp_line
			(start 4.11 -4.111)
			(end 4.11 -3.635)
			(stroke
				(width 0.15)
				(type solid)
			)
			(layer "F.SilkS")
		)
		(fp_line
			(start 3.634 -4.111)
			(end 4.11 -4.111)
			(stroke
				(width 0.15)
				(type solid)
			)
			(layer "F.SilkS")
		)
		(fp_line
			(start -4.111 -3.635)
			(end -4.111 -4.111)
			(stroke
				(width 0.15)
				(type solid)
			)
			(layer "F.SilkS")
		)
		(fp_line
			(start -3.635 -4.111)
			(end -4.111 -4.111)
			(stroke
				(width 0.15)
				(type solid)
			)
			(layer "F.SilkS")
		)
		(fp_circle
			(center -4.6 -3.25)
			(end -4.55 -3.25)
			(stroke
				(width 0.15)
				(type solid)
			)
			(fill yes)
			(layer "F.SilkS")
		)
		(fp_poly
			(pts
				(xy 4.5 4.5) (xy -4.5 4.5) (xy -4.5 -4.5) (xy 4.5 -4.5)
			)
			(stroke
				(width 0.05)
				(type solid)
			)
			(fill no)
			(layer "F.CrtYd")
		)
		(fp_poly
			(pts
				(xy -4.05 -4.05) (xy 4.05 -4.05) (xy 4.05 4.05) (xy -4.05 4.05)
			)
			(stroke
				(width 0.15)
				(type solid)
			)
			(fill no)
			(layer "F.Fab")
		)
		(pad "" smd roundrect
			(at -1.8 -1.8 225)
			(size 0.8 0.8)
			(layers "F.Paste")
			(roundrect_rratio 0.221239)
		)
		(pad "" smd roundrect
			(at -1.8 -0.6 225)
			(size 0.8 0.8)
			(layers "F.Paste")
			(roundrect_rratio 0.221239)
		)
		(pad "" smd roundrect
			(at -1.8 0.6 225)
			(size 0.8 0.8)
			(layers "F.Paste")
			(roundrect_rratio 0.221239)
		)
		(pad "" smd roundrect
			(at -1.8 1.8 225)
			(size 0.8 0.8)
			(layers "F.Paste")
			(roundrect_rratio 0.221239)
		)
		(pad "" smd roundrect
			(at -0.6 -1.8 225)
			(size 0.8 0.8)
			(layers "F.Paste")
			(roundrect_rratio 0.221239)
		)
		(pad "" smd roundrect
			(at -0.6 -0.6 225)
			(size 0.8 0.8)
			(layers "F.Paste")
			(roundrect_rratio 0.221239)
		)
		(pad "" smd roundrect
			(at -0.6 0.6 225)
			(size 0.8 0.8)
			(layers "F.Paste")
			(roundrect_rratio 0.221239)
		)
		(pad "" smd roundrect
			(at -0.6 1.8 225)
			(size 0.8 0.8)
			(layers "F.Paste")
			(roundrect_rratio 0.221239)
		)
		(pad "" smd roundrect
			(at 0.6 -1.8 225)
			(size 0.8 0.8)
			(layers "F.Paste")
			(roundrect_rratio 0.221239)
		)
		(pad "" smd roundrect
			(at 0.6 -0.6 225)
			(size 0.8 0.8)
			(layers "F.Paste")
			(roundrect_rratio 0.221239)
		)
		(pad "" smd roundrect
			(at 0.6 0.6 225)
			(size 0.8 0.8)
			(layers "F.Paste")
			(roundrect_rratio 0.221239)
		)
		(pad "" smd roundrect
			(at 0.6 1.8 225)
			(size 0.8 0.8)
			(layers "F.Paste")
			(roundrect_rratio 0.221239)
		)
		(pad "" smd roundrect
			(at 1.8 -1.8 225)
			(size 0.8 0.8)
			(layers "F.Paste")
			(roundrect_rratio 0.221239)
		)
		(pad "" smd roundrect
			(at 1.8 -0.6 225)
			(size 0.8 0.8)
			(layers "F.Paste")
			(roundrect_rratio 0.221239)
		)
		(pad "" smd roundrect
			(at 1.8 0.6 225)
			(size 0.8 0.8)
			(layers "F.Paste")
			(roundrect_rratio 0.221239)
		)
		(pad "" smd roundrect
			(at 1.8 1.8 225)
			(size 0.8 0.8)
			(layers "F.Paste")
			(roundrect_rratio 0.221239)
		)
		(pad "1" smd roundrect
			(at -4 -3.25 225)
			(size 0.8 0.3)
			(layers "F.Cu" "F.Mask" "F.Paste")
			(roundrect_rratio 0.25)
			(net 80 "/Connectors/MFP0")
			(pinfunction "MFP0")
			(pintype "passive")
		)
		(pad "2" smd roundrect
			(at -4 -2.75 225)
			(size 0.8 0.3)
			(layers "F.Cu" "F.Mask" "F.Paste")
			(roundrect_rratio 0.25)
			(net 81 "/Connectors/MFP1")
			(pinfunction "MFP1")
			(pintype "passive")
		)
		(pad "3" smd roundrect
			(at -4 -2.25 225)
			(size 0.8 0.3)
			(layers "F.Cu" "F.Mask" "F.Paste")
			(roundrect_rratio 0.25)
			(net 82 "/Connectors/MFP2")
			(pinfunction "MFP2")
			(pintype "passive")
		)
		(pad "4" smd roundrect
			(at -4 -1.75 225)
			(size 0.8 0.3)
			(layers "F.Cu" "F.Mask" "F.Paste")
			(roundrect_rratio 0.25)
			(net 76 "/Deserializer/CFG0")
			(pinfunction "CFG0")
			(pintype "passive")
		)
		(pad "5" smd roundrect
			(at -4.000001 -1.25 225)
			(size 0.8 0.3)
			(layers "F.Cu" "F.Mask" "F.Paste")
			(roundrect_rratio 0.25)
			(net 16 "/Deserializer/SIOD_P")
			(pinfunction "SIOD_P")
			(pintype "passive")
		)
		(pad "6" smd roundrect
			(at -4 -0.75 225)
			(size 0.8 0.3)
			(layers "F.Cu" "F.Mask" "F.Paste")
			(roundrect_rratio 0.25)
			(net 24 "/Deserializer/SIOD_N")
			(pinfunction "SIOD_N")
			(pintype "passive")
		)
		(pad "7" smd roundrect
			(at -4 -0.25 225)
			(size 0.8 0.3)
			(layers "F.Cu" "F.Mask" "F.Paste")
			(roundrect_rratio 0.25)
			(net 26 "/Deserializer/VDD_1.8V")
			(pinfunction "VDD_1.8V")
			(pintype "passive")
		)
		(pad "8" smd roundrect
			(at -4 0.25 225)
			(size 0.8 0.3)
			(layers "F.Cu" "F.Mask" "F.Paste")
			(roundrect_rratio 0.25)
			(net 28 "/Deserializer/CAP_VDD")
			(pinfunction "CAP_VDD")
			(pintype "passive")
		)
		(pad "9" smd roundrect
			(at -4 0.75 225)
			(size 0.8 0.3)
			(layers "F.Cu" "F.Mask" "F.Paste")
			(roundrect_rratio 0.25)
			(net 22 "/Deserializer/SIOC_N")
			(pinfunction "SIOC_N")
			(pintype "passive")
		)
		(pad "10" smd roundrect
			(at -4.000001 1.25 225)
			(size 0.8 0.3)
			(layers "F.Cu" "F.Mask" "F.Paste")
			(roundrect_rratio 0.25)
			(net 15 "/Deserializer/SIOC_P")
			(pinfunction "SIOC_P")
			(pintype "passive")
		)
		(pad "11" smd roundrect
			(at -4 1.75 225)
			(size 0.8 0.3)
			(layers "F.Cu" "F.Mask" "F.Paste")
			(roundrect_rratio 0.25)
			(net 79 "/Deserializer/PWDNB")
			(pinfunction "PWDNB")
			(pintype "passive")
		)
		(pad "12" smd roundrect
			(at -4 2.25 225)
			(size 0.8 0.3)
			(layers "F.Cu" "F.Mask" "F.Paste")
			(roundrect_rratio 0.25)
			(net 83 "/Connectors/MFP3")
			(pinfunction "MFP3")
			(pintype "passive")
		)
		(pad "13" smd roundrect
			(at -4 2.75 225)
			(size 0.8 0.3)
			(layers "F.Cu" "F.Mask" "F.Paste")
			(roundrect_rratio 0.25)
			(net 84 "/Connectors/MFP4")
			(pinfunction "MFP4")
			(pintype "passive")
		)
		(pad "14" smd roundrect
			(at -4 3.25 225)
			(size 0.8 0.3)
			(layers "F.Cu" "F.Mask" "F.Paste")
			(roundrect_rratio 0.25)
			(net 85 "/Connectors/MFP5")
			(pinfunction "MFP5")
			(pintype "passive")
		)
		(pad "15" smd roundrect
			(at -3.25 4 315)
			(size 0.8 0.3)
			(layers "F.Cu" "F.Mask" "F.Paste")
			(roundrect_rratio 0.25)
			(net 12 "/Deserializer/X1")
			(pinfunction "X1/OSC")
			(pintype "passive")
		)
		(pad "16" smd roundrect
			(at -2.75 4 315)
			(size 0.8 0.3)
			(layers "F.Cu" "F.Mask" "F.Paste")
			(roundrect_rratio 0.25)
			(net 75 "/Deserializer/X2")
			(pinfunction "X2")
			(pintype "passive")
		)
		(pad "17" smd roundrect
			(at -2.25 4 315)
			(size 0.8 0.3)
			(layers "F.Cu" "F.Mask" "F.Paste")
			(roundrect_rratio 0.25)
			(net 78 "/Deserializer/XRES")
			(pinfunction "XRES")
			(pintype "passive")
		)
		(pad "18" smd roundrect
			(at -1.75 4 315)
			(size 0.8 0.3)
			(layers "F.Cu" "F.Mask" "F.Paste")
			(roundrect_rratio 0.25)
			(net 14 "/Deserializer/SIOB_P")
			(pinfunction "SIOB_P")
			(pintype "passive")
		)
		(pad "19" smd roundrect
			(at -1.25 4.000001 315)
			(size 0.8 0.3)
			(layers "F.Cu" "F.Mask" "F.Paste")
			(roundrect_rratio 0.25)
			(net 20 "/Deserializer/SIOB_N")
			(pinfunction "SIOB_N")
			(pintype "passive")
		)
		(pad "20" smd roundrect
			(at -0.75 4 315)
			(size 0.8 0.3)
			(layers "F.Cu" "F.Mask" "F.Paste")
			(roundrect_rratio 0.25)
			(net 28 "/Deserializer/CAP_VDD")
			(pinfunction "CAP_VDD")
			(pintype "passive")
		)
		(pad "21" smd roundrect
			(at -0.25 4 315)
			(size 0.8 0.3)
			(layers "F.Cu" "F.Mask" "F.Paste")
			(roundrect_rratio 0.25)
			(net 26 "/Deserializer/VDD_1.8V")
			(pinfunction "VDD_1.8V")
			(pintype "passive")
		)
		(pad "22" smd roundrect
			(at 0.25 4 315)
			(size 0.8 0.3)
			(layers "F.Cu" "F.Mask" "F.Paste")
			(roundrect_rratio 0.25)
			(net 18 "/Deserializer/SIOA_N")
			(pinfunction "SIOA_N")
			(pintype "passive")
		)
		(pad "23" smd roundrect
			(at 0.75 4 315)
			(size 0.8 0.3)
			(layers "F.Cu" "F.Mask" "F.Paste")
			(roundrect_rratio 0.25)
			(net 13 "/Deserializer/SIOA_P")
			(pinfunction "SIOA_P")
			(pintype "passive")
		)
		(pad "24" smd roundrect
			(at 1.25 4.000001 315)
			(size 0.8 0.3)
			(layers "F.Cu" "F.Mask" "F.Paste")
			(roundrect_rratio 0.25)
			(net 146 "VDDIO")
			(pinfunction "VDDIO")
			(pintype "passive")
		)
		(pad "25" smd roundrect
			(at 1.75 4 315)
			(size 0.8 0.3)
			(layers "F.Cu" "F.Mask" "F.Paste")
			(roundrect_rratio 0.25)
			(net 77 "/Deserializer/CFG1")
			(pinfunction "CFG1/MFP6")
			(pintype "passive")
		)
		(pad "26" smd roundrect
			(at 2.25 4 315)
			(size 0.8 0.3)
			(layers "F.Cu" "F.Mask" "F.Paste")
			(roundrect_rratio 0.25)
			(net 86 "/Connectors/MFP7")
			(pinfunction "SDA1/MFP7")
			(pintype "passive")
		)
		(pad "27" smd roundrect
			(at 2.75 4 315)
			(size 0.8 0.3)
			(layers "F.Cu" "F.Mask" "F.Paste")
			(roundrect_rratio 0.25)
			(net 87 "/Connectors/MFP8")
			(pinfunction "SCL1/MFP8")
			(pintype "passive")
		)
		(pad "28" smd roundrect
			(at 3.25 4 315)
			(size 0.8 0.3)
			(layers "F.Cu" "F.Mask" "F.Paste")
			(roundrect_rratio 0.25)
			(net 88 "/Connectors/SDA")
			(pinfunction "SDA")
			(pintype "passive")
		)
		(pad "29" smd roundrect
			(at 4 3.25 225)
			(size 0.8 0.3)
			(layers "F.Cu" "F.Mask" "F.Paste")
			(roundrect_rratio 0.25)
			(net 121 "/Connectors/SCL")
			(pinfunction "SCL")
			(pintype "passive")
		)
		(pad "30" smd roundrect
			(at 4 2.75 225)
			(size 0.8 0.3)
			(layers "F.Cu" "F.Mask" "F.Paste")
			(roundrect_rratio 0.25)
			(net 29 "/Deserializer/VTERM")
			(pinfunction "VTERM")
			(pintype "passive")
		)
		(pad "31" smd roundrect
			(at 4 2.25 225)
			(size 0.8 0.3)
			(layers "F.Cu" "F.Mask" "F.Paste")
			(roundrect_rratio 0.25)
			(net 92 "/Connectors/CSI0.D0_P")
			(pinfunction "DA0_P")
			(pintype "passive")
		)
		(pad "32" smd roundrect
			(at 4 1.75 225)
			(size 0.8 0.3)
			(layers "F.Cu" "F.Mask" "F.Paste")
			(roundrect_rratio 0.25)
			(net 91 "/Connectors/CSI0.D0_N")
			(pinfunction "DA0_N")
			(pintype "passive")
		)
		(pad "33" smd roundrect
			(at 4.000001 1.25 225)
			(size 0.8 0.3)
			(layers "F.Cu" "F.Mask" "F.Paste")
			(roundrect_rratio 0.25)
			(net 136 "unconnected-(U7-CKC_P-Pad33)")
			(pinfunction "CKC_P")
			(pintype "passive+no_connect")
		)
		(pad "34" smd roundrect
			(at 4 0.75 225)
			(size 0.8 0.3)
			(layers "F.Cu" "F.Mask" "F.Paste")
			(roundrect_rratio 0.25)
			(net 137 "unconnected-(U7-CKC_N-Pad34)")
			(pinfunction "CKC_N")
			(pintype "passive+no_connect")
		)
		(pad "35" smd roundrect
			(at 4 0.25 225)
			(size 0.8 0.3)
			(layers "F.Cu" "F.Mask" "F.Paste")
			(roundrect_rratio 0.25)
			(net 90 "/Connectors/CSI0.D1_P")
			(pinfunction "DA1_P")
			(pintype "passive")
		)
		(pad "36" smd roundrect
			(at 4 -0.25 225)
			(size 0.8 0.3)
			(layers "F.Cu" "F.Mask" "F.Paste")
			(roundrect_rratio 0.25)
			(net 89 "/Connectors/CSI0.D1_N")
			(pinfunction "DA1_N")
			(pintype "passive")
		)
		(pad "37" smd roundrect
			(at 4 -0.75 225)
			(size 0.8 0.3)
			(layers "F.Cu" "F.Mask" "F.Paste")
			(roundrect_rratio 0.25)
			(net 102 "/Connectors/CSI0.D2_P")
			(pinfunction "DA2_P")
			(pintype "passive")
		)
		(pad "38" smd roundrect
			(at 4.000001 -1.25 225)
			(size 0.8 0.3)
			(layers "F.Cu" "F.Mask" "F.Paste")
			(roundrect_rratio 0.25)
			(net 101 "/Connectors/CSI0.D2_N")
			(pinfunction "DA2_N")
			(pintype "passive")
		)
		(pad "39" smd roundrect
			(at 4 -1.75 225)
			(size 0.8 0.3)
			(layers "F.Cu" "F.Mask" "F.Paste")
			(roundrect_rratio 0.25)
			(net 104 "/Connectors/CSI0.CLK_P")
			(pinfunction "CKA_P")
			(pintype "passive")
		)
		(pad "40" smd roundrect
			(at 4 -2.25 225)
			(size 0.8 0.3)
			(layers "F.Cu" "F.Mask" "F.Paste")
			(roundrect_rratio 0.25)
			(net 103 "/Connectors/CSI0.CLK_N")
			(pinfunction "CKA_N")
			(pintype "passive")
		)
		(pad "41" smd roundrect
			(at 4 -2.75 225)
			(size 0.8 0.3)
			(layers "F.Cu" "F.Mask" "F.Paste")
			(roundrect_rratio 0.25)
			(net 100 "/Connectors/CSI0.D3_P")
			(pinfunction "DA3_P")
			(pintype "passive")
		)
		(pad "42" smd roundrect
			(at 4 -3.25 225)
			(size 0.8 0.3)
			(layers "F.Cu" "F.Mask" "F.Paste")
			(roundrect_rratio 0.25)
			(net 99 "/Connectors/CSI0.D3_N")
			(pinfunction "DA3_N")
			(pintype "passive")
		)
		(pad "43" smd roundrect
			(at 3.25 -4 315)
			(size 0.8 0.3)
			(layers "F.Cu" "F.Mask" "F.Paste")
			(roundrect_rratio 0.25)
			(net 96 "/Connectors/CSI1.D0_P")
			(pinfunction "DB0_P")
			(pintype "passive")
		)
		(pad "44" smd roundrect
			(at 2.75 -4 315)
			(size 0.8 0.3)
			(layers "F.Cu" "F.Mask" "F.Paste")
			(roundrect_rratio 0.25)
			(net 95 "/Connectors/CSI1.D0_N")
			(pinfunction "DB0_N")
			(pintype "passive")
		)
		(pad "45" smd roundrect
			(at 2.25 -4 315)
			(size 0.8 0.3)
			(layers "F.Cu" "F.Mask" "F.Paste")
			(roundrect_rratio 0.25)
			(net 98 "/Connectors/CSI1.CLK_P")
			(pinfunction "CKB_P")
			(pintype "passive")
		)
		(pad "46" smd roundrect
			(at 1.75 -4 315)
			(size 0.8 0.3)
			(layers "F.Cu" "F.Mask" "F.Paste")
			(roundrect_rratio 0.25)
			(net 97 "/Connectors/CSI1.CLK_N")
			(pinfunction "CKB_N")
			(pintype "passive")
		)
		(pad "47" smd roundrect
			(at 1.25 -4.000001 315)
			(size 0.8 0.3)
			(layers "F.Cu" "F.Mask" "F.Paste")
			(roundrect_rratio 0.25)
			(net 94 "/Connectors/CSI1.D1_P")
			(pinfunction "DB1_P")
			(pintype "passive")
		)
		(pad "48" smd roundrect
			(at 0.75 -4 315)
			(size 0.8 0.3)
			(layers "F.Cu" "F.Mask" "F.Paste")
			(roundrect_rratio 0.25)
			(net 93 "/Connectors/CSI1.D1_N")
			(pinfunction "DB1_N")
			(pintype "passive")
		)
		(pad "49" smd roundrect
			(at 0.25 -4 315)
			(size 0.8 0.3)
			(layers "F.Cu" "F.Mask" "F.Paste")
			(roundrect_rratio 0.25)
			(net 108 "/Connectors/CSI1.D2_P")
			(pinfunction "DB2_P")
			(pintype "passive")
		)
		(pad "50" smd roundrect
			(at -0.25 -4 315)
			(size 0.8 0.3)
			(layers "F.Cu" "F.Mask" "F.Paste")
			(roundrect_rratio 0.25)
			(net 107 "/Connectors/CSI1.D2_N")
			(pinfunction "DB2_N")
			(pintype "passive")
		)
		(pad "51" smd roundrect
			(at -0.75 -4 315)
			(size 0.8 0.3)
			(layers "F.Cu" "F.Mask" "F.Paste")
			(roundrect_rratio 0.25)
			(net 138 "unconnected-(U7-CKF_P-Pad51)")
			(pinfunction "CKF_P")
			(pintype "passive+no_connect")
		)
		(pad "52" smd roundrect
			(at -1.25 -4.000001 315)
			(size 0.8 0.3)
			(layers "F.Cu" "F.Mask" "F.Paste")
			(roundrect_rratio 0.25)
			(net 139 "unconnected-(U7-CKF_N-Pad52)")
			(pinfunction "CKF_N")
			(pintype "passive+no_connect")
		)
		(pad "53" smd roundrect
			(at -1.75 -4 315)
			(size 0.8 0.3)
			(layers "F.Cu" "F.Mask" "F.Paste")
			(roundrect_rratio 0.25)
			(net 106 "/Connectors/CSI1.D3_P")
			(pinfunction "DB3_P")
			(pintype "passive")
		)
		(pad "54" smd roundrect
			(at -2.25 -4 315)
			(size 0.8 0.3)
			(layers "F.Cu" "F.Mask" "F.Paste")
			(roundrect_rratio 0.25)
			(net 105 "/Connectors/CSI1.D3_N")
			(pinfunction "DB3_N")
			(pintype "passive")
		)
		(pad "55" smd roundrect
			(at -2.75 -4 315)
			(size 0.8 0.3)
			(layers "F.Cu" "F.Mask" "F.Paste")
			(roundrect_rratio 0.25)
			(net 27 "/Deserializer/VDD")
			(pinfunction "VDD")
			(pintype "passive")
		)
		(pad "56" smd roundrect
			(at -3.25 -4 315)
			(size 0.8 0.3)
			(layers "F.Cu" "F.Mask" "F.Paste")
			(roundrect_rratio 0.25)
			(net 27 "/Deserializer/VDD")
			(pinfunction "VDD")
			(pintype "passive")
		)
		(pad "57" smd roundrect
			(at 0 0 225)
			(size 4.8 4.8)
			(layers "F.Cu" "F.Mask")
			(roundrect_rratio 0.1)
			(net 1 "GND")
			(pinfunction "GND")
			(pintype "passive")
		)
	)
	(footprint "antmicro-footprints:TP_SMD_0.75mm"
		(layer "F.Cu")
		(at 155.448 97.89)
		(property "Reference" "TP7"
			(at 0 -0.6 0)
			(layer "F.SilkS")
			(hide yes)
			(effects
				(font
					(size 0.7 0.7)
					(thickness 0.15)
				)
				(justify left bottom)
			)
		)
		(property "Value" "TP_0.75mm_SMD"
			(at 0 1.2 0)
			(layer "F.Fab")
			(effects
				(font
					(size 0.7 0.7)
					(thickness 0.15)
				)
				(justify left bottom)
			)
		)
		(property "Description" "SMT test point"
			(at 0 0 0)
			(layer "F.Fab")
			(hide yes)
			(effects
				(font
					(size 1.27 1.27)
					(thickness 0.15)
				)
			)
		)
		(property "Author" "Antmicro"
			(at 0 0 0)
			(layer "F.Fab")
			(hide yes)
			(effects
				(font
					(size 1 1)
					(thickness 0.15)
				)
			)
		)
		(property "License" "Apache-2.0"
			(at 0 0 0)
			(layer "F.Fab")
			(hide yes)
			(effects
				(font
					(size 1 1)
					(thickness 0.15)
				)
			)
		)
		(property "MPN" ""
			(at 0 0 0)
			(layer "F.Fab")
			(hide yes)
			(effects
				(font
					(size 1 1)
					(thickness 0.15)
				)
			)
		)
		(property "Manufacturer" ""
			(at 0 0 0)
			(layer "F.Fab")
			(hide yes)
			(effects
				(font
					(size 1 1)
					(thickness 0.15)
				)
			)
		)
		(sheetname "/Connectors/")
		(sheetfile "connectors.kicad_sch")
		(fp_circle
			(center 0 0)
			(end 0.475 0)
			(stroke
				(width 0.05)
				(type default)
			)
			(fill no)
			(layer "F.CrtYd")
		)
		(pad "1" smd circle
			(at 0 0)
			(size 0.75 0.75)
			(layers "F.Cu" "F.Mask")
			(net 113 "/Connectors/FFC_5V")
			(pinfunction "1")
			(pintype "passive")
		)
	)
	(footprint "antmicro-footprints:SOD-123FL"
		(layer "F.Cu")
		(at 175.005 51.308)
		(property "Reference" "D1"
			(at 2.063307 -0.360854 0)
			(layer "F.SilkS")
			(effects
				(font
					(size 0.7 0.7)
					(thickness 0.15)
				)
				(justify left bottom)
			)
		)
		(property "Value" "SMF4L15A"
			(at 0 1.967 0)
			(layer "F.Fab")
			(effects
				(font
					(size 0.7 0.7)
					(thickness 0.15)
				)
				(justify left bottom)
			)
		)
		(property "Datasheet" "https://www.littelfuse.com/media?resourcetype=datasheets&itemid=d2ba8fab-1de3-4176-8530-f36ecb0b8799&filename=smf4l"
			(at 0 0 0)
			(layer "F.Fab")
			(hide yes)
			(effects
				(font
					(size 1.27 1.27)
					(thickness 0.15)
				)
			)
		)
		(property "Description" "Unidirectional TVS, 30 kV,  SOD-123FL, 15 V, 600 pF"
			(at 0 0 0)
			(layer "F.Fab")
			(hide yes)
			(effects
				(font
					(size 1.27 1.27)
					(thickness 0.15)
				)
			)
		)
		(property "Author" "Antmicro"
			(at 0 0 0)
			(layer "F.Fab")
			(hide yes)
			(effects
				(font
					(size 1 1)
					(thickness 0.15)
				)
			)
		)
		(property "License" "Apache-2.0"
			(at 0 0 0)
			(layer "F.Fab")
			(hide yes)
			(effects
				(font
					(size 1 1)
					(thickness 0.15)
				)
			)
		)
		(property "MPN" "SMF4L15A"
			(at 0 0 0)
			(layer "F.Fab")
			(hide yes)
			(effects
				(font
					(size 1 1)
					(thickness 0.15)
				)
			)
		)
		(property "Manufacturer" "Littelfuse"
			(at 0 0 0)
			(layer "F.Fab")
			(hide yes)
			(effects
				(font
					(size 1 1)
					(thickness 0.15)
				)
			)
		)
		(sheetname "/Connectors/")
		(sheetfile "connectors.kicad_sch")
		(attr smd)
		(fp_line
			(start -2.3 -1.1)
			(end -2.3 1.1)
			(stroke
				(width 0.15)
				(type solid)
			)
			(layer "F.SilkS")
		)
		(fp_line
			(start -2.3 1.1)
			(end 0 1.1)
			(stroke
				(width 0.15)
				(type solid)
			)
			(layer "F.SilkS")
		)
		(fp_line
			(start 0 -1.1)
			(end -2.3 -1.1)
			(stroke
				(width 0.15)
				(type solid)
			)
			(layer "F.SilkS")
		)
		(fp_rect
			(start -2.35 -1.125)
			(end 2.35 1.125)
			(stroke
				(width 0.05)
				(type solid)
			)
			(fill no)
			(layer "F.CrtYd")
		)
		(fp_rect
			(start -1.825 -0.875)
			(end 1.824 0.873)
			(stroke
				(width 0.15)
				(type solid)
			)
			(fill no)
			(layer "F.Fab")
		)
		(fp_rect
			(start -0.775 -0.875)
			(end -0.525 0.875)
			(stroke
				(width 0.15)
				(type solid)
			)
			(fill yes)
			(layer "F.Fab")
		)
		(pad "1" smd roundrect
			(at -1.43 0)
			(size 1.34 1.8)
			(layers "F.Cu" "F.Mask" "F.Paste")
			(roundrect_rratio 0.14)
			(net 2 "/Connectors/DC_UNFUSED")
			(pinfunction "C")
			(pintype "passive")
		)
		(pad "2" smd roundrect
			(at 1.429 0)
			(size 1.34 1.8)
			(layers "F.Cu" "F.Mask" "F.Paste")
			(roundrect_rratio 0.14)
			(net 1 "GND")
			(pinfunction "A")
			(pintype "passive")
		)
	)
	(footprint "antmicro-footprints:C_0402_1005Metric"
		(layer "F.Cu")
		(at 151.13 74.676 45)
		(descr "Capacitor SMD 0402")
		(tags "capacitor SMD 0402")
		(property "Reference" "C29"
			(at 4.003639 0.193747 45)
			(layer "F.SilkS")
			(effects
				(font
					(size 0.7 0.7)
					(thickness 0.15)
				)
				(justify left bottom)
			)
		)
		(property "Value" "C_100n_0402"
			(at -1.022927 2.155213 45)
			(layer "F.Fab")
			(effects
				(font
					(size 0.7 0.7)
					(thickness 0.15)
				)
				(justify left bottom)
			)
		)
		(property "Datasheet" "https://www.murata.com/products/productdetail?partno=GRM155R61H104KE14%23"
			(at 0 0 45)
			(layer "F.Fab")
			(hide yes)
			(effects
				(font
					(size 1.27 1.27)
					(thickness 0.15)
				)
			)
		)
		(property "Description" "SMD Multilayer Ceramic Capacitor, 0.1 µF, 50 V, 0402 [1005 Metric], ± 10%, X5R, GRM Series"
			(at 0 0 45)
			(layer "F.Fab")
			(hide yes)
			(effects
				(font
					(size 1.27 1.27)
					(thickness 0.15)
				)
			)
		)
		(property "Author" "Antmicro"
			(at 97.068858 -84.992954 0)
			(layer "F.Fab")
			(hide yes)
			(effects
				(font
					(size 1 1)
					(thickness 0.15)
				)
			)
		)
		(property "Dielectric" "X5R"
			(at 97.068858 -84.992954 0)
			(layer "F.Fab")
			(hide yes)
			(effects
				(font
					(size 1 1)
					(thickness 0.15)
				)
			)
		)
		(property "License" "Apache-2.0"
			(at 97.068858 -84.992954 0)
			(layer "F.Fab")
			(hide yes)
			(effects
				(font
					(size 1 1)
					(thickness 0.15)
				)
			)
		)
		(property "MPN" "GRM155R61H104KE14D"
			(at 97.068858 -84.992954 0)
			(layer "F.Fab")
			(hide yes)
			(effects
				(font
					(size 1 1)
					(thickness 0.15)
				)
			)
		)
		(property "Manufacturer" "Murata"
			(at 97.068858 -84.992954 0)
			(layer "F.Fab")
			(hide yes)
			(effects
				(font
					(size 1 1)
					(thickness 0.15)
				)
			)
		)
		(property "Val" "100n"
			(at 97.068858 -84.992954 0)
			(layer "F.Fab")
			(hide yes)
			(effects
				(font
					(size 1 1)
					(thickness 0.15)
				)
			)
		)
		(property "Voltage" "50V"
			(at 97.068858 -84.992954 0)
			(layer "F.Fab")
			(hide yes)
			(effects
				(font
					(size 1 1)
					(thickness 0.15)
				)
			)
		)
		(sheetname "/Deserializer/")
		(sheetfile "deserializer.kicad_sch")
		(attr smd)
		(fp_poly
			(pts
				(xy -0.925 -0.47) (xy 0.925 -0.47) (xy 0.925 0.47) (xy -0.925 0.47)
			)
			(stroke
				(width 0.05)
				(type default)
			)
			(fill no)
			(layer "F.CrtYd")
		)
		(fp_line
			(start -0.494 -0.25)
			(end 0.504 -0.25)
			(stroke
				(width 0.15)
				(type solid)
			)
			(layer "F.Fab")
		)
		(fp_line
			(start -0.494 0.248)
			(end -0.494 -0.25)
			(stroke
				(width 0.15)
				(type solid)
			)
			(layer "F.Fab")
		)
		(fp_line
			(start 0.504 -0.25)
			(end 0.504 0.248)
			(stroke
				(width 0.15)
				(type solid)
			)
			(layer "F.Fab")
		)
		(fp_line
			(start 0.504 0.248)
			(end -0.494 0.248)
			(stroke
				(width 0.15)
				(type solid)
			)
			(layer "F.Fab")
		)
		(pad "1" smd roundrect
			(at -0.48 0 45)
			(size 0.59 0.64)
			(layers "F.Cu" "F.Mask" "F.Paste")
			(roundrect_rratio 0.25)
			(net 15 "/Deserializer/SIOC_P")
			(pintype "passive")
		)
		(pad "2" smd roundrect
			(at 0.48 0 45)
			(size 0.59 0.64)
			(layers "F.Cu" "F.Mask" "F.Paste")
			(roundrect_rratio 0.25)
			(net 116 "/Connectors/PoCC")
			(pintype "passive")
		)
	)
	(footprint "antmicro-footprints:R_0402_1005Metric"
		(layer "F.Cu")
		(at 173.656 64.87 90)
		(descr "Resistor SMD 0402")
		(tags "resistor SMD 0402")
		(property "Reference" "R58"
			(at -2.996432 0.322713 90)
			(layer "F.SilkS")
			(effects
				(font
					(size 0.7 0.7)
					(thickness 0.15)
				)
				(justify left bottom)
			)
		)
		(property "Value" "R_2k2_0402"
			(at -1.011843 1.772047 90)
			(layer "F.Fab")
			(effects
				(font
					(size 0.7 0.7)
					(thickness 0.15)
				)
				(justify left bottom)
			)
		)
		(property "Datasheet" "https://www.bourns.com/docs/product-datasheets/cr.pdf"
			(at 0 0 90)
			(layer "F.Fab")
			(hide yes)
			(effects
				(font
					(size 1.27 1.27)
					(thickness 0.15)
				)
			)
		)
		(property "Description" "SMD Chip Resistor, 2.2 kohm, ± 1%, 62.5 mW, 0402 [1005 Metric], Thick Film, General Purpose"
			(at 0 0 90)
			(layer "F.Fab")
			(hide yes)
			(effects
				(font
					(size 1.27 1.27)
					(thickness 0.15)
				)
			)
		)
		(property "Author" "Antmicro"
			(at 238.526 -108.786 0)
			(layer "F.Fab")
			(hide yes)
			(effects
				(font
					(size 1 1)
					(thickness 0.15)
				)
			)
		)
		(property "License" "Apache-2.0"
			(at 238.526 -108.786 0)
			(layer "F.Fab")
			(hide yes)
			(effects
				(font
					(size 1 1)
					(thickness 0.15)
				)
			)
		)
		(property "MPN" "CR0402-FX-2201GLF"
			(at 238.526 -108.786 0)
			(layer "F.Fab")
			(hide yes)
			(effects
				(font
					(size 1 1)
					(thickness 0.15)
				)
			)
		)
		(property "Manufacturer" "Bourns"
			(at 238.526 -108.786 0)
			(layer "F.Fab")
			(hide yes)
			(effects
				(font
					(size 1 1)
					(thickness 0.15)
				)
			)
		)
		(property "Tolerance" "1%"
			(at 238.526 -108.786 0)
			(layer "F.Fab")
			(hide yes)
			(effects
				(font
					(size 1 1)
					(thickness 0.15)
				)
			)
		)
		(property "Val" "2k2"
			(at 238.526 -108.786 0)
			(layer "F.Fab")
			(hide yes)
			(effects
				(font
					(size 1 1)
					(thickness 0.15)
				)
			)
		)
		(sheetname "/Connectors/")
		(sheetfile "connectors.kicad_sch")
		(attr smd)
		(fp_rect
			(start -0.925 -0.47)
			(end 0.925 0.47)
			(stroke
				(width 0.05)
				(type default)
			)
			(fill no)
			(layer "F.CrtYd")
		)
		(fp_rect
			(start -0.5 -0.25)
			(end 0.5 0.25)
			(stroke
				(width 0.15)
				(type solid)
			)
			(fill no)
			(layer "F.Fab")
		)
		(pad "1" smd roundrect
			(at -0.48 0 90)
			(size 0.59 0.64)
			(layers "F.Cu" "F.Mask" "F.Paste")
			(roundrect_rratio 0.25)
			(net 133 "Net-(U8-A_{1})")
			(pintype "passive")
		)
		(pad "2" smd roundrect
			(at 0.48 0 90)
			(size 0.59 0.64)
			(layers "F.Cu" "F.Mask" "F.Paste")
			(roundrect_rratio 0.25)
			(net 3 "+1V8")
			(pintype "passive")
		)
	)
	(footprint "antmicro-footprints:R_0402_1005Metric"
		(layer "F.Cu")
		(at 162.052 56.642 90)
		(descr "Resistor SMD 0402")
		(tags "resistor SMD 0402")
		(property "Reference" "R27"
			(at -1.122484 1.262 90)
			(layer "F.SilkS")
			(effects
				(font
					(size 0.7 0.7)
					(thickness 0.15)
				)
				(justify left bottom)
			)
		)
		(property "Value" "R_5k1_0402"
			(at -1.011843 1.772047 90)
			(layer "F.Fab")
			(effects
				(font
					(size 0.7 0.7)
					(thickness 0.15)
				)
				(justify left bottom)
			)
		)
		(property "Datasheet" "https://www.bourns.com/docs/product-datasheets/cr.pdf"
			(at 0 0 90)
			(layer "F.Fab")
			(hide yes)
			(effects
				(font
					(size 1.27 1.27)
					(thickness 0.15)
				)
			)
		)
		(property "Description" "SMD Chip Resistor, 5.1 kohm, ± 1%, 63 mW, 0402 [1005 Metric], Thick Film, General Purpose"
			(at 0 0 90)
			(layer "F.Fab")
			(hide yes)
			(effects
				(font
					(size 1.27 1.27)
					(thickness 0.15)
				)
			)
		)
		(property "Author" "Antmicro"
			(at 218.694 -105.41 0)
			(layer "F.Fab")
			(hide yes)
			(effects
				(font
					(size 1 1)
					(thickness 0.15)
				)
			)
		)
		(property "License" "Apache-2.0"
			(at 218.694 -105.41 0)
			(layer "F.Fab")
			(hide yes)
			(effects
				(font
					(size 1 1)
					(thickness 0.15)
				)
			)
		)
		(property "MPN" "CR0402-FX-5101GLF"
			(at 218.694 -105.41 0)
			(layer "F.Fab")
			(hide yes)
			(effects
				(font
					(size 1 1)
					(thickness 0.15)
				)
			)
		)
		(property "Manufacturer" "Bourns"
			(at 218.694 -105.41 0)
			(layer "F.Fab")
			(hide yes)
			(effects
				(font
					(size 1 1)
					(thickness 0.15)
				)
			)
		)
		(property "Tolerance" "1%"
			(at 218.694 -105.41 0)
			(layer "F.Fab")
			(hide yes)
			(effects
				(font
					(size 1 1)
					(thickness 0.15)
				)
			)
		)
		(property "Val" "5k1"
			(at 218.694 -105.41 0)
			(layer "F.Fab")
			(hide yes)
			(effects
				(font
					(size 1 1)
					(thickness 0.15)
				)
			)
		)
		(sheetname "/Power/")
		(sheetfile "power.kicad_sch")
		(attr smd)
		(fp_rect
			(start -0.925 -0.47)
			(end 0.925 0.47)
			(stroke
				(width 0.05)
				(type default)
			)
			(fill no)
			(layer "F.CrtYd")
		)
		(fp_rect
			(start -0.5 -0.25)
			(end 0.5 0.25)
			(stroke
				(width 0.15)
				(type solid)
			)
			(fill no)
			(layer "F.Fab")
		)
		(pad "1" smd roundrect
			(at -0.48 0 90)
			(size 0.59 0.64)
			(layers "F.Cu" "F.Mask" "F.Paste")
			(roundrect_rratio 0.25)
			(net 54 "Net-(L4-Pad2)")
			(pintype "passive")
		)
		(pad "2" smd roundrect
			(at 0.48 0 90)
			(size 0.59 0.64)
			(layers "F.Cu" "F.Mask" "F.Paste")
			(roundrect_rratio 0.25)
			(net 58 "Net-(L12-Pad1)")
			(pintype "passive")
		)
	)
	(footprint "antmicro-footprints:C_0402_1005Metric"
		(layer "F.Cu")
		(at 135.564 66.5564 90)
		(descr "Capacitor SMD 0402")
		(tags "capacitor SMD 0402")
		(property "Reference" "C11"
			(at -1.7696 1.215 90)
			(layer "F.SilkS")
			(effects
				(font
					(size 0.7 0.7)
					(thickness 0.15)
				)
				(justify left bottom)
			)
		)
		(property "Value" "C_10n_0402"
			(at -1.022927 2.155213 90)
			(layer "F.Fab")
			(effects
				(font
					(size 0.7 0.7)
					(thickness 0.15)
				)
				(justify left bottom)
			)
		)
		(property "Datasheet" "https://www.murata.com/products/productdetail?partno=GRM155R71H103KA88%23"
			(at 0 0 90)
			(layer "F.Fab")
			(hide yes)
			(effects
				(font
					(size 1.27 1.27)
					(thickness 0.15)
				)
			)
		)
		(property "Description" "SMD Multilayer Ceramic Capacitor, 10000 pF, 50 V, 0402 [1005 Metric], ± 10%, X7R, GRM Series"
			(at 0 0 90)
			(layer "F.Fab")
			(hide yes)
			(effects
				(font
					(size 1.27 1.27)
					(thickness 0.15)
				)
			)
		)
		(property "Author" "Antmicro"
			(at 202.1204 -69.0076 0)
			(layer "F.Fab")
			(hide yes)
			(effects
				(font
					(size 1 1)
					(thickness 0.15)
				)
			)
		)
		(property "Dielectric" "X7R"
			(at 202.1204 -69.0076 0)
			(layer "F.Fab")
			(hide yes)
			(effects
				(font
					(size 1 1)
					(thickness 0.15)
				)
			)
		)
		(property "License" "Apache-2.0"
			(at 202.1204 -69.0076 0)
			(layer "F.Fab")
			(hide yes)
			(effects
				(font
					(size 1 1)
					(thickness 0.15)
				)
			)
		)
		(property "MPN" "GRM155R71H103KA88D"
			(at 202.1204 -69.0076 0)
			(layer "F.Fab")
			(hide yes)
			(effects
				(font
					(size 1 1)
					(thickness 0.15)
				)
			)
		)
		(property "Manufacturer" "Murata"
			(at 202.1204 -69.0076 0)
			(layer "F.Fab")
			(hide yes)
			(effects
				(font
					(size 1 1)
					(thickness 0.15)
				)
			)
		)
		(property "Val" "10n"
			(at 202.1204 -69.0076 0)
			(layer "F.Fab")
			(hide yes)
			(effects
				(font
					(size 1 1)
					(thickness 0.15)
				)
			)
		)
		(property "Voltage" "50V"
			(at 202.1204 -69.0076 0)
			(layer "F.Fab")
			(hide yes)
			(effects
				(font
					(size 1 1)
					(thickness 0.15)
				)
			)
		)
		(sheetname "/Power/")
		(sheetfile "power.kicad_sch")
		(attr smd)
		(fp_rect
			(start -0.925 -0.47)
			(end 0.925 0.47)
			(stroke
				(width 0.05)
				(type default)
			)
			(fill no)
			(layer "F.CrtYd")
		)
		(fp_line
			(start 0.504 -0.25)
			(end 0.504 0.248)
			(stroke
				(width 0.15)
				(type solid)
			)
			(layer "F.Fab")
		)
		(fp_line
			(start -0.494 -0.25)
			(end 0.504 -0.25)
			(stroke
				(width 0.15)
				(type solid)
			)
			(layer "F.Fab")
		)
		(fp_line
			(start 0.504 0.248)
			(end -0.494 0.248)
			(stroke
				(width 0.15)
				(type solid)
			)
			(layer "F.Fab")
		)
		(fp_line
			(start -0.494 0.248)
			(end -0.494 -0.25)
			(stroke
				(width 0.15)
				(type solid)
			)
			(layer "F.Fab")
		)
		(pad "1" smd roundrect
			(at -0.48 0 90)
			(size 0.59 0.64)
			(layers "F.Cu" "F.Mask" "F.Paste")
			(roundrect_rratio 0.25)
			(net 1 "GND")
			(pintype "passive")
		)
		(pad "2" smd roundrect
			(at 0.48 0 90)
			(size 0.59 0.64)
			(layers "F.Cu" "F.Mask" "F.Paste")
			(roundrect_rratio 0.25)
			(net 4 "+12V")
			(pintype "passive")
		)
	)
	(footprint "antmicro-footprints:SOT-23-5"
		(layer "F.Cu")
		(at 167.132 56.769 -90)
		(property "Reference" "U2"
			(at 2.159 1.778 270)
			(layer "F.SilkS")
			(effects
				(font
					(size 0.7 0.7)
					(thickness 0.15)
				)
				(justify left bottom)
			)
		)
		(property "Value" "SN74LV1T125DBVR"
			(at 0.002 2.799 90)
			(layer "F.Fab")
			(effects
				(font
					(size 0.7 0.7)
					(thickness 0.15)
				)
				(justify right bottom)
			)
		)
		(property "Datasheet" "https://www.ti.com/lit/ds/symlink/sn74lv1t125.pdf?HQS=dis-mous-null-mousermode-dsf-pf-null-wwe&ts=1627648952184&ref_url=https%253A%252F%252Fmouser.com%252F"
			(at 0 0 270)
			(layer "F.Fab")
			(hide yes)
			(effects
				(font
					(size 1.27 1.27)
					(thickness 0.15)
				)
			)
		)
		(property "Description" "Buffer, 74LV1T125, 1.6 V to 5.5 V, SOT-23-5"
			(at 0 0 270)
			(layer "F.Fab")
			(hide yes)
			(effects
				(font
					(size 1.27 1.27)
					(thickness 0.15)
				)
			)
		)
		(property "Author" "Antmicro"
			(at 110.363 223.901 0)
			(layer "F.Fab")
			(hide yes)
			(effects
				(font
					(size 1 1)
					(thickness 0.15)
				)
			)
		)
		(property "License" "Apache-2.0"
			(at 110.363 223.901 0)
			(layer "F.Fab")
			(hide yes)
			(effects
				(font
					(size 1 1)
					(thickness 0.15)
				)
			)
		)
		(property "MPN" "SN74LV1T125DBVR"
			(at 110.363 223.901 0)
			(layer "F.Fab")
			(hide yes)
			(effects
				(font
					(size 1 1)
					(thickness 0.15)
				)
			)
		)
		(property "Manufacturer" "Texas Instruments"
			(at 110.363 223.901 0)
			(layer "F.Fab")
			(hide yes)
			(effects
				(font
					(size 1 1)
					(thickness 0.15)
				)
			)
		)
		(sheetname "/Connectors/")
		(sheetfile "connectors.kicad_sch")
		(attr smd)
		(fp_line
			(start -0.85 1.6)
			(end -0.85 1.301)
			(stroke
				(width 0.15)
				(type solid)
			)
			(layer "F.SilkS")
		)
		(fp_line
			(start -0.55 1.6)
			(end -0.85 1.6)
			(stroke
				(width 0.15)
				(type solid)
			)
			(layer "F.SilkS")
		)
		(fp_line
			(start 0.8 1.599)
			(end 0.549 1.599)
			(stroke
				(width 0.15)
				(type solid)
			)
			(layer "F.SilkS")
		)
		(fp_line
			(start 0.8 1.3)
			(end 0.8 1.599)
			(stroke
				(width 0.15)
				(type solid)
			)
			(layer "F.SilkS")
		)
		(fp_line
			(start 0.8 0.55)
			(end 0.8 -0.55)
			(stroke
				(width 0.15)
				(type solid)
			)
			(layer "F.SilkS")
		)
		(fp_line
			(start 0.8 -1.3)
			(end 0.8 -1.6)
			(stroke
				(width 0.15)
				(type solid)
			)
			(layer "F.SilkS")
		)
		(fp_line
			(start -0.8 -1.6)
			(end -0.8 -1.3)
			(stroke
				(width 0.15)
				(type solid)
			)
			(layer "F.SilkS")
		)
		(fp_line
			(start -0.8 -1.6)
			(end -0.5 -1.6)
			(stroke
				(width 0.15)
				(type solid)
			)
			(layer "F.SilkS")
		)
		(fp_line
			(start 0.8 -1.6)
			(end 0.5 -1.6)
			(stroke
				(width 0.15)
				(type solid)
			)
			(layer "F.SilkS")
		)
		(fp_circle
			(center -1.25 -1.5)
			(end -1.2 -1.5)
			(stroke
				(width 0.15)
				(type solid)
			)
			(fill yes)
			(layer "F.SilkS")
		)
		(fp_rect
			(start 1.9 -1.76)
			(end -1.9 1.75)
			(stroke
				(width 0.05)
				(type solid)
			)
			(fill no)
			(layer "F.CrtYd")
		)
		(fp_line
			(start -0.398 -1.526)
			(end -0.874 -1.05)
			(stroke
				(width 0.15)
				(type solid)
			)
			(layer "F.Fab")
		)
		(fp_rect
			(start 0.874 1.523)
			(end -0.873 -1.525)
			(stroke
				(width 0.15)
				(type solid)
			)
			(fill no)
			(layer "F.Fab")
		)
		(pad "1" smd rect
			(at -1.351 -0.951 180)
			(size 0.55 1)
			(layers "F.Cu" "F.Mask" "F.Paste")
			(net 131 "Net-(U2-~{OE})")
			(pinfunction "~{OE}")
			(pintype "input")
		)
		(pad "2" smd rect
			(at -1.351 0 180)
			(size 0.55 1)
			(layers "F.Cu" "F.Mask" "F.Paste")
			(net 66 "/Connectors/VSYNC_CAM1")
			(pinfunction "A")
			(pintype "input")
		)
		(pad "3" smd rect
			(at -1.351 0.949 180)
			(size 0.55 1)
			(layers "F.Cu" "F.Mask" "F.Paste")
			(net 1 "GND")
			(pinfunction "GND")
			(pintype "power_in")
		)
		(pad "4" smd rect
			(at 1.35 0.949 180)
			(size 0.55 1)
			(layers "F.Cu" "F.Mask" "F.Paste")
			(net 132 "Net-(U2-Y)")
			(pinfunction "Y")
			(pintype "output")
		)
		(pad "5" smd rect
			(at 1.35 -0.951 180)
			(size 0.55 1)
			(layers "F.Cu" "F.Mask" "F.Paste")
			(net 3 "+1V8")
			(pinfunction "VCC")
			(pintype "power_in")
		)
	)
	(footprint "antmicro-footprints:L_Coilcraft-PFL1609"
		(layer "F.Cu")
		(at 128.524 53.594)
		(property "Reference" "L13"
			(at -1.498634 1.480804 0)
			(layer "F.SilkS")
			(effects
				(font
					(size 0.7 0.7)
					(thickness 0.15)
				)
				(justify left bottom)
			)
		)
		(property "Value" "L_470n_1A_Coilcraft-PFL1609"
			(at 0 2 0)
			(layer "F.Fab")
			(effects
				(font
					(size 0.7 0.7)
					(thickness 0.15)
				)
				(justify left bottom)
			)
		)
		(property "Datasheet" "https://www.coilcraft.com/getmedia/2f4cd442-d64d-4413-a518-12fcfd03318d/pfl1609.pdf"
			(at 0 0 0)
			(layer "F.Fab")
			(hide yes)
			(effects
				(font
					(size 1.27 1.27)
					(thickness 0.15)
				)
			)
		)
		(property "Description" "Power Inductor (SMT), 6.8 µH, 9.2 A, Shielded, 12.8 A, XAL7070"
			(at 0 0 0)
			(layer "F.Fab")
			(hide yes)
			(effects
				(font
					(size 1.27 1.27)
					(thickness 0.15)
				)
			)
		)
		(property "Author" "Antmicro"
			(at 0 0 0)
			(layer "F.Fab")
			(hide yes)
			(effects
				(font
					(size 1 1)
					(thickness 0.15)
				)
			)
		)
		(property "IMax" "1 A"
			(at 0 0 0)
			(layer "F.Fab")
			(hide yes)
			(effects
				(font
					(size 1 1)
					(thickness 0.15)
				)
			)
		)
		(property "ISat" "0.99 A"
			(at 0 0 0)
			(layer "F.Fab")
			(hide yes)
			(effects
				(font
					(size 1 1)
					(thickness 0.15)
				)
			)
		)
		(property "License" "Apache-2.0"
			(at 0 0 0)
			(layer "F.Fab")
			(hide yes)
			(effects
				(font
					(size 1 1)
					(thickness 0.15)
				)
			)
		)
		(property "MPN" "PFL1609-471"
			(at 0 0 0)
			(layer "F.Fab")
			(hide yes)
			(effects
				(font
					(size 1 1)
					(thickness 0.15)
				)
			)
		)
		(property "Manufacturer" "Coilcraft"
			(at 0 0 0)
			(layer "F.Fab")
			(hide yes)
			(effects
				(font
					(size 1 1)
					(thickness 0.15)
				)
			)
		)
		(property "Size" "1.07x1.8"
			(at 0 0 0)
			(layer "F.Fab")
			(hide yes)
			(effects
				(font
					(size 1 1)
					(thickness 0.15)
				)
			)
		)
		(property "Val" "470n/0.99A"
			(at 0 0 0)
			(layer "F.Fab")
			(hide yes)
			(effects
				(font
					(size 1 1)
					(thickness 0.15)
				)
			)
		)
		(sheetname "/Power/")
		(sheetfile "power.kicad_sch")
		(attr smd)
		(fp_line
			(start -0.23 -0.45)
			(end 0.23 -0.45)
			(stroke
				(width 0.15)
				(type solid)
			)
			(layer "F.SilkS")
		)
		(fp_line
			(start -0.23 0.45)
			(end 0.23 0.45)
			(stroke
				(width 0.15)
				(type solid)
			)
			(layer "F.SilkS")
		)
		(fp_rect
			(start -1.2 -0.84)
			(end 1.2 0.84)
			(stroke
				(width 0.05)
				(type solid)
			)
			(fill no)
			(layer "F.CrtYd")
		)
		(fp_rect
			(start -0.9 -0.535)
			(end 0.9 0.535)
			(stroke
				(width 0.15)
				(type solid)
			)
			(fill no)
			(layer "F.Fab")
		)
		(pad "1" smd roundrect
			(at -0.635 0)
			(size 0.64 1.02)
			(layers "F.Cu" "F.Mask" "F.Paste")
			(roundrect_rratio 0.15)
			(net 59 "Net-(L13-Pad1)")
			(pintype "passive")
		)
		(pad "2" smd roundrect
			(at 0.635 0)
			(size 0.64 1.02)
			(layers "F.Cu" "F.Mask" "F.Paste")
			(roundrect_rratio 0.15)
			(net 114 "/Connectors/PoCA")
			(pintype "passive")
		)
	)
	(footprint "antmicro-footprints:L_Coilcraft-MSS6132T"
		(layer "F.Cu")
		(at 135.128 61.976 90)
		(property "Reference" "L2"
			(at -0.635 -3.429 90)
			(layer "F.SilkS")
			(effects
				(font
					(size 0.7 0.7)
					(thickness 0.15)
				)
				(justify left bottom)
			)
		)
		(property "Value" "L_22u_1.12A_Coilcraft-MSS6132T"
			(at -0.508 4.826 90)
			(layer "F.Fab")
			(effects
				(font
					(size 0.7 0.7)
					(thickness 0.15)
				)
				(justify left bottom)
			)
		)
		(property "Datasheet" "https://www.coilcraft.com/getmedia/d035c9b3-191d-46aa-ab3f-5c1a849157c1/mss6132t.pdf"
			(at 0 0 90)
			(layer "F.Fab")
			(hide yes)
			(effects
				(font
					(size 1.27 1.27)
					(thickness 0.15)
				)
			)
		)
		(property "Description" "Power Inductor (SMT), 22 µH, 1.85 A, Shielded, 2.45 A, WE-MAPI"
			(at 0 0 90)
			(layer "F.Fab")
			(hide yes)
			(effects
				(font
					(size 1.27 1.27)
					(thickness 0.15)
				)
			)
		)
		(property "Author" "Antmicro"
			(at 197.104 -73.152 0)
			(layer "F.Fab")
			(hide yes)
			(effects
				(font
					(size 1 1)
					(thickness 0.15)
				)
			)
		)
		(property "IMax" "1.45A"
			(at 197.104 -73.152 0)
			(layer "F.Fab")
			(hide yes)
			(effects
				(font
					(size 1 1)
					(thickness 0.15)
				)
			)
		)
		(property "ISat" "1.12A"
			(at 197.104 -73.152 0)
			(layer "F.Fab")
			(hide yes)
			(effects
				(font
					(size 1 1)
					(thickness 0.15)
				)
			)
		)
		(property "License" "Apache-2.0"
			(at 197.104 -73.152 0)
			(layer "F.Fab")
			(hide yes)
			(effects
				(font
					(size 1 1)
					(thickness 0.15)
				)
			)
		)
		(property "MPN" "MSS6132T-223"
			(at 197.104 -73.152 0)
			(layer "F.Fab")
			(hide yes)
			(effects
				(font
					(size 1 1)
					(thickness 0.15)
				)
			)
		)
		(property "Manufacturer" "Coilcraft"
			(at 197.104 -73.152 0)
			(layer "F.Fab")
			(hide yes)
			(effects
				(font
					(size 1 1)
					(thickness 0.15)
				)
			)
		)
		(property "Size" "6.1x6.1"
			(at 197.104 -73.152 0)
			(layer "F.Fab")
			(hide yes)
			(effects
				(font
					(size 1 1)
					(thickness 0.15)
				)
			)
		)
		(property "Val" "22u/1.12A"
			(at 197.104 -73.152 0)
			(layer "F.Fab")
			(hide yes)
			(effects
				(font
					(size 1 1)
					(thickness 0.15)
				)
			)
		)
		(sheetname "/Power/")
		(sheetfile "power.kicad_sch")
		(attr smd)
		(fp_line
			(start -0.8 -3.05)
			(end 0.8 -3.05)
			(stroke
				(width 0.15)
				(type solid)
			)
			(layer "F.SilkS")
		)
		(fp_line
			(start -0.8 3.05)
			(end 0.8 3.05)
			(stroke
				(width 0.15)
				(type solid)
			)
			(layer "F.SilkS")
		)
		(fp_rect
			(start -3.35 -3.35)
			(end 3.35 3.35)
			(stroke
				(width 0.05)
				(type solid)
			)
			(fill no)
			(layer "F.CrtYd")
		)
		(fp_rect
			(start -3.1 -3.1)
			(end 3.1 3.1)
			(stroke
				(width 0.15)
				(type solid)
			)
			(fill no)
			(layer "F.Fab")
		)
		(pad "1" smd custom
			(at -2.71 0 180)
			(size 6 0.575)
			(layers "F.Cu" "F.Mask" "F.Paste")
			(net 4 "+12V")
			(pintype "passive")
			(options
				(clearance outline)
				(anchor rect)
			)
			(primitives
				(gr_poly
					(pts
						(xy 2.4 1.71) (xy 2.117646 1.21) (xy 1.9 0.96) (xy 1.65 0.71) (xy 1.2 0.41) (xy 0.4 0.11) (xy 0.4 0.01)
						(xy 2.9 0) (xy 2.9 1.71)
					)
					(width 0.2)
					(fill yes)
				)
				(gr_poly
					(pts
						(xy -2.4 1.731128) (xy -2.117646 1.231128) (xy -1.9 0.981128) (xy -1.65 0.731128) (xy -1.2 0.431128)
						(xy -0.4 0.131128) (xy -0.4 0.031128) (xy -2.9 0.021128) (xy -2.9 1.731128)
					)
					(width 0.2)
					(fill yes)
				)
			)
		)
		(pad "2" smd custom
			(at 2.71 0)
			(size 6 0.575)
			(layers "F.Cu" "F.Mask" "F.Paste")
			(net 52 "Net-(L2-Pad2)")
			(pintype "passive")
			(options
				(clearance outline)
				(anchor rect)
			)
			(primitives
				(gr_poly
					(pts
						(xy -2.4 1.731128) (xy -2.117646 1.231128) (xy -1.9 0.981128) (xy -1.65 0.731128) (xy -1.2 0.431128)
						(xy -0.4 0.131128) (xy -0.4 0.031128) (xy -2.9 0.021128) (xy -2.9 1.731128)
					)
					(width 0.2)
					(fill yes)
				)
				(gr_poly
					(pts
						(xy 2.4 1.71) (xy 2.117646 1.21) (xy 1.9 0.96) (xy 1.65 0.71) (xy 1.2 0.41) (xy 0.4 0.11) (xy 0.4 0.01)
						(xy 2.9 0) (xy 2.9 1.71)
					)
					(width 0.2)
					(fill yes)
				)
			)
		)
	)
	(footprint "antmicro-footprints:Conn_FAKRA_7-2287906-0"
		(layer "F.Cu")
		(at 163.782 38.348)
		(descr "Connector FAKRA, 5 pins")
		(property "Reference" "J5"
			(at 5.054 5.3 0)
			(layer "F.SilkS")
			(effects
				(font
					(size 0.7 0.7)
					(thickness 0.15)
				)
				(justify left bottom)
			)
		)
		(property "Value" "Conn_FAKRA_59S2AQ-40MT5-Z_1"
			(at -6.55 15.019 0)
			(layer "F.Fab")
			(effects
				(font
					(size 0.7 0.7)
					(thickness 0.15)
				)
				(justify left bottom)
			)
		)
		(property ki_fp_filters "*BNC* *SMA* *SMB* *SMC* *Cinch*")
		(sheetname "/Connectors/")
		(sheetfile "connectors.kicad_sch")
		(attr through_hole)
		(fp_line
			(start -4.572 0.94)
			(end -4.572 13.919)
			(stroke
				(width 0.15)
				(type solid)
			)
			(layer "F.SilkS")
		)
		(fp_line
			(start -4.572 13.919)
			(end 4.572 13.919)
			(stroke
				(width 0.15)
				(type solid)
			)
			(layer "F.SilkS")
		)
		(fp_line
			(start 4.572 0.94)
			(end -4.572 0.94)
			(stroke
				(width 0.15)
				(type solid)
			)
			(layer "F.SilkS")
		)
		(fp_line
			(start 4.572 13.919)
			(end 4.572 0.94)
			(stroke
				(width 0.15)
				(type solid)
			)
			(layer "F.SilkS")
		)
		(fp_rect
			(start -5.14 -12.64)
			(end 5.131 14.164)
			(stroke
				(width 0.05)
				(type solid)
			)
			(fill no)
			(layer "F.CrtYd")
		)
		(fp_text user "License: Apache-2.0"
			(at -6.55 16.219 0)
			(layer "F.Fab")
			(effects
				(font
					(size 0.7 0.7)
					(thickness 0.15)
				)
				(justify left bottom)
			)
		)
		(fp_text user "${REFERENCE}"
			(at -6.55 18.619 0)
			(layer "F.Fab")
			(effects
				(font
					(size 0.7 0.7)
					(thickness 0.15)
				)
				(justify left bottom)
			)
		)
		(fp_text user "Author: Antmicro"
			(at -6.55 17.419 0)
			(layer "F.Fab")
			(effects
				(font
					(size 0.7 0.7)
					(thickness 0.15)
				)
				(justify left bottom)
			)
		)
		(pad "1" smd roundrect
			(at 0 3.62 270)
			(size 4.79 1.9)
			(layers "F.Cu" "F.Mask" "F.Paste")
			(roundrect_rratio 0.25)
			(net 117 "/Connectors/PoCD")
			(pinfunction "1")
			(pintype "passive")
		)
		(pad "2" thru_hole circle
			(at -3 3.315 270)
			(size 1.8 1.8)
			(drill 1.45)
			(layers "*.Cu" "*.Mask")
			(remove_unused_layers no)
			(net 1 "GND")
			(pinfunction "2")
			(pintype "passive")
		)
		(pad "2" smd roundrect
			(at -2.9975 3.7175 270)
			(size 4.985 1.8)
			(layers "F.Cu" "F.Mask" "F.Paste")
			(roundrect_rratio 0.25)
			(net 1 "GND")
			(pinfunction "2")
			(pintype "passive")
		)
		(pad "3" thru_hole circle
			(at -3 10.315 270)
			(size 1.8 1.8)
			(drill 1.45)
			(layers "*.Cu" "*.Mask")
			(remove_unused_layers no)
			(net 1 "GND")
			(pinfunction "3")
			(pintype "passive")
		)
		(pad "3" smd roundrect
			(at -3 10.815 270)
			(size 5.6 1.8)
			(layers "F.Cu" "F.Mask" "F.Paste")
			(roundrect_rratio 0.25)
			(net 1 "GND")
			(pinfunction "3")
			(pintype "passive")
		)
		(pad "4" thru_hole circle
			(at 3 10.315 270)
			(size 1.8 1.8)
			(drill 1.45)
			(layers "*.Cu" "*.Mask")
			(remove_unused_layers no)
			(net 1 "GND")
			(pinfunction "4")
			(pintype "passive")
		)
		(pad "4" smd roundrect
			(at 3 10.815 270)
			(size 5.6 1.8)
			(layers "F.Cu" "F.Mask" "F.Paste")
			(roundrect_rratio 0.25)
			(net 1 "GND")
			(pinfunction "4")
			(pintype "passive")
		)
		(pad "5" thru_hole circle
			(at 3 3.315 270)
			(size 1.8 1.8)
			(drill 1.45)
			(layers "*.Cu" "*.Mask")
			(remove_unused_layers no)
			(net 1 "GND")
			(pinfunction "5")
			(pintype "passive")
		)
		(pad "5" smd roundrect
			(at 3 3.72 270)
			(size 4.99 1.8)
			(layers "F.Cu" "F.Mask" "F.Paste")
			(roundrect_rratio 0.25)
			(net 1 "GND")
			(pinfunction "5")
			(pintype "passive")
		)
	)
	(footprint "antmicro-footprints:R_0402_1005Metric"
		(layer "F.Cu")
		(at 172.132 64.87 90)
		(descr "Resistor SMD 0402")
		(tags "resistor SMD 0402")
		(property "Reference" "R59"
			(at -2.948 0.334 270)
			(layer "F.SilkS")
			(effects
				(font
					(size 0.7 0.7)
					(thickness 0.15)
				)
				(justify left bottom)
			)
		)
		(property "Value" "R_2k2_0402"
			(at -1.011843 1.772047 90)
			(layer "F.Fab")
			(effects
				(font
					(size 0.7 0.7)
					(thickness 0.15)
				)
				(justify left bottom)
			)
		)
		(property "Datasheet" "https://www.bourns.com/docs/product-datasheets/cr.pdf"
			(at 0 0 90)
			(layer "F.Fab")
			(hide yes)
			(effects
				(font
					(size 1.27 1.27)
					(thickness 0.15)
				)
			)
		)
		(property "Description" "SMD Chip Resistor, 2.2 kohm, ± 1%, 62.5 mW, 0402 [1005 Metric], Thick Film, General Purpose"
			(at 0 0 90)
			(layer "F.Fab")
			(hide yes)
			(effects
				(font
					(size 1.27 1.27)
					(thickness 0.15)
				)
			)
		)
		(property "Author" "Antmicro"
			(at 237.002 -107.262 0)
			(layer "F.Fab")
			(hide yes)
			(effects
				(font
					(size 1 1)
					(thickness 0.15)
				)
			)
		)
		(property "License" "Apache-2.0"
			(at 237.002 -107.262 0)
			(layer "F.Fab")
			(hide yes)
			(effects
				(font
					(size 1 1)
					(thickness 0.15)
				)
			)
		)
		(property "MPN" "CR0402-FX-2201GLF"
			(at 237.002 -107.262 0)
			(layer "F.Fab")
			(hide yes)
			(effects
				(font
					(size 1 1)
					(thickness 0.15)
				)
			)
		)
		(property "Manufacturer" "Bourns"
			(at 237.002 -107.262 0)
			(layer "F.Fab")
			(hide yes)
			(effects
				(font
					(size 1 1)
					(thickness 0.15)
				)
			)
		)
		(property "Tolerance" "1%"
			(at 237.002 -107.262 0)
			(layer "F.Fab")
			(hide yes)
			(effects
				(font
					(size 1 1)
					(thickness 0.15)
				)
			)
		)
		(property "Val" "2k2"
			(at 237.002 -107.262 0)
			(layer "F.Fab")
			(hide yes)
			(effects
				(font
					(size 1 1)
					(thickness 0.15)
				)
			)
		)
		(sheetname "/Connectors/")
		(sheetfile "connectors.kicad_sch")
		(attr smd)
		(fp_rect
			(start -0.925 -0.47)
			(end 0.925 0.47)
			(stroke
				(width 0.05)
				(type default)
			)
			(fill no)
			(layer "F.CrtYd")
		)
		(fp_rect
			(start -0.5 -0.25)
			(end 0.5 0.25)
			(stroke
				(width 0.15)
				(type solid)
			)
			(fill no)
			(layer "F.Fab")
		)
		(pad "1" smd roundrect
			(at -0.48 0 90)
			(size 0.59 0.64)
			(layers "F.Cu" "F.Mask" "F.Paste")
			(roundrect_rratio 0.25)
			(net 134 "Net-(U8-A_{2})")
			(pintype "passive")
		)
		(pad "2" smd roundrect
			(at 0.48 0 90)
			(size 0.59 0.64)
			(layers "F.Cu" "F.Mask" "F.Paste")
			(roundrect_rratio 0.25)
			(net 3 "+1V8")
			(pintype "passive")
		)
	)
	(footprint "antmicro-footprints:SOD-523_NP"
		(layer "F.Cu")
		(at 181.864 62.3535 -90)
		(property "Reference" "D9"
			(at 8.5125 -0.254 90)
			(layer "F.SilkS")
			(effects
				(font
					(size 0.7 0.7)
					(thickness 0.15)
				)
				(justify right bottom)
			)
		)
		(property "Value" "ESD5B5_0ST1G"
			(at 0 1.499 90)
			(layer "F.Fab")
			(effects
				(font
					(size 0.7 0.7)
					(thickness 0.15)
				)
				(justify right bottom)
			)
		)
		(property "Datasheet" "https://www.onsemi.com/pdf/datasheet/esd5b5.0st1-d.pdf"
			(at 0 0 270)
			(layer "F.Fab")
			(hide yes)
			(effects
				(font
					(size 1.27 1.27)
					(thickness 0.15)
				)
			)
		)
		(property "Description" "Bidirectional TVS, 30 kV,  SOD-523, 5 V, 32 pF"
			(at 0 0 270)
			(layer "F.Fab")
			(hide yes)
			(effects
				(font
					(size 1.27 1.27)
					(thickness 0.15)
				)
			)
		)
		(property "Author" "Antmicro"
			(at 119.5105 244.2175 0)
			(layer "F.Fab")
			(hide yes)
			(effects
				(font
					(size 1 1)
					(thickness 0.15)
				)
			)
		)
		(property "License" "Apache-2.0"
			(at 119.5105 244.2175 0)
			(layer "F.Fab")
			(hide yes)
			(effects
				(font
					(size 1 1)
					(thickness 0.15)
				)
			)
		)
		(property "MPN" "ESD5B5.0ST1G"
			(at 119.5105 244.2175 0)
			(layer "F.Fab")
			(hide yes)
			(effects
				(font
					(size 1 1)
					(thickness 0.15)
				)
			)
		)
		(property "Manufacturer" "ON Semiconductor"
			(at 119.5105 244.2175 0)
			(layer "F.Fab")
			(hide yes)
			(effects
				(font
					(size 1 1)
					(thickness 0.15)
				)
			)
		)
		(sheetname "/Connectors/")
		(sheetfile "connectors.kicad_sch")
		(attr smd)
		(fp_rect
			(start -1 -0.6)
			(end 1 0.6)
			(stroke
				(width 0.05)
				(type solid)
			)
			(fill no)
			(layer "F.CrtYd")
		)
		(fp_line
			(start -0.652 0.423)
			(end 0.65 0.423)
			(stroke
				(width 0.15)
				(type solid)
			)
			(layer "F.Fab")
		)
		(fp_line
			(start -0.652 0.423)
			(end -0.652 -0.425)
			(stroke
				(width 0.15)
				(type solid)
			)
			(layer "F.Fab")
		)
		(fp_line
			(start -0.652 -0.425)
			(end 0.65 -0.425)
			(stroke
				(width 0.15)
				(type solid)
			)
			(layer "F.Fab")
		)
		(fp_line
			(start 0.65 -0.425)
			(end 0.65 0.423)
			(stroke
				(width 0.15)
				(type solid)
			)
			(layer "F.Fab")
		)
		(pad "1" smd roundrect
			(at -0.701 0 270)
			(size 0.5 0.6)
			(layers "F.Cu" "F.Mask" "F.Paste")
			(roundrect_rratio 0.25)
			(net 1 "GND")
			(pinfunction "C")
			(pintype "passive")
		)
		(pad "2" smd roundrect
			(at 0.699 0 270)
			(size 0.5 0.6)
			(layers "F.Cu" "F.Mask" "F.Paste")
			(roundrect_rratio 0.25)
			(net 50 "/Connectors/FFC_3V3")
			(pinfunction "A")
			(pintype "passive")
		)
	)
	(footprint "antmicro-footprints:C_0402_1005Metric"
		(layer "F.Cu")
		(at 127.436 85.702 -90)
		(descr "Capacitor SMD 0402")
		(tags "capacitor SMD 0402")
		(property "Reference" "C25"
			(at -0.485 -2.104 90)
			(layer "F.SilkS")
			(effects
				(font
					(size 0.7 0.7)
					(thickness 0.15)
				)
				(justify right bottom)
			)
		)
		(property "Value" "C_22u_0402"
			(at -1.022927 2.155213 90)
			(layer "F.Fab")
			(effects
				(font
					(size 0.7 0.7)
					(thickness 0.15)
				)
				(justify right bottom)
			)
		)
		(property "Datasheet" "https://www.murata.com/products/productdetail?partno=GRM158R60J226ME01%23"
			(at 0 0 270)
			(layer "F.Fab")
			(hide yes)
			(effects
				(font
					(size 1.27 1.27)
					(thickness 0.15)
				)
			)
		)
		(property "Description" "SMD Multilayer Ceramic Capacitor, 22 uF, 4 V, 0402 [1005 Metric], X6S"
			(at 0 0 270)
			(layer "F.Fab")
			(hide yes)
			(effects
				(font
					(size 1.27 1.27)
					(thickness 0.15)
				)
			)
		)
		(property "Author" "Antmicro"
			(at 41.734 213.138 0)
			(layer "F.Fab")
			(hide yes)
			(effects
				(font
					(size 1 1)
					(thickness 0.15)
				)
			)
		)
		(property "Dielectric" ""
			(at 41.734 213.138 0)
			(layer "F.Fab")
			(hide yes)
			(effects
				(font
					(size 1 1)
					(thickness 0.15)
				)
			)
		)
		(property "License" "Apache-2.0"
			(at 41.734 213.138 0)
			(layer "F.Fab")
			(hide yes)
			(effects
				(font
					(size 1 1)
					(thickness 0.15)
				)
			)
		)
		(property "MPN" "GRM158R60J226ME01D"
			(at 41.734 213.138 0)
			(layer "F.Fab")
			(hide yes)
			(effects
				(font
					(size 1 1)
					(thickness 0.15)
				)
			)
		)
		(property "Manufacturer" "Murata"
			(at 41.734 213.138 0)
			(layer "F.Fab")
			(hide yes)
			(effects
				(font
					(size 1 1)
					(thickness 0.15)
				)
			)
		)
		(property "Val" "22u"
			(at 41.734 213.138 0)
			(layer "F.Fab")
			(hide yes)
			(effects
				(font
					(size 1 1)
					(thickness 0.15)
				)
			)
		)
		(property "Voltage" ""
			(at 41.734 213.138 0)
			(layer "F.Fab")
			(hide yes)
			(effects
				(font
					(size 1 1)
					(thickness 0.15)
				)
			)
		)
		(sheetname "/Power/")
		(sheetfile "power.kicad_sch")
		(attr smd)
		(fp_rect
			(start -0.925 -0.47)
			(end 0.925 0.47)
			(stroke
				(width 0.05)
				(type default)
			)
			(fill no)
			(layer "F.CrtYd")
		)
		(fp_line
			(start -0.494 0.248)
			(end -0.494 -0.25)
			(stroke
				(width 0.15)
				(type solid)
			)
			(layer "F.Fab")
		)
		(fp_line
			(start 0.504 0.248)
			(end -0.494 0.248)
			(stroke
				(width 0.15)
				(type solid)
			)
			(layer "F.Fab")
		)
		(fp_line
			(start -0.494 -0.25)
			(end 0.504 -0.25)
			(stroke
				(width 0.15)
				(type solid)
			)
			(layer "F.Fab")
		)
		(fp_line
			(start 0.504 -0.25)
			(end 0.504 0.248)
			(stroke
				(width 0.15)
				(type solid)
			)
			(layer "F.Fab")
		)
		(pad "1" smd roundrect
			(at -0.48 0 270)
			(size 0.59 0.64)
			(layers "F.Cu" "F.Mask" "F.Paste")
			(roundrect_rratio 0.25)
			(net 1 "GND")
			(pintype "passive")
		)
		(pad "2" smd roundrect
			(at 0.48 0 270)
			(size 0.59 0.64)
			(layers "F.Cu" "F.Mask" "F.Paste")
			(roundrect_rratio 0.25)
			(net 11 "/Power/OUT_1V2")
			(pintype "passive")
		)
	)
	(footprint "antmicro-footprints:R_0603_1608Metric"
		(layer "F.Cu")
		(at 130.937 80.264 -90)
		(descr "Resistor SMD 0603")
		(tags "resistor SMD 0603")
		(property "Reference" "R62"
			(at -1.882 -1.596 90)
			(layer "F.SilkS")
			(effects
				(font
					(size 0.7 0.7)
					(thickness 0.15)
				)
				(justify right bottom)
			)
		)
		(property "Value" "R_0R_22.4A_0603"
			(at 0 1.6 90)
			(layer "F.Fab")
			(effects
				(font
					(size 0.7 0.7)
					(thickness 0.15)
				)
				(justify right bottom)
			)
		)
		(property "Datasheet" "https://fscdn.rohm.com/en/products/databook/datasheet/passive/resistor/chip_resistor/pmr-jpw-e.pdf"
			(at 0 0 270)
			(layer "F.Fab")
			(hide yes)
			(effects
				(font
					(size 1.27 1.27)
					(thickness 0.15)
				)
			)
		)
		(property "Description" "SMD Chip Resistor"
			(at 0 0 270)
			(layer "F.Fab")
			(hide yes)
			(effects
				(font
					(size 1.27 1.27)
					(thickness 0.15)
				)
			)
		)
		(property "Author" "Antmicro"
			(at 50.673 211.201 0)
			(layer "F.Fab")
			(hide yes)
			(effects
				(font
					(size 1 1)
					(thickness 0.15)
				)
			)
		)
		(property "License" "Apache-2.0"
			(at 50.673 211.201 0)
			(layer "F.Fab")
			(hide yes)
			(effects
				(font
					(size 1 1)
					(thickness 0.15)
				)
			)
		)
		(property "MPN" "PMR03EZPJ000"
			(at 50.673 211.201 0)
			(layer "F.Fab")
			(hide yes)
			(effects
				(font
					(size 1 1)
					(thickness 0.15)
				)
			)
		)
		(property "Manufacturer" "ROHM Semiconductor"
			(at 50.673 211.201 0)
			(layer "F.Fab")
			(hide yes)
			(effects
				(font
					(size 1 1)
					(thickness 0.15)
				)
			)
		)
		(property "Max. Curr." "22.4A"
			(at 50.673 211.201 0)
			(layer "F.Fab")
			(hide yes)
			(effects
				(font
					(size 1 1)
					(thickness 0.15)
				)
			)
		)
		(property "Tolerance" "template_tolerance"
			(at 50.673 211.201 0)
			(layer "F.Fab")
			(hide yes)
			(effects
				(font
					(size 1 1)
					(thickness 0.15)
				)
			)
		)
		(property "Val" "0R"
			(at 50.673 211.201 0)
			(layer "F.Fab")
			(hide yes)
			(effects
				(font
					(size 1 1)
					(thickness 0.15)
				)
			)
		)
		(sheetname "/Power/")
		(sheetfile "power.kicad_sch")
		(attr smd)
		(fp_line
			(start -0.15 0.4)
			(end 0.15 0.4)
			(stroke
				(width 0.15)
				(type solid)
			)
			(layer "F.SilkS")
		)
		(fp_line
			(start -0.15 -0.4)
			(end 0.15 -0.4)
			(stroke
				(width 0.15)
				(type solid)
			)
			(layer "F.SilkS")
		)
		(fp_rect
			(start -1.25 -0.65)
			(end 1.25 0.65)
			(stroke
				(width 0.05)
				(type solid)
			)
			(fill no)
			(layer "F.CrtYd")
		)
		(fp_rect
			(start -0.8 -0.4)
			(end 0.8 0.4)
			(stroke
				(width 0.15)
				(type solid)
			)
			(fill no)
			(layer "F.Fab")
		)
		(pad "1" smd roundrect
			(at -0.7 0 270)
			(size 0.8 1)
			(layers "F.Cu" "F.Mask" "F.Paste")
			(roundrect_rratio 0.2)
			(net 123 "/Power/OUT_12V")
			(pintype "passive")
		)
		(pad "2" smd roundrect
			(at 0.7 0 270)
			(size 0.8 1)
			(layers "F.Cu" "F.Mask" "F.Paste")
			(roundrect_rratio 0.2)
			(net 4 "+12V")
			(pintype "passive")
		)
	)
	(footprint "antmicro-footprints:LED_0603_1608Metric_G"
		(layer "F.Cu")
		(at 152.4 96.11 -90)
		(descr "LED SMD 0603 Green")
		(tags "LED SMD 0603 Green")
		(property "Reference" "D2"
			(at -1.782222 34.65 0)
			(layer "F.SilkS")
			(effects
				(font
					(size 0.7 0.7)
					(thickness 0.15)
				)
				(justify right bottom)
			)
		)
		(property "Value" "LED_G_0603_LTST-C190GKT"
			(at -0.001 1.599 90)
			(layer "F.Fab")
			(effects
				(font
					(size 0.7 0.7)
					(thickness 0.15)
				)
				(justify right bottom)
			)
		)
		(property "Datasheet" "https://media.digikey.com/pdf/Data%20Sheets/Lite-On%20PDFs/LTST-C190GKT.pdf"
			(at 0 0 270)
			(layer "F.Fab")
			(hide yes)
			(effects
				(font
					(size 1.27 1.27)
					(thickness 0.15)
				)
			)
		)
		(property "Description" "LED, Green, SMD, 0603, 20 mA, 2.1 V, 569 nm"
			(at 0 0 270)
			(layer "F.Fab")
			(hide yes)
			(effects
				(font
					(size 1.27 1.27)
					(thickness 0.15)
				)
			)
		)
		(property "Author" "Antmicro"
			(at 56.29 248.51 0)
			(layer "F.Fab")
			(hide yes)
			(effects
				(font
					(size 1 1)
					(thickness 0.15)
				)
			)
		)
		(property "Color" "Green"
			(at 56.29 248.51 0)
			(layer "F.Fab")
			(hide yes)
			(effects
				(font
					(size 1 1)
					(thickness 0.15)
				)
			)
		)
		(property "License" "Apache-2.0"
			(at 56.29 248.51 0)
			(layer "F.Fab")
			(hide yes)
			(effects
				(font
					(size 1 1)
					(thickness 0.15)
				)
			)
		)
		(property "MPN" "LTST-C190GKT"
			(at 56.29 248.51 0)
			(layer "F.Fab")
			(hide yes)
			(effects
				(font
					(size 1 1)
					(thickness 0.15)
				)
			)
		)
		(property "Manufacturer" "Lite-On"
			(at 56.29 248.51 0)
			(layer "F.Fab")
			(hide yes)
			(effects
				(font
					(size 1 1)
					(thickness 0.15)
				)
			)
		)
		(property "VSD_class" "LED"
			(at 56.29 248.51 0)
			(layer "F.Fab")
			(hide yes)
			(effects
				(font
					(size 1 1)
					(thickness 0.15)
				)
			)
		)
		(sheetname "/Connectors/")
		(sheetfile "connectors.kicad_sch")
		(attr smd)
		(fp_line
			(start 0.22 0.35)
			(end -0.22 0.35)
			(stroke
				(width 0.15)
				(type solid)
			)
			(layer "F.SilkS")
		)
		(fp_line
			(start -0.094672 0.201008)
			(end -0.094672 -0.198992)
			(stroke
				(width 0.1)
				(type solid)
			)
			(layer "F.SilkS")
		)
		(fp_line
			(start 0.105328 0.201008)
			(end -0.094672 0.001008)
			(stroke
				(width 0.1)
				(type solid)
			)
			(layer "F.SilkS")
		)
		(fp_line
			(start 0.105328 0.201008)
			(end 0.105328 -0.198992)
			(stroke
				(width 0.1)
				(type solid)
			)
			(layer "F.SilkS")
		)
		(fp_line
			(start -0.094672 0.001008)
			(end -0.24 0.001008)
			(stroke
				(width 0.1)
				(type solid)
			)
			(layer "F.SilkS")
		)
		(fp_line
			(start -0.094672 0.001008)
			(end 0.105328 -0.198992)
			(stroke
				(width 0.1)
				(type solid)
			)
			(layer "F.SilkS")
		)
		(fp_line
			(start 0.105328 0.001008)
			(end 0.24 0.001)
			(stroke
				(width 0.1)
				(type solid)
			)
			(layer "F.SilkS")
		)
		(fp_line
			(start -1.18 -0.319)
			(end -1.18 0.321)
			(stroke
				(width 0.15)
				(type solid)
			)
			(layer "F.SilkS")
		)
		(fp_line
			(start 0.22 -0.35)
			(end -0.22 -0.35)
			(stroke
				(width 0.15)
				(type solid)
			)
			(layer "F.SilkS")
		)
		(fp_rect
			(start 1.25 0.65)
			(end -1.25 -0.65)
			(stroke
				(width 0.05)
				(type solid)
			)
			(fill no)
			(layer "F.CrtYd")
		)
		(fp_line
			(start -0.199 0.2)
			(end -0.199 0.1)
			(stroke
				(width 0.15)
				(type solid)
			)
			(layer "F.Fab")
		)
		(fp_line
			(start 0.201 0.2)
			(end 0.201 0)
			(stroke
				(width 0.15)
				(type solid)
			)
			(layer "F.Fab")
		)
		(fp_line
			(start -0.199 0)
			(end -0.597 0)
			(stroke
				(width 0.15)
				(type solid)
			)
			(layer "F.Fab")
		)
		(fp_line
			(start -0.101 0)
			(end 0.201 0.2)
			(stroke
				(width 0.15)
				(type solid)
			)
			(layer "F.Fab")
		)
		(fp_line
			(start 0.201 0)
			(end 0.201 -0.202)
			(stroke
				(width 0.15)
				(type solid)
			)
			(layer "F.Fab")
		)
		(fp_line
			(start 0.599 0)
			(end 0.201 0)
			(stroke
				(width 0.15)
				(type solid)
			)
			(layer "F.Fab")
		)
		(fp_line
			(start -0.199 -0.202)
			(end -0.199 0.1)
			(stroke
				(width 0.15)
				(type solid)
			)
			(layer "F.Fab")
		)
		(fp_line
			(start 0.201 -0.202)
			(end -0.101 0)
			(stroke
				(width 0.15)
				(type solid)
			)
			(layer "F.Fab")
		)
		(fp_rect
			(start 0.848 0.4)
			(end -0.85 -0.402)
			(stroke
				(width 0.15)
				(type solid)
			)
			(fill no)
			(layer "F.Fab")
		)
		(pad "1" smd roundrect
			(at -0.7 0 90)
			(size 0.8 1)
			(layers "F.Cu" "F.Mask" "F.Paste")
			(roundrect_rratio 0.2)
			(net 64 "Net-(D2-C)")
			(pinfunction "C")
			(pintype "passive")
		)
		(pad "2" smd roundrect
			(at 0.7 0 90)
			(size 0.8 1)
			(layers "F.Cu" "F.Mask" "F.Paste")
			(roundrect_rratio 0.2)
			(net 2 "/Connectors/DC_UNFUSED")
			(pinfunction "A")
			(pintype "passive")
		)
	)
	(footprint "antmicro-footprints:R_0402_1005Metric"
		(layer "F.Cu")
		(at 131.064 76.962)
		(descr "Resistor SMD 0402")
		(tags "resistor SMD 0402")
		(property "Reference" "R30"
			(at 0.938 0.277 0)
			(layer "F.SilkS")
			(effects
				(font
					(size 0.7 0.7)
					(thickness 0.15)
				)
				(justify left bottom)
			)
		)
		(property "Value" "R_120k_0402"
			(at -1.011843 1.772047 0)
			(layer "F.Fab")
			(effects
				(font
					(size 0.7 0.7)
					(thickness 0.15)
				)
				(justify left bottom)
			)
		)
		(property "Datasheet" "https://www.bourns.com/docs/product-datasheets/cr.pdf"
			(at 0 0 0)
			(layer "F.Fab")
			(hide yes)
			(effects
				(font
					(size 1.27 1.27)
					(thickness 0.15)
				)
			)
		)
		(property "Description" "SMD Chip Resistor, 120 kohm, ± 1%, 100 mW, 0402 [1005 Metric], Thick Film, Precision"
			(at 0 0 0)
			(layer "F.Fab")
			(hide yes)
			(effects
				(font
					(size 1.27 1.27)
					(thickness 0.15)
				)
			)
		)
		(property "Author" "Antmicro"
			(at 0 0 0)
			(layer "F.Fab")
			(hide yes)
			(effects
				(font
					(size 1 1)
					(thickness 0.15)
				)
			)
		)
		(property "License" "Apache-2.0"
			(at 0 0 0)
			(layer "F.Fab")
			(hide yes)
			(effects
				(font
					(size 1 1)
					(thickness 0.15)
				)
			)
		)
		(property "MPN" "CR0402-FX-1203GLF"
			(at 0 0 0)
			(layer "F.Fab")
			(hide yes)
			(effects
				(font
					(size 1 1)
					(thickness 0.15)
				)
			)
		)
		(property "Manufacturer" "Bourns"
			(at 0 0 0)
			(layer "F.Fab")
			(hide yes)
			(effects
				(font
					(size 1 1)
					(thickness 0.15)
				)
			)
		)
		(property "Tolerance" "1%"
			(at 0 0 0)
			(layer "F.Fab")
			(hide yes)
			(effects
				(font
					(size 1 1)
					(thickness 0.15)
				)
			)
		)
		(property "Val" "120k"
			(at 0 0 0)
			(layer "F.Fab")
			(hide yes)
			(effects
				(font
					(size 1 1)
					(thickness 0.15)
				)
			)
		)
		(sheetname "/Power/")
		(sheetfile "power.kicad_sch")
		(attr smd)
		(fp_rect
			(start -0.925 -0.47)
			(end 0.925 0.47)
			(stroke
				(width 0.05)
				(type default)
			)
			(fill no)
			(layer "F.CrtYd")
		)
		(fp_rect
			(start -0.5 -0.25)
			(end 0.5 0.25)
			(stroke
				(width 0.15)
				(type solid)
			)
			(fill no)
			(layer "F.Fab")
		)
		(pad "1" smd roundrect
			(at -0.48 0)
			(size 0.59 0.64)
			(layers "F.Cu" "F.Mask" "F.Paste")
			(roundrect_rratio 0.25)
			(net 122 "/Power/FB_12V")
			(pintype "passive")
		)
		(pad "2" smd roundrect
			(at 0.48 0)
			(size 0.59 0.64)
			(layers "F.Cu" "F.Mask" "F.Paste")
			(roundrect_rratio 0.25)
			(net 123 "/Power/OUT_12V")
			(pintype "passive")
		)
	)
	(footprint "antmicro-footprints:R_0402_1005Metric"
		(layer "F.Cu")
		(at 153.1112 79.5528 -135)
		(descr "Resistor SMD 0402")
		(tags "resistor SMD 0402")
		(property "Reference" "R49"
			(at -1.185394 -2.298946 45)
			(layer "F.SilkS")
			(effects
				(font
					(size 0.7 0.7)
					(thickness 0.15)
				)
				(justify right bottom)
			)
		)
		(property "Value" "R_10k_0402"
			(at -1.011843 1.772046 45)
			(layer "F.Fab")
			(effects
				(font
					(size 0.7 0.7)
					(thickness 0.15)
				)
				(justify right bottom)
			)
		)
		(property "Datasheet" "https://www.bourns.com/docs/product-datasheets/cr.pdf"
			(at 0 0 225)
			(layer "F.Fab")
			(hide yes)
			(effects
				(font
					(size 1.27 1.27)
					(thickness 0.15)
				)
			)
		)
		(property "Description" "SMD Chip Resistor, 10 kohm, ± 1%, 62.5 mW, 0402 [1005 Metric], Thick Film, General Purpose"
			(at 0 0 225)
			(layer "F.Fab")
			(hide yes)
			(effects
				(font
					(size 1.27 1.27)
					(thickness 0.15)
				)
			)
		)
		(property "Author" "Antmicro"
			(at 205.124843 244.071092 0)
			(layer "F.Fab")
			(hide yes)
			(effects
				(font
					(size 1 1)
					(thickness 0.15)
				)
			)
		)
		(property "License" "Apache-2.0"
			(at 205.124843 244.071092 0)
			(layer "F.Fab")
			(hide yes)
			(effects
				(font
					(size 1 1)
					(thickness 0.15)
				)
			)
		)
		(property "MPN" "CR0402-FX-1002GLF"
			(at 205.124843 244.071092 0)
			(layer "F.Fab")
			(hide yes)
			(effects
				(font
					(size 1 1)
					(thickness 0.15)
				)
			)
		)
		(property "Manufacturer" "Bourns"
			(at 205.124843 244.071092 0)
			(layer "F.Fab")
			(hide yes)
			(effects
				(font
					(size 1 1)
					(thickness 0.15)
				)
			)
		)
		(property "Tolerance" "1%"
			(at 205.124843 244.071092 0)
			(layer "F.Fab")
			(hide yes)
			(effects
				(font
					(size 1 1)
					(thickness 0.15)
				)
			)
		)
		(property "Val" "10k"
			(at 205.124843 244.071092 0)
			(layer "F.Fab")
			(hide yes)
			(effects
				(font
					(size 1 1)
					(thickness 0.15)
				)
			)
		)
		(sheetname "/Deserializer/")
		(sheetfile "deserializer.kicad_sch")
		(attr smd)
		(fp_poly
			(pts
				(xy -0.925 -0.47) (xy 0.925 -0.47) (xy 0.925 0.47) (xy -0.925 0.47)
			)
			(stroke
				(width 0.05)
				(type default)
			)
			(fill no)
			(layer "F.CrtYd")
		)
		(fp_poly
			(pts
				(xy -0.5 -0.25) (xy 0.5 -0.25) (xy 0.5 0.25) (xy -0.5 0.25)
			)
			(stroke
				(width 0.15)
				(type solid)
			)
			(fill no)
			(layer "F.Fab")
		)
		(pad "1" smd roundrect
			(at -0.48 0 225)
			(size 0.59 0.64)
			(layers "F.Cu" "F.Mask" "F.Paste")
			(roundrect_rratio 0.25)
			(net 1 "GND")
			(pintype "passive")
		)
		(pad "2" smd roundrect
			(at 0.48 0 225)
			(size 0.59 0.64)
			(layers "F.Cu" "F.Mask" "F.Paste")
			(roundrect_rratio 0.25)
			(net 76 "/Deserializer/CFG0")
			(pintype "passive")
		)
	)
	(footprint "antmicro-footprints:C_0402_1005Metric"
		(layer "F.Cu")
		(at 187.706 55.118)
		(descr "Capacitor SMD 0402")
		(tags "capacitor SMD 0402")
		(property "Reference" "C59"
			(at 0.698445 0.413325 0)
			(layer "F.SilkS")
			(effects
				(font
					(size 0.7 0.7)
					(thickness 0.15)
				)
				(justify left bottom)
			)
		)
		(property "Value" "C_1u_0402"
			(at -1.022927 2.155213 0)
			(layer "F.Fab")
			(effects
				(font
					(size 0.7 0.7)
					(thickness 0.15)
				)
				(justify left bottom)
			)
		)
		(property "Datasheet" "https://product.tdk.com/en/search/capacitor/ceramic/mlcc/info?part_no=C1005X6S1A105K050BC"
			(at 0 0 0)
			(layer "F.Fab")
			(hide yes)
			(effects
				(font
					(size 1.27 1.27)
					(thickness 0.15)
				)
			)
		)
		(property "Description" "SMD Multilayer Ceramic Capacitor, 1 µF, 10 V, 0402 [1005 Metric], ± 10%, X6S, C"
			(at 0 0 0)
			(layer "F.Fab")
			(hide yes)
			(effects
				(font
					(size 1.27 1.27)
					(thickness 0.15)
				)
			)
		)
		(property "Author" "Antmicro"
			(at 0 0 0)
			(layer "F.Fab")
			(hide yes)
			(effects
				(font
					(size 1 1)
					(thickness 0.15)
				)
			)
		)
		(property "Dielectric" ""
			(at 0 0 0)
			(layer "F.Fab")
			(hide yes)
			(effects
				(font
					(size 1 1)
					(thickness 0.15)
				)
			)
		)
		(property "License" "Apache-2.0"
			(at 0 0 0)
			(layer "F.Fab")
			(hide yes)
			(effects
				(font
					(size 1 1)
					(thickness 0.15)
				)
			)
		)
		(property "MPN" "C1005X6S1A105K050BC"
			(at 0 0 0)
			(layer "F.Fab")
			(hide yes)
			(effects
				(font
					(size 1 1)
					(thickness 0.15)
				)
			)
		)
		(property "Manufacturer" "TDK"
			(at 0 0 0)
			(layer "F.Fab")
			(hide yes)
			(effects
				(font
					(size 1 1)
					(thickness 0.15)
				)
			)
		)
		(property "Val" "1u"
			(at 0 0 0)
			(layer "F.Fab")
			(hide yes)
			(effects
				(font
					(size 1 1)
					(thickness 0.15)
				)
			)
		)
		(property "Voltage" ""
			(at 0 0 0)
			(layer "F.Fab")
			(hide yes)
			(effects
				(font
					(size 1 1)
					(thickness 0.15)
				)
			)
		)
		(sheetname "/Power/")
		(sheetfile "power.kicad_sch")
		(attr smd)
		(fp_rect
			(start -0.925 -0.47)
			(end 0.925 0.47)
			(stroke
				(width 0.05)
				(type default)
			)
			(fill no)
			(layer "F.CrtYd")
		)
		(fp_line
			(start -0.494 -0.25)
			(end 0.504 -0.25)
			(stroke
				(width 0.15)
				(type solid)
			)
			(layer "F.Fab")
		)
		(fp_line
			(start -0.494 0.248)
			(end -0.494 -0.25)
			(stroke
				(width 0.15)
				(type solid)
			)
			(layer "F.Fab")
		)
		(fp_line
			(start 0.504 -0.25)
			(end 0.504 0.248)
			(stroke
				(width 0.15)
				(type solid)
			)
			(layer "F.Fab")
		)
		(fp_line
			(start 0.504 0.248)
			(end -0.494 0.248)
			(stroke
				(width 0.15)
				(type solid)
			)
			(layer "F.Fab")
		)
		(pad "1" smd roundrect
			(at -0.48 0)
			(size 0.59 0.64)
			(layers "F.Cu" "F.Mask" "F.Paste")
			(roundrect_rratio 0.25)
			(net 1 "GND")
			(pintype "passive")
		)
		(pad "2" smd roundrect
			(at 0.48 0)
			(size 0.59 0.64)
			(layers "F.Cu" "F.Mask" "F.Paste")
			(roundrect_rratio 0.25)
			(net 113 "/Connectors/FFC_5V")
			(pintype "passive")
		)
	)
	(footprint "antmicro-footprints:C_0402_1005Metric"
		(layer "F.Cu")
		(at 130.963 93.078 90)
		(descr "Capacitor SMD 0402")
		(tags "capacitor SMD 0402")
		(property "Reference" "C24"
			(at -0.394 -2.185 90)
			(layer "F.SilkS")
			(effects
				(font
					(size 0.7 0.7)
					(thickness 0.15)
				)
				(justify left bottom)
			)
		)
		(property "Value" "C_22u_0402"
			(at -1.022927 2.155213 90)
			(layer "F.Fab")
			(effects
				(font
					(size 0.7 0.7)
					(thickness 0.15)
				)
				(justify left bottom)
			)
		)
		(property "Datasheet" "https://www.murata.com/products/productdetail?partno=GRM158R60J226ME01%23"
			(at 0 0 90)
			(layer "F.Fab")
			(hide yes)
			(effects
				(font
					(size 1.27 1.27)
					(thickness 0.15)
				)
			)
		)
		(property "Description" "SMD Multilayer Ceramic Capacitor, 22 uF, 4 V, 0402 [1005 Metric], X6S"
			(at 0 0 90)
			(layer "F.Fab")
			(hide yes)
			(effects
				(font
					(size 1.27 1.27)
					(thickness 0.15)
				)
			)
		)
		(property "Author" "Antmicro"
			(at 224.041 -37.885 0)
			(layer "F.Fab")
			(hide yes)
			(effects
				(font
					(size 1 1)
					(thickness 0.15)
				)
			)
		)
		(property "Dielectric" ""
			(at 224.041 -37.885 0)
			(layer "F.Fab")
			(hide yes)
			(effects
				(font
					(size 1 1)
					(thickness 0.15)
				)
			)
		)
		(property "License" "Apache-2.0"
			(at 224.041 -37.885 0)
			(layer "F.Fab")
			(hide yes)
			(effects
				(font
					(size 1 1)
					(thickness 0.15)
				)
			)
		)
		(property "MPN" "GRM158R60J226ME01D"
			(at 224.041 -37.885 0)
			(layer "F.Fab")
			(hide yes)
			(effects
				(font
					(size 1 1)
					(thickness 0.15)
				)
			)
		)
		(property "Manufacturer" "Murata"
			(at 224.041 -37.885 0)
			(layer "F.Fab")
			(hide yes)
			(effects
				(font
					(size 1 1)
					(thickness 0.15)
				)
			)
		)
		(property "Val" "22u"
			(at 224.041 -37.885 0)
			(layer "F.Fab")
			(hide yes)
			(effects
				(font
					(size 1 1)
					(thickness 0.15)
				)
			)
		)
		(property "Voltage" ""
			(at 224.041 -37.885 0)
			(layer "F.Fab")
			(hide yes)
			(effects
				(font
					(size 1 1)
					(thickness 0.15)
				)
			)
		)
		(sheetname "/Power/")
		(sheetfile "power.kicad_sch")
		(attr smd)
		(fp_rect
			(start -0.925 -0.47)
			(end 0.925 0.47)
			(stroke
				(width 0.05)
				(type default)
			)
			(fill no)
			(layer "F.CrtYd")
		)
		(fp_line
			(start 0.504 -0.25)
			(end 0.504 0.248)
			(stroke
				(width 0.15)
				(type solid)
			)
			(layer "F.Fab")
		)
		(fp_line
			(start -0.494 -0.25)
			(end 0.504 -0.25)
			(stroke
				(width 0.15)
				(type solid)
			)
			(layer "F.Fab")
		)
		(fp_line
			(start 0.504 0.248)
			(end -0.494 0.248)
			(stroke
				(width 0.15)
				(type solid)
			)
			(layer "F.Fab")
		)
		(fp_line
			(start -0.494 0.248)
			(end -0.494 -0.25)
			(stroke
				(width 0.15)
				(type solid)
			)
			(layer "F.Fab")
		)
		(pad "1" smd roundrect
			(at -0.48 0 90)
			(size 0.59 0.64)
			(layers "F.Cu" "F.Mask" "F.Paste")
			(roundrect_rratio 0.25)
			(net 1 "GND")
			(pintype "passive")
		)
		(pad "2" smd roundrect
			(at 0.48 0 90)
			(size 0.59 0.64)
			(layers "F.Cu" "F.Mask" "F.Paste")
			(roundrect_rratio 0.25)
			(net 10 "/Power/OUT_1V8")
			(pintype "passive")
		)
	)
	(footprint "antmicro-footprints:R_0402_1005Metric"
		(layer "F.Cu")
		(at 139.192 94.488 180)
		(descr "Resistor SMD 0402")
		(tags "resistor SMD 0402")
		(property "Reference" "R64"
			(at -1.016 0.508 0)
			(layer "F.SilkS")
			(effects
				(font
					(size 0.7 0.7)
					(thickness 0.15)
				)
				(justify left bottom)
			)
		)
		(property "Value" "R_10k_0402"
			(at -1.011843 1.772047 0)
			(layer "F.Fab")
			(effects
				(font
					(size 0.7 0.7)
					(thickness 0.15)
				)
				(justify right bottom)
			)
		)
		(property "Datasheet" "https://www.bourns.com/docs/product-datasheets/cr.pdf"
			(at 0 0 180)
			(layer "F.Fab")
			(hide yes)
			(effects
				(font
					(size 1.27 1.27)
					(thickness 0.15)
				)
			)
		)
		(property "Description" "SMD Chip Resistor, 10 kohm, ± 1%, 62.5 mW, 0402 [1005 Metric], Thick Film, General Purpose"
			(at 0 0 180)
			(layer "F.Fab")
			(hide yes)
			(effects
				(font
					(size 1.27 1.27)
					(thickness 0.15)
				)
			)
		)
		(property "Author" "Antmicro"
			(at 278.384 188.976 0)
			(layer "F.Fab")
			(hide yes)
			(effects
				(font
					(size 1 1)
					(thickness 0.15)
				)
			)
		)
		(property "License" "Apache-2.0"
			(at 278.384 188.976 0)
			(layer "F.Fab")
			(hide yes)
			(effects
				(font
					(size 1 1)
					(thickness 0.15)
				)
			)
		)
		(property "MPN" "CR0402-FX-1002GLF"
			(at 278.384 188.976 0)
			(layer "F.Fab")
			(hide yes)
			(effects
				(font
					(size 1 1)
					(thickness 0.15)
				)
			)
		)
		(property "Manufacturer" "Bourns"
			(at 278.384 188.976 0)
			(layer "F.Fab")
			(hide yes)
			(effects
				(font
					(size 1 1)
					(thickness 0.15)
				)
			)
		)
		(property "Tolerance" "1%"
			(at 278.384 188.976 0)
			(layer "F.Fab")
			(hide yes)
			(effects
				(font
					(size 1 1)
					(thickness 0.15)
				)
			)
		)
		(property "Val" "10k"
			(at 278.384 188.976 0)
			(layer "F.Fab")
			(hide yes)
			(effects
				(font
					(size 1 1)
					(thickness 0.15)
				)
			)
		)
		(sheetname "/Power/")
		(sheetfile "power.kicad_sch")
		(attr smd)
		(fp_rect
			(start -0.925 -0.47)
			(end 0.925 0.47)
			(stroke
				(width 0.05)
				(type default)
			)
			(fill no)
			(layer "F.CrtYd")
		)
		(fp_rect
			(start -0.5 -0.25)
			(end 0.5 0.25)
			(stroke
				(width 0.15)
				(type solid)
			)
			(fill no)
			(layer "F.Fab")
		)
		(pad "1" smd roundrect
			(at -0.48 0 180)
			(size 0.59 0.64)
			(layers "F.Cu" "F.Mask" "F.Paste")
			(roundrect_rratio 0.25)
			(net 1 "GND")
			(pintype "passive")
		)
		(pad "2" smd roundrect
			(at 0.48 0 180)
			(size 0.59 0.64)
			(layers "F.Cu" "F.Mask" "F.Paste")
			(roundrect_rratio 0.25)
			(net 69 "/Power/EN_1V8")
			(pintype "passive")
		)
	)
	(footprint "antmicro-footprints:TP_SMD_0.75mm"
		(layer "F.Cu")
		(at 136.222 84.914)
		(property "Reference" "TP3"
			(at -3.3062 0.3024 0)
			(layer "F.SilkS")
			(hide yes)
			(effects
				(font
					(size 0.7 0.7)
					(thickness 0.15)
				)
				(justify left bottom)
			)
		)
		(property "Value" "TP_0.75mm_SMD"
			(at 0 1.2 0)
			(layer "F.Fab")
			(effects
				(font
					(size 0.7 0.7)
					(thickness 0.15)
				)
				(justify left bottom)
			)
		)
		(property "Description" "SMT test point"
			(at 0 0 0)
			(layer "F.Fab")
			(hide yes)
			(effects
				(font
					(size 1.27 1.27)
					(thickness 0.15)
				)
			)
		)
		(property "Author" "Antmicro"
			(at 0 0 0)
			(layer "F.Fab")
			(hide yes)
			(effects
				(font
					(size 1 1)
					(thickness 0.15)
				)
			)
		)
		(property "License" "Apache-2.0"
			(at 0 0 0)
			(layer "F.Fab")
			(hide yes)
			(effects
				(font
					(size 1 1)
					(thickness 0.15)
				)
			)
		)
		(property "MPN" ""
			(at 0 0 0)
			(layer "F.Fab")
			(hide yes)
			(effects
				(font
					(size 1 1)
					(thickness 0.15)
				)
			)
		)
		(property "Manufacturer" ""
			(at 0 0 0)
			(layer "F.Fab")
			(hide yes)
			(effects
				(font
					(size 1 1)
					(thickness 0.15)
				)
			)
		)
		(sheetname "/Connectors/")
		(sheetfile "connectors.kicad_sch")
		(fp_circle
			(center 0 0)
			(end 0.475 0)
			(stroke
				(width 0.05)
				(type default)
			)
			(fill no)
			(layer "F.CrtYd")
		)
		(pad "1" smd circle
			(at 0 0)
			(size 0.75 0.75)
			(layers "F.Cu" "F.Mask")
			(net 86 "/Connectors/MFP7")
			(pinfunction "1")
			(pintype "passive")
		)
	)
	(footprint "antmicro-footprints:C_0402_1005Metric"
		(layer "F.Cu")
		(at 122.301 66.548 90)
		(descr "Capacitor SMD 0402")
		(tags "capacitor SMD 0402")
		(property "Reference" "C6"
			(at -1.397 -0.635 90)
			(layer "F.SilkS")
			(effects
				(font
					(size 0.7 0.7)
					(thickness 0.15)
				)
				(justify left bottom)
			)
		)
		(property "Value" "C_100n_0402"
			(at -1.022927 2.155213 90)
			(layer "F.Fab")
			(effects
				(font
					(size 0.7 0.7)
					(thickness 0.15)
				)
				(justify left bottom)
			)
		)
		(property "Datasheet" "https://www.murata.com/products/productdetail?partno=GRM155R61H104KE14%23"
			(at 0 0 90)
			(layer "F.Fab")
			(hide yes)
			(effects
				(font
					(size 1.27 1.27)
					(thickness 0.15)
				)
			)
		)
		(property "Description" "SMD Multilayer Ceramic Capacitor, 0.1 µF, 50 V, 0402 [1005 Metric], ± 10%, X5R, GRM Series"
			(at 0 0 90)
			(layer "F.Fab")
			(hide yes)
			(effects
				(font
					(size 1.27 1.27)
					(thickness 0.15)
				)
			)
		)
		(property "Author" "Antmicro"
			(at 188.849 -55.753 0)
			(layer "F.Fab")
			(hide yes)
			(effects
				(font
					(size 1 1)
					(thickness 0.15)
				)
			)
		)
		(property "Dielectric" "X5R"
			(at 188.849 -55.753 0)
			(layer "F.Fab")
			(hide yes)
			(effects
				(font
					(size 1 1)
					(thickness 0.15)
				)
			)
		)
		(property "License" "Apache-2.0"
			(at 188.849 -55.753 0)
			(layer "F.Fab")
			(hide yes)
			(effects
				(font
					(size 1 1)
					(thickness 0.15)
				)
			)
		)
		(property "MPN" "GRM155R61H104KE14D"
			(at 188.849 -55.753 0)
			(layer "F.Fab")
			(hide yes)
			(effects
				(font
					(size 1 1)
					(thickness 0.15)
				)
			)
		)
		(property "Manufacturer" "Murata"
			(at 188.849 -55.753 0)
			(layer "F.Fab")
			(hide yes)
			(effects
				(font
					(size 1 1)
					(thickness 0.15)
				)
			)
		)
		(property "Val" "100n"
			(at 188.849 -55.753 0)
			(layer "F.Fab")
			(hide yes)
			(effects
				(font
					(size 1 1)
					(thickness 0.15)
				)
			)
		)
		(property "Voltage" "50V"
			(at 188.849 -55.753 0)
			(layer "F.Fab")
			(hide yes)
			(effects
				(font
					(size 1 1)
					(thickness 0.15)
				)
			)
		)
		(sheetname "/Power/")
		(sheetfile "power.kicad_sch")
		(attr smd)
		(fp_rect
			(start -0.925 -0.47)
			(end 0.925 0.47)
			(stroke
				(width 0.05)
				(type default)
			)
			(fill no)
			(layer "F.CrtYd")
		)
		(fp_line
			(start 0.504 -0.25)
			(end 0.504 0.248)
			(stroke
				(width 0.15)
				(type solid)
			)
			(layer "F.Fab")
		)
		(fp_line
			(start -0.494 -0.25)
			(end 0.504 -0.25)
			(stroke
				(width 0.15)
				(type solid)
			)
			(layer "F.Fab")
		)
		(fp_line
			(start 0.504 0.248)
			(end -0.494 0.248)
			(stroke
				(width 0.15)
				(type solid)
			)
			(layer "F.Fab")
		)
		(fp_line
			(start -0.494 0.248)
			(end -0.494 -0.25)
			(stroke
				(width 0.15)
				(type solid)
			)
			(layer "F.Fab")
		)
		(pad "1" smd roundrect
			(at -0.48 0 90)
			(size 0.59 0.64)
			(layers "F.Cu" "F.Mask" "F.Paste")
			(roundrect_rratio 0.25)
			(net 1 "GND")
			(pintype "passive")
		)
		(pad "2" smd roundrect
			(at 0.48 0 90)
			(size 0.59 0.64)
			(layers "F.Cu" "F.Mask" "F.Paste")
			(roundrect_rratio 0.25)
			(net 4 "+12V")
			(pintype "passive")
		)
	)
	(footprint "antmicro-footprints:C_0402_1005Metric"
		(layer "F.Cu")
		(at 125.658 74.018 90)
		(descr "Capacitor SMD 0402")
		(tags "capacitor SMD 0402")
		(property "Reference" "C14"
			(at 0.739 1.215 90)
			(layer "F.SilkS")
			(effects
				(font
					(size 0.7 0.7)
					(thickness 0.15)
				)
				(justify left bottom)
			)
		)
		(property "Value" "C_2u2_0402"
			(at -1.022927 2.155213 90)
			(layer "F.Fab")
			(effects
				(font
					(size 0.7 0.7)
					(thickness 0.15)
				)
				(justify left bottom)
			)
		)
		(property "Datasheet" "https://product.tdk.com/en/search/capacitor/ceramic/mlcc/info?part_no=C1005X5R1A225K050BC"
			(at 0 0 90)
			(layer "F.Fab")
			(hide yes)
			(effects
				(font
					(size 1.27 1.27)
					(thickness 0.15)
				)
			)
		)
		(property "Description" "SMD Multilayer Ceramic Capacitor, 2.2 µF, 10 V, 0402 [1005 Metric], ± 10%, X5R, C"
			(at 0 0 90)
			(layer "F.Fab")
			(hide yes)
			(effects
				(font
					(size 1.27 1.27)
					(thickness 0.15)
				)
			)
		)
		(property "Author" "Antmicro"
			(at 199.676 -51.64 0)
			(layer "F.Fab")
			(hide yes)
			(effects
				(font
					(size 1 1)
					(thickness 0.15)
				)
			)
		)
		(property "Dielectric" ""
			(at 199.676 -51.64 0)
			(layer "F.Fab")
			(hide yes)
			(effects
				(font
					(size 1 1)
					(thickness 0.15)
				)
			)
		)
		(property "License" "Apache-2.0"
			(at 199.676 -51.64 0)
			(layer "F.Fab")
			(hide yes)
			(effects
				(font
					(size 1 1)
					(thickness 0.15)
				)
			)
		)
		(property "MPN" "C1005X5R1A225K050BC"
			(at 199.676 -51.64 0)
			(layer "F.Fab")
			(hide yes)
			(effects
				(font
					(size 1 1)
					(thickness 0.15)
				)
			)
		)
		(property "Manufacturer" "TDK"
			(at 199.676 -51.64 0)
			(layer "F.Fab")
			(hide yes)
			(effects
				(font
					(size 1 1)
					(thickness 0.15)
				)
			)
		)
		(property "Val" "2u2"
			(at 199.676 -51.64 0)
			(layer "F.Fab")
			(hide yes)
			(effects
				(font
					(size 1 1)
					(thickness 0.15)
				)
			)
		)
		(property "Voltage" ""
			(at 199.676 -51.64 0)
			(layer "F.Fab")
			(hide yes)
			(effects
				(font
					(size 1 1)
					(thickness 0.15)
				)
			)
		)
		(sheetname "/Power/")
		(sheetfile "power.kicad_sch")
		(attr smd)
		(fp_rect
			(start -0.925 -0.47)
			(end 0.925 0.47)
			(stroke
				(width 0.05)
				(type default)
			)
			(fill no)
			(layer "F.CrtYd")
		)
		(fp_line
			(start 0.504 -0.25)
			(end 0.504 0.248)
			(stroke
				(width 0.15)
				(type solid)
			)
			(layer "F.Fab")
		)
		(fp_line
			(start -0.494 -0.25)
			(end 0.504 -0.25)
			(stroke
				(width 0.15)
				(type solid)
			)
			(layer "F.Fab")
		)
		(fp_line
			(start 0.504 0.248)
			(end -0.494 0.248)
			(stroke
				(width 0.15)
				(type solid)
			)
			(layer "F.Fab")
		)
		(fp_line
			(start -0.494 0.248)
			(end -0.494 -0.25)
			(stroke
				(width 0.15)
				(type solid)
			)
			(layer "F.Fab")
		)
		(pad "1" smd roundrect
			(at -0.48 0 90)
			(size 0.59 0.64)
			(layers "F.Cu" "F.Mask" "F.Paste")
			(roundrect_rratio 0.25)
			(net 1 "GND")
			(pintype "passive")
		)
		(pad "2" smd roundrect
			(at 0.48 0 90)
			(size 0.59 0.64)
			(layers "F.Cu" "F.Mask" "F.Paste")
			(roundrect_rratio 0.25)
			(net 5 "+5V")
			(pintype "passive")
		)
	)
	(footprint "antmicro-footprints:TP_SMD_0.75mm"
		(layer "F.Cu")
		(at 150.876 97.89)
		(property "Reference" "TP11"
			(at 0 -0.6 0)
			(layer "F.SilkS")
			(hide yes)
			(effects
				(font
					(size 0.7 0.7)
					(thickness 0.15)
				)
				(justify left bottom)
			)
		)
		(property "Value" "TP_0.75mm_SMD"
			(at 0 1.2 0)
			(layer "F.Fab")
			(effects
				(font
					(size 0.7 0.7)
					(thickness 0.15)
				)
				(justify left bottom)
			)
		)
		(property "Description" "SMT test point"
			(at 0 0 0)
			(layer "F.Fab")
			(hide yes)
			(effects
				(font
					(size 1.27 1.27)
					(thickness 0.15)
				)
			)
		)
		(property "Author" "Antmicro"
			(at 0 0 0)
			(layer "F.Fab")
			(hide yes)
			(effects
				(font
					(size 1 1)
					(thickness 0.15)
				)
			)
		)
		(property "License" "Apache-2.0"
			(at 0 0 0)
			(layer "F.Fab")
			(hide yes)
			(effects
				(font
					(size 1 1)
					(thickness 0.15)
				)
			)
		)
		(property "MPN" ""
			(at 0 0 0)
			(layer "F.Fab")
			(hide yes)
			(effects
				(font
					(size 1 1)
					(thickness 0.15)
				)
			)
		)
		(property "Manufacturer" ""
			(at 0 0 0)
			(layer "F.Fab")
			(hide yes)
			(effects
				(font
					(size 1 1)
					(thickness 0.15)
				)
			)
		)
		(sheetname "/Power/")
		(sheetfile "power.kicad_sch")
		(fp_circle
			(center 0 0)
			(end 0.475 0)
			(stroke
				(width 0.05)
				(type default)
			)
			(fill no)
			(layer "F.CrtYd")
		)
		(pad "1" smd circle
			(at 0 0)
			(size 0.75 0.75)
			(layers "F.Cu" "F.Mask")
			(net 5 "+5V")
			(pinfunction "1")
			(pintype "passive")
		)
	)
	(footprint "antmicro-footprints:D_SOD-323F"
		(layer "F.Cu")
		(at 126.166 78.844 90)
		(property "Reference" "D3"
			(at -1.293 -1.198 90)
			(layer "F.SilkS")
			(effects
				(font
					(size 0.7 0.7)
					(thickness 0.15)
				)
				(justify left bottom)
			)
		)
		(property "Value" "PMEG3010CEJ,115"
			(at -1.7 1.899 90)
			(layer "F.Fab")
			(effects
				(font
					(size 0.7 0.7)
					(thickness 0.15)
				)
				(justify left bottom)
			)
		)
		(property "Datasheet" "https://assets.nexperia.com/documents/data-sheet/PMEG3010CEH_PMEG3010CEJ.pdf"
			(at 0 0 90)
			(layer "F.Fab")
			(hide yes)
			(effects
				(font
					(size 1.27 1.27)
					(thickness 0.15)
				)
			)
		)
		(property "Description" "Schottky Rectifier, 30 V, 1 A, Single, SOD-323F, 2 Pins, 520 mV"
			(at 0 0 90)
			(layer "F.Fab")
			(hide yes)
			(effects
				(font
					(size 1.27 1.27)
					(thickness 0.15)
				)
			)
		)
		(property "Author" "Antmicro"
			(at 205.01 -47.322 0)
			(layer "F.Fab")
			(hide yes)
			(effects
				(font
					(size 1 1)
					(thickness 0.15)
				)
			)
		)
		(property "License" "Apache-2.0"
			(at 205.01 -47.322 0)
			(layer "F.Fab")
			(hide yes)
			(effects
				(font
					(size 1 1)
					(thickness 0.15)
				)
			)
		)
		(property "MPN" "PMEG3010CEJ,115"
			(at 205.01 -47.322 0)
			(layer "F.Fab")
			(hide yes)
			(effects
				(font
					(size 1 1)
					(thickness 0.15)
				)
			)
		)
		(property "Manufacturer" "Nexperia"
			(at 205.01 -47.322 0)
			(layer "F.Fab")
			(hide yes)
			(effects
				(font
					(size 1 1)
					(thickness 0.15)
				)
			)
		)
		(property "Public" ""
			(at 205.01 -47.322 0)
			(layer "F.Fab")
			(hide yes)
			(effects
				(font
					(size 1 1)
					(thickness 0.15)
				)
			)
		)
		(sheetname "/Power/")
		(sheetfile "power.kicad_sch")
		(attr smd)
		(fp_line
			(start 0.973 -0.749)
			(end 0.973 -0.449)
			(stroke
				(width 0.15)
				(type solid)
			)
			(layer "F.SilkS")
		)
		(fp_line
			(start 0.623 -0.749)
			(end 0.973 -0.749)
			(stroke
				(width 0.15)
				(type solid)
			)
			(layer "F.SilkS")
		)
		(fp_line
			(start -0.625 -0.749)
			(end -0.975 -0.749)
			(stroke
				(width 0.15)
				(type solid)
			)
			(layer "F.SilkS")
		)
		(fp_line
			(start -0.975 -0.749)
			(end -0.975 -0.449)
			(stroke
				(width 0.15)
				(type solid)
			)
			(layer "F.SilkS")
		)
		(fp_line
			(start -0.5 -0.425)
			(end -0.5 0.425)
			(stroke
				(width 0.15)
				(type solid)
			)
			(layer "F.SilkS")
		)
		(fp_line
			(start 0.973 0.451)
			(end 0.973 0.749)
			(stroke
				(width 0.15)
				(type solid)
			)
			(layer "F.SilkS")
		)
		(fp_line
			(start 0.973 0.749)
			(end 0.623 0.749)
			(stroke
				(width 0.15)
				(type solid)
			)
			(layer "F.SilkS")
		)
		(fp_line
			(start -0.625 0.749)
			(end -0.975 0.749)
			(stroke
				(width 0.15)
				(type solid)
			)
			(layer "F.SilkS")
		)
		(fp_line
			(start -0.975 0.749)
			(end -0.975 0.451)
			(stroke
				(width 0.15)
				(type solid)
			)
			(layer "F.SilkS")
		)
		(fp_rect
			(start -1.55 -0.95)
			(end 1.55 0.95)
			(stroke
				(width 0.05)
				(type solid)
			)
			(fill no)
			(layer "F.CrtYd")
		)
		(fp_rect
			(start -1.25 -0.676)
			(end 1.245365 0.676)
			(stroke
				(width 0.1)
				(type solid)
			)
			(fill no)
			(layer "F.Fab")
		)
		(pad "1" smd roundrect
			(at -1.051 0.001 90)
			(size 0.8 0.6)
			(layers "F.Cu" "F.Mask" "F.Paste")
			(roundrect_rratio 0.15)
			(net 123 "/Power/OUT_12V")
			(pinfunction "C")
			(pintype "passive")
		)
		(pad "2" smd roundrect
			(at 1.05 0.001 90)
			(size 0.8 0.6)
			(layers "F.Cu" "F.Mask" "F.Paste")
			(roundrect_rratio 0.15)
			(net 124 "/Power/SW_12V")
			(pinfunction "A")
			(pintype "passive")
		)
	)
	(footprint "antmicro-footprints:L_Coilcraft-1210POC"
		(layer "F.Cu")
		(at 136.906 56.642 90)
		(property "Reference" "L6"
			(at -0.635 -1.778 90)
			(layer "F.SilkS")
			(effects
				(font
					(size 0.7 0.7)
					(thickness 0.15)
				)
				(justify left bottom)
			)
		)
		(property "Value" "L_6u8_1A_Coilcraft-1210POC"
			(at 0 2.4 90)
			(layer "F.Fab")
			(effects
				(font
					(size 0.7 0.7)
					(thickness 0.15)
				)
				(justify left bottom)
			)
		)
		(property "Datasheet" "https://www.coilcraft.com/getmedia/5e8de018-68c5-4442-84ce-d5212c44660c/1210poc.pdf"
			(at 0 0 90)
			(layer "F.Fab")
			(hide yes)
			(effects
				(font
					(size 1.27 1.27)
					(thickness 0.15)
				)
			)
		)
		(property "Description" "Power Inductor (SMT), 6.8 µH, 9.2 A, Shielded, 12.8 A, XAL7070"
			(at 0 0 90)
			(layer "F.Fab")
			(hide yes)
			(effects
				(font
					(size 1.27 1.27)
					(thickness 0.15)
				)
			)
		)
		(property "Author" "Antmicro"
			(at 193.548 -80.264 0)
			(layer "F.Fab")
			(hide yes)
			(effects
				(font
					(size 1 1)
					(thickness 0.15)
				)
			)
		)
		(property "IMax" "1.36 A"
			(at 193.548 -80.264 0)
			(layer "F.Fab")
			(hide yes)
			(effects
				(font
					(size 1 1)
					(thickness 0.15)
				)
			)
		)
		(property "ISat" "1 A"
			(at 193.548 -80.264 0)
			(layer "F.Fab")
			(hide yes)
			(effects
				(font
					(size 1 1)
					(thickness 0.15)
				)
			)
		)
		(property "License" "Apache-2.0"
			(at 193.548 -80.264 0)
			(layer "F.Fab")
			(hide yes)
			(effects
				(font
					(size 1 1)
					(thickness 0.15)
				)
			)
		)
		(property "MPN" "1210POC-682"
			(at 193.548 -80.264 0)
			(layer "F.Fab")
			(hide yes)
			(effects
				(font
					(size 1 1)
					(thickness 0.15)
				)
			)
		)
		(property "Manufacturer" "Coilcraft"
			(at 193.548 -80.264 0)
			(layer "F.Fab")
			(hide yes)
			(effects
				(font
					(size 1 1)
					(thickness 0.15)
				)
			)
		)
		(property "Size" "2.67x3.3"
			(at 193.548 -80.264 0)
			(layer "F.Fab")
			(hide yes)
			(effects
				(font
					(size 1 1)
					(thickness 0.15)
				)
			)
		)
		(property "Val" "6u8/1A"
			(at 193.548 -80.264 0)
			(layer "F.Fab")
			(hide yes)
			(effects
				(font
					(size 1 1)
					(thickness 0.15)
				)
			)
		)
		(sheetname "/Power/")
		(sheetfile "power.kicad_sch")
		(attr smd)
		(fp_line
			(start -0.7 -1.4)
			(end 0.7 -1.4)
			(stroke
				(width 0.15)
				(type solid)
			)
			(layer "F.SilkS")
		)
		(fp_line
			(start -0.7 1.4)
			(end 0.7 1.4)
			(stroke
				(width 0.15)
				(type solid)
			)
			(layer "F.SilkS")
		)
		(fp_rect
			(start -1.9 -1.585)
			(end 1.9 1.585)
			(stroke
				(width 0.05)
				(type solid)
			)
			(fill no)
			(layer "F.CrtYd")
		)
		(fp_line
			(start 1.65 -1.335)
			(end -1.65 -1.335)
			(stroke
				(width 0.15)
				(type solid)
			)
			(layer "F.Fab")
		)
		(fp_line
			(start 1.65 1.335)
			(end 1.65 -1.335)
			(stroke
				(width 0.15)
				(type solid)
			)
			(layer "F.Fab")
		)
		(fp_line
			(start 1.65 1.335)
			(end -1.65 1.335)
			(stroke
				(width 0.15)
				(type solid)
			)
			(layer "F.Fab")
		)
		(fp_line
			(start -1.65 1.335)
			(end -1.65 -1.335)
			(stroke
				(width 0.15)
				(type solid)
			)
			(layer "F.Fab")
		)
		(pad "1" smd rect
			(at -1.27 0 90)
			(size 0.65 2.65)
			(layers "F.Cu" "F.Mask" "F.Paste")
			(net 52 "Net-(L2-Pad2)")
			(pintype "passive")
		)
		(pad "2" smd rect
			(at 1.27 0 90)
			(size 0.65 2.65)
			(layers "F.Cu" "F.Mask" "F.Paste")
			(net 56 "Net-(L10-Pad1)")
			(pintype "passive")
		)
	)
	(footprint "antmicro-footprints:Conn_Molex_Nano-Fit_1x2_SMD_1054301202"
		(layer "F.Cu")
		(at 175.514 43.688 180)
		(descr "Molex Nano-Fit Power Connectors, 105430-xx02, 2 Pins per row")
		(tags "connector Molex Nano-Fit")
		(property "Reference" "J1"
			(at 2.604588 -5.512148 0)
			(layer "F.SilkS")
			(effects
				(font
					(size 0.7 0.7)
					(thickness 0.15)
				)
				(justify right bottom)
			)
		)
		(property "Value" "Molex_Nano-Fit_1x2_SMD_1054301202"
			(at 0 7.1 0)
			(layer "F.Fab")
			(effects
				(font
					(size 0.7 0.7)
					(thickness 0.15)
				)
				(justify right bottom)
			)
		)
		(property "Datasheet" "https://www.farnell.com/cad/3578051.pdf"
			(at 0 0 180)
			(layer "F.Fab")
			(hide yes)
			(effects
				(font
					(size 1.27 1.27)
					(thickness 0.15)
				)
			)
		)
		(property "Description" "Pin Header, Pitch 2.5 mm, 1 Row, 2 Contacts, Nano-Fit"
			(at 0 0 180)
			(layer "F.Fab")
			(hide yes)
			(effects
				(font
					(size 1.27 1.27)
					(thickness 0.15)
				)
			)
		)
		(property "Author" "Antmicro"
			(at 351.028 87.376 0)
			(layer "F.Fab")
			(hide yes)
			(effects
				(font
					(size 1 1)
					(thickness 0.15)
				)
			)
		)
		(property "License" "Apache-2.0"
			(at 351.028 87.376 0)
			(layer "F.Fab")
			(hide yes)
			(effects
				(font
					(size 1 1)
					(thickness 0.15)
				)
			)
		)
		(property "MPN" "105430-1202"
			(at 351.028 87.376 0)
			(layer "F.Fab")
			(hide yes)
			(effects
				(font
					(size 1 1)
					(thickness 0.15)
				)
			)
		)
		(property "Manufacturer" "Molex"
			(at 351.028 87.376 0)
			(layer "F.Fab")
			(hide yes)
			(effects
				(font
					(size 1 1)
					(thickness 0.15)
				)
			)
		)
		(sheetname "/Connectors/")
		(sheetfile "connectors.kicad_sch")
		(attr smd)
		(fp_line
			(start 4.48 2.298)
			(end 4.48 -4.5)
			(stroke
				(width 0.15)
				(type solid)
			)
			(layer "F.SilkS")
		)
		(fp_line
			(start 4.48 2.298)
			(end 4.28 2.698)
			(stroke
				(width 0.15)
				(type solid)
			)
			(layer "F.SilkS")
		)
		(fp_line
			(start 4.48 -4.5)
			(end 2.68 -4.5)
			(stroke
				(width 0.15)
				(type solid)
			)
			(layer "F.SilkS")
		)
		(fp_line
			(start 4.28 2.698)
			(end 4.28 4.299)
			(stroke
				(width 0.15)
				(type solid)
			)
			(layer "F.SilkS")
		)
		(fp_line
			(start -0.22 -4.5)
			(end 0.78 -4.5)
			(stroke
				(width 0.15)
				(type solid)
			)
			(layer "F.SilkS")
		)
		(fp_line
			(start -1.72 -4.5)
			(end -4.47 -4.5)
			(stroke
				(width 0.15)
				(type solid)
			)
			(layer "F.SilkS")
		)
		(fp_line
			(start -4.321 4.299)
			(end 4.28 4.299)
			(stroke
				(width 0.15)
				(type solid)
			)
			(layer "F.SilkS")
		)
		(fp_line
			(start -4.321 2.499)
			(end -4.321 4.299)
			(stroke
				(width 0.15)
				(type solid)
			)
			(layer "F.SilkS")
		)
		(fp_line
			(start -4.47 2.099)
			(end -4.321 2.499)
			(stroke
				(width 0.15)
				(type solid)
			)
			(layer "F.SilkS")
		)
		(fp_line
			(start -4.47 -4.5)
			(end -4.47 2.099)
			(stroke
				(width 0.15)
				(type solid)
			)
			(layer "F.SilkS")
		)
		(fp_circle
			(center 2.428 -4.91)
			(end 2.478 -4.91)
			(stroke
				(width 0.15)
				(type solid)
			)
			(fill yes)
			(layer "F.SilkS")
		)
		(fp_rect
			(start -4.77 -6.21)
			(end 4.77 6.11)
			(stroke
				(width 0.05)
				(type solid)
			)
			(fill no)
			(layer "F.CrtYd")
		)
		(pad "1" smd roundrect
			(at 1.528 -4.901 270)
			(size 2.5 1.24)
			(layers "F.Cu" "F.Mask" "F.Paste")
			(roundrect_rratio 0.25)
			(net 2 "/Connectors/DC_UNFUSED")
			(pintype "passive")
		)
		(pad "2" smd roundrect
			(at -0.97 -4.901 270)
			(size 2.5 1.24)
			(layers "F.Cu" "F.Mask" "F.Paste")
			(roundrect_rratio 0.25)
			(net 1 "GND")
			(pintype "passive")
		)
		(pad "MP" smd roundrect
			(at -3.54 0.029 180)
			(size 1.1 8.2)
			(layers "F.Cu" "F.Mask" "F.Paste")
			(roundrect_rratio 0.25)
			(net 1 "GND")
			(pintype "passive")
		)
		(pad "MP" smd roundrect
			(at 3.499 0.029 180)
			(size 1.1 8.2)
			(layers "F.Cu" "F.Mask" "F.Paste")
			(roundrect_rratio 0.25)
			(net 1 "GND")
			(pintype "passive")
		)
	)
	(footprint "antmicro-footprints:R_0402_1005Metric"
		(layer "F.Cu")
		(at 181.356 67.056)
		(descr "Resistor SMD 0402")
		(tags "resistor SMD 0402")
		(property "Reference" "R11"
			(at -1.279 9.2202 0)
			(layer "F.SilkS")
			(effects
				(font
					(size 0.7 0.7)
					(thickness 0.15)
				)
				(justify left bottom)
			)
		)
		(property "Value" "R_100R_0402"
			(at -1.011843 1.772047 0)
			(layer "F.Fab")
			(effects
				(font
					(size 0.7 0.7)
					(thickness 0.15)
				)
				(justify left bottom)
			)
		)
		(property "Datasheet" "https://www.bourns.com/docs/product-datasheets/cr.pdf"
			(at 0 0 0)
			(layer "F.Fab")
			(hide yes)
			(effects
				(font
					(size 1.27 1.27)
					(thickness 0.15)
				)
			)
		)
		(property "Description" "SMD Chip Resistor, 100 ohm, ± 1%, 62.5 mW, 0402 [1005 Metric], Thick Film, General Purpose"
			(at 0 0 0)
			(layer "F.Fab")
			(hide yes)
			(effects
				(font
					(size 1.27 1.27)
					(thickness 0.15)
				)
			)
		)
		(property "Author" "Antmicro"
			(at 0 0 0)
			(layer "F.Fab")
			(hide yes)
			(effects
				(font
					(size 1 1)
					(thickness 0.15)
				)
			)
		)
		(property "License" "Apache-2.0"
			(at 0 0 0)
			(layer "F.Fab")
			(hide yes)
			(effects
				(font
					(size 1 1)
					(thickness 0.15)
				)
			)
		)
		(property "MPN" "CR0402-FX-1000GLF"
			(at 0 0 0)
			(layer "F.Fab")
			(hide yes)
			(effects
				(font
					(size 1 1)
					(thickness 0.15)
				)
			)
		)
		(property "Manufacturer" "Bourns"
			(at 0 0 0)
			(layer "F.Fab")
			(hide yes)
			(effects
				(font
					(size 1 1)
					(thickness 0.15)
				)
			)
		)
		(property "Tolerance" "1%"
			(at 0 0 0)
			(layer "F.Fab")
			(hide yes)
			(effects
				(font
					(size 1 1)
					(thickness 0.15)
				)
			)
		)
		(property "Val" "100R"
			(at 0 0 0)
			(layer "F.Fab")
			(hide yes)
			(effects
				(font
					(size 1 1)
					(thickness 0.15)
				)
			)
		)
		(sheetname "/Connectors/")
		(sheetfile "connectors.kicad_sch")
		(attr smd)
		(fp_rect
			(start -0.925 -0.47)
			(end 0.925 0.47)
			(stroke
				(width 0.05)
				(type default)
			)
			(fill no)
			(layer "F.CrtYd")
		)
		(fp_rect
			(start -0.5 -0.25)
			(end 0.5 0.25)
			(stroke
				(width 0.15)
				(type solid)
			)
			(fill no)
			(layer "F.Fab")
		)
		(pad "1" smd roundrect
			(at -0.48 0)
			(size 0.59 0.64)
			(layers "F.Cu" "F.Mask" "F.Paste")
			(roundrect_rratio 0.25)
			(net 44 "/Connectors/SDA_CAM")
			(pintype "passive")
		)
		(pad "2" smd roundrect
			(at 0.48 0)
			(size 0.59 0.64)
			(layers "F.Cu" "F.Mask" "F.Paste")
			(roundrect_rratio 0.25)
			(net 119 "/Connectors/SDA_CAM0")
			(pintype "passive")
		)
	)
	(footprint "antmicro-footprints:LED_0603_1608Metric_G"
		(layer "F.Cu")
		(at 144.776 96.1 90)
		(descr "LED SMD 0603 Green")
		(tags "LED SMD 0603 Green")
		(property "Reference" "D20"
			(at 6.343331 -26.359333 180)
			(layer "F.SilkS")
			(effects
				(font
					(size 0.7 0.7)
					(thickness 0.15)
				)
				(justify right bottom)
			)
		)
		(property "Value" "LED_G_0603_LTST-C190GKT"
			(at -0.001 1.599 90)
			(layer "F.Fab")
			(effects
				(font
					(size 0.7 0.7)
					(thickness 0.15)
				)
				(justify left bottom)
			)
		)
		(property "Datasheet" "https://media.digikey.com/pdf/Data%20Sheets/Lite-On%20PDFs/LTST-C190GKT.pdf"
			(at 0 0 90)
			(layer "F.Fab")
			(hide yes)
			(effects
				(font
					(size 1.27 1.27)
					(thickness 0.15)
				)
			)
		)
		(property "Description" "LED, Green, SMD, 0603, 20 mA, 2.1 V, 569 nm"
			(at 0 0 90)
			(layer "F.Fab")
			(hide yes)
			(effects
				(font
					(size 1.27 1.27)
					(thickness 0.15)
				)
			)
		)
		(property "Author" "Antmicro"
			(at 240.876 -48.676 0)
			(layer "F.Fab")
			(hide yes)
			(effects
				(font
					(size 1 1)
					(thickness 0.15)
				)
			)
		)
		(property "Color" "Green"
			(at 240.876 -48.676 0)
			(layer "F.Fab")
			(hide yes)
			(effects
				(font
					(size 1 1)
					(thickness 0.15)
				)
			)
		)
		(property "License" "Apache-2.0"
			(at 240.876 -48.676 0)
			(layer "F.Fab")
			(hide yes)
			(effects
				(font
					(size 1 1)
					(thickness 0.15)
				)
			)
		)
		(property "MPN" "LTST-C190GKT"
			(at 240.876 -48.676 0)
			(layer "F.Fab")
			(hide yes)
			(effects
				(font
					(size 1 1)
					(thickness 0.15)
				)
			)
		)
		(property "Manufacturer" "Lite-On"
			(at 240.876 -48.676 0)
			(layer "F.Fab")
			(hide yes)
			(effects
				(font
					(size 1 1)
					(thickness 0.15)
				)
			)
		)
		(property "VSD_class" "LED"
			(at 240.876 -48.676 0)
			(layer "F.Fab")
			(hide yes)
			(effects
				(font
					(size 1 1)
					(thickness 0.15)
				)
			)
		)
		(sheetname "/Power/")
		(sheetfile "power.kicad_sch")
		(attr smd)
		(fp_line
			(start 0.22 -0.35)
			(end -0.22 -0.35)
			(stroke
				(width 0.15)
				(type solid)
			)
			(layer "F.SilkS")
		)
		(fp_line
			(start -1.18 -0.319)
			(end -1.18 0.321)
			(stroke
				(width 0.15)
				(type solid)
			)
			(layer "F.SilkS")
		)
		(fp_line
			(start 0.105328 0.001008)
			(end 0.24 0.001)
			(stroke
				(width 0.1)
				(type solid)
			)
			(layer "F.SilkS")
		)
		(fp_line
			(start -0.094672 0.001008)
			(end 0.105328 -0.198992)
			(stroke
				(width 0.1)
				(type solid)
			)
			(layer "F.SilkS")
		)
		(fp_line
			(start -0.094672 0.001008)
			(end -0.24 0.001008)
			(stroke
				(width 0.1)
				(type solid)
			)
			(layer "F.SilkS")
		)
		(fp_line
			(start 0.105328 0.201008)
			(end 0.105328 -0.198992)
			(stroke
				(width 0.1)
				(type solid)
			)
			(layer "F.SilkS")
		)
		(fp_line
			(start 0.105328 0.201008)
			(end -0.094672 0.001008)
			(stroke
				(width 0.1)
				(type solid)
			)
			(layer "F.SilkS")
		)
		(fp_line
			(start -0.094672 0.201008)
			(end -0.094672 -0.198992)
			(stroke
				(width 0.1)
				(type solid)
			)
			(layer "F.SilkS")
		)
		(fp_line
			(start 0.22 0.35)
			(end -0.22 0.35)
			(stroke
				(width 0.15)
				(type solid)
			)
			(layer "F.SilkS")
		)
		(fp_rect
			(start 1.25 0.65)
			(end -1.25 -0.65)
			(stroke
				(width 0.05)
				(type solid)
			)
			(fill no)
			(layer "F.CrtYd")
		)
		(fp_line
			(start 0.201 -0.202)
			(end -0.101 0)
			(stroke
				(width 0.15)
				(type solid)
			)
			(layer "F.Fab")
		)
		(fp_line
			(start -0.199 -0.202)
			(end -0.199 0.1)
			(stroke
				(width 0.15)
				(type solid)
			)
			(layer "F.Fab")
		)
		(fp_line
			(start 0.599 0)
			(end 0.201 0)
			(stroke
				(width 0.15)
				(type solid)
			)
			(layer "F.Fab")
		)
		(fp_line
			(start 0.201 0)
			(end 0.201 -0.202)
			(stroke
				(width 0.15)
				(type solid)
			)
			(layer "F.Fab")
		)
		(fp_line
			(start -0.101 0)
			(end 0.201 0.2)
			(stroke
				(width 0.15)
				(type solid)
			)
			(layer "F.Fab")
		)
		(fp_line
			(start -0.199 0)
			(end -0.597 0)
			(stroke
				(width 0.15)
				(type solid)
			)
			(layer "F.Fab")
		)
		(fp_line
			(start 0.201 0.2)
			(end 0.201 0)
			(stroke
				(width 0.15)
				(type solid)
			)
			(layer "F.Fab")
		)
		(fp_line
			(start -0.199 0.2)
			(end -0.199 0.1)
			(stroke
				(width 0.15)
				(type solid)
			)
			(layer "F.Fab")
		)
		(fp_rect
			(start 0.848 0.4)
			(end -0.85 -0.402)
			(stroke
				(width 0.15)
				(type solid)
			)
			(fill no)
			(layer "F.Fab")
		)
		(pad "1" smd roundrect
			(at -0.7 0 270)
			(size 0.8 1)
			(layers "F.Cu" "F.Mask" "F.Paste")
			(roundrect_rratio 0.2)
			(net 145 "Net-(D20-C)")
			(pinfunction "C")
			(pintype "passive")
		)
		(pad "2" smd roundrect
			(at 0.7 0 270)
			(size 0.8 1)
			(layers "F.Cu" "F.Mask" "F.Paste")
			(roundrect_rratio 0.2)
			(net 147 "Net-(D20-A)")
			(pinfunction "A")
			(pintype "passive")
		)
	)
	(footprint "antmicro-footprints:LED_0603_1608Metric_G"
		(layer "F.Cu")
		(at 150.876 96.11 -90)
		(descr "LED SMD 0603 Green")
		(tags "LED SMD 0603 Green")
		(property "Reference" "D16"
			(at -2.704444 32.459333 0)
			(layer "F.SilkS")
			(effects
				(font
					(size 0.7 0.7)
					(thickness 0.15)
				)
				(justify right bottom)
			)
		)
		(property "Value" "LED_G_0603_LTST-C190GKT"
			(at -0.001 1.599 90)
			(layer "F.Fab")
			(effects
				(font
					(size 0.7 0.7)
					(thickness 0.15)
				)
				(justify right bottom)
			)
		)
		(property "Datasheet" "https://media.digikey.com/pdf/Data%20Sheets/Lite-On%20PDFs/LTST-C190GKT.pdf"
			(at 0 0 270)
			(layer "F.Fab")
			(hide yes)
			(effects
				(font
					(size 1.27 1.27)
					(thickness 0.15)
				)
			)
		)
		(property "Description" "LED, Green, SMD, 0603, 20 mA, 2.1 V, 569 nm"
			(at 0 0 270)
			(layer "F.Fab")
			(hide yes)
			(effects
				(font
					(size 1.27 1.27)
					(thickness 0.15)
				)
			)
		)
		(property "Author" "Antmicro"
			(at 54.766 246.986 0)
			(layer "F.Fab")
			(hide yes)
			(effects
				(font
					(size 1 1)
					(thickness 0.15)
				)
			)
		)
		(property "Color" "Green"
			(at 54.766 246.986 0)
			(layer "F.Fab")
			(hide yes)
			(effects
				(font
					(size 1 1)
					(thickness 0.15)
				)
			)
		)
		(property "License" "Apache-2.0"
			(at 54.766 246.986 0)
			(layer "F.Fab")
			(hide yes)
			(effects
				(font
					(size 1 1)
					(thickness 0.15)
				)
			)
		)
		(property "MPN" "LTST-C190GKT"
			(at 54.766 246.986 0)
			(layer "F.Fab")
			(hide yes)
			(effects
				(font
					(size 1 1)
					(thickness 0.15)
				)
			)
		)
		(property "Manufacturer" "Lite-On"
			(at 54.766 246.986 0)
			(layer "F.Fab")
			(hide yes)
			(effects
				(font
					(size 1 1)
					(thickness 0.15)
				)
			)
		)
		(property "VSD_class" "LED"
			(at 54.766 246.986 0)
			(layer "F.Fab")
			(hide yes)
			(effects
				(font
					(size 1 1)
					(thickness 0.15)
				)
			)
		)
		(sheetname "/Power/")
		(sheetfile "power.kicad_sch")
		(attr smd)
		(fp_line
			(start 0.22 0.35)
			(end -0.22 0.35)
			(stroke
				(width 0.15)
				(type solid)
			)
			(layer "F.SilkS")
		)
		(fp_line
			(start -0.094672 0.201008)
			(end -0.094672 -0.198992)
			(stroke
				(width 0.1)
				(type solid)
			)
			(layer "F.SilkS")
		)
		(fp_line
			(start 0.105328 0.201008)
			(end -0.094672 0.001008)
			(stroke
				(width 0.1)
				(type solid)
			)
			(layer "F.SilkS")
		)
		(fp_line
			(start 0.105328 0.201008)
			(end 0.105328 -0.198992)
			(stroke
				(width 0.1)
				(type solid)
			)
			(layer "F.SilkS")
		)
		(fp_line
			(start -0.094672 0.001008)
			(end -0.24 0.001008)
			(stroke
				(width 0.1)
				(type solid)
			)
			(layer "F.SilkS")
		)
		(fp_line
			(start -0.094672 0.001008)
			(end 0.105328 -0.198992)
			(stroke
				(width 0.1)
				(type solid)
			)
			(layer "F.SilkS")
		)
		(fp_line
			(start 0.105328 0.001008)
			(end 0.24 0.001)
			(stroke
				(width 0.1)
				(type solid)
			)
			(layer "F.SilkS")
		)
		(fp_line
			(start -1.18 -0.319)
			(end -1.18 0.321)
			(stroke
				(width 0.15)
				(type solid)
			)
			(layer "F.SilkS")
		)
		(fp_line
			(start 0.22 -0.35)
			(end -0.22 -0.35)
			(stroke
				(width 0.15)
				(type solid)
			)
			(layer "F.SilkS")
		)
		(fp_rect
			(start 1.25 0.65)
			(end -1.25 -0.65)
			(stroke
				(width 0.05)
				(type solid)
			)
			(fill no)
			(layer "F.CrtYd")
		)
		(fp_line
			(start -0.199 0.2)
			(end -0.199 0.1)
			(stroke
				(width 0.15)
				(type solid)
			)
			(layer "F.Fab")
		)
		(fp_line
			(start 0.201 0.2)
			(end 0.201 0)
			(stroke
				(width 0.15)
				(type solid)
			)
			(layer "F.Fab")
		)
		(fp_line
			(start -0.199 0)
			(end -0.597 0)
			(stroke
				(width 0.15)
				(type solid)
			)
			(layer "F.Fab")
		)
		(fp_line
			(start -0.101 0)
			(end 0.201 0.2)
			(stroke
				(width 0.15)
				(type solid)
			)
			(layer "F.Fab")
		)
		(fp_line
			(start 0.201 0)
			(end 0.201 -0.202)
			(stroke
				(width 0.15)
				(type solid)
			)
			(layer "F.Fab")
		)
		(fp_line
			(start 0.599 0)
			(end 0.201 0)
			(stroke
				(width 0.15)
				(type solid)
			)
			(layer "F.Fab")
		)
		(fp_line
			(start -0.199 -0.202)
			(end -0.199 0.1)
			(stroke
				(width 0.15)
				(type solid)
			)
			(layer "F.Fab")
		)
		(fp_line
			(start 0.201 -0.202)
			(end -0.101 0)
			(stroke
				(width 0.15)
				(type solid)
			)
			(layer "F.Fab")
		)
		(fp_rect
			(start 0.848 0.4)
			(end -0.85 -0.402)
			(stroke
				(width 0.15)
				(type solid)
			)
			(fill no)
			(layer "F.Fab")
		)
		(pad "1" smd roundrect
			(at -0.7 0 90)
			(size 0.8 1)
			(layers "F.Cu" "F.Mask" "F.Paste")
			(roundrect_rratio 0.2)
			(net 140 "Net-(D16-C)")
			(pinfunction "C")
			(pintype "passive")
		)
		(pad "2" smd roundrect
			(at 0.7 0 90)
			(size 0.8 1)
			(layers "F.Cu" "F.Mask" "F.Paste")
			(roundrect_rratio 0.2)
			(net 5 "+5V")
			(pinfunction "A")
			(pintype "passive")
		)
	)
	(footprint "antmicro-footprints:C_0402_1005Metric"
		(layer "F.Cu")
		(at 145.724 66.5485 90)
		(descr "Capacitor SMD 0402")
		(tags "capacitor SMD 0402")
		(property "Reference" "C12"
			(at -1.8537 -0.563 90)
			(layer "F.SilkS")
			(effects
				(font
					(size 0.7 0.7)
					(thickness 0.15)
				)
				(justify left bottom)
			)
		)
		(property "Value" "C_10n_0402"
			(at -1.022927 2.155213 90)
			(layer "F.Fab")
			(effects
				(font
					(size 0.7 0.7)
					(thickness 0.15)
				)
				(justify left bottom)
			)
		)
		(property "Datasheet" "https://www.murata.com/products/productdetail?partno=GRM155R71H103KA88%23"
			(at 0 0 90)
			(layer "F.Fab")
			(hide yes)
			(effects
				(font
					(size 1.27 1.27)
					(thickness 0.15)
				)
			)
		)
		(property "Description" "SMD Multilayer Ceramic Capacitor, 10000 pF, 50 V, 0402 [1005 Metric], ± 10%, X7R, GRM Series"
			(at 0 0 90)
			(layer "F.Fab")
			(hide yes)
			(effects
				(font
					(size 1.27 1.27)
					(thickness 0.15)
				)
			)
		)
		(property "Author" "Antmicro"
			(at 212.2725 -79.1755 0)
			(layer "F.Fab")
			(hide yes)
			(effects
				(font
					(size 1 1)
					(thickness 0.15)
				)
			)
		)
		(property "Dielectric" "X7R"
			(at 212.2725 -79.1755 0)
			(layer "F.Fab")
			(hide yes)
			(effects
				(font
					(size 1 1)
					(thickness 0.15)
				)
			)
		)
		(property "License" "Apache-2.0"
			(at 212.2725 -79.1755 0)
			(layer "F.Fab")
			(hide yes)
			(effects
				(font
					(size 1 1)
					(thickness 0.15)
				)
			)
		)
		(property "MPN" "GRM155R71H103KA88D"
			(at 212.2725 -79.1755 0)
			(layer "F.Fab")
			(hide yes)
			(effects
				(font
					(size 1 1)
					(thickness 0.15)
				)
			)
		)
		(property "Manufacturer" "Murata"
			(at 212.2725 -79.1755 0)
			(layer "F.Fab")
			(hide yes)
			(effects
				(font
					(size 1 1)
					(thickness 0.15)
				)
			)
		)
		(property "Val" "10n"
			(at 212.2725 -79.1755 0)
			(layer "F.Fab")
			(hide yes)
			(effects
				(font
					(size 1 1)
					(thickness 0.15)
				)
			)
		)
		(property "Voltage" "50V"
			(at 212.2725 -79.1755 0)
			(layer "F.Fab")
			(hide yes)
			(effects
				(font
					(size 1 1)
					(thickness 0.15)
				)
			)
		)
		(sheetname "/Power/")
		(sheetfile "power.kicad_sch")
		(attr smd)
		(fp_rect
			(start -0.925 -0.47)
			(end 0.925 0.47)
			(stroke
				(width 0.05)
				(type default)
			)
			(fill no)
			(layer "F.CrtYd")
		)
		(fp_line
			(start 0.504 -0.25)
			(end 0.504 0.248)
			(stroke
				(width 0.15)
				(type solid)
			)
			(layer "F.Fab")
		)
		(fp_line
			(start -0.494 -0.25)
			(end 0.504 -0.25)
			(stroke
				(width 0.15)
				(type solid)
			)
			(layer "F.Fab")
		)
		(fp_line
			(start 0.504 0.248)
			(end -0.494 0.248)
			(stroke
				(width 0.15)
				(type solid)
			)
			(layer "F.Fab")
		)
		(fp_line
			(start -0.494 0.248)
			(end -0.494 -0.25)
			(stroke
				(width 0.15)
				(type solid)
			)
			(layer "F.Fab")
		)
		(pad "1" smd roundrect
			(at -0.48 0 90)
			(size 0.59 0.64)
			(layers "F.Cu" "F.Mask" "F.Paste")
			(roundrect_rratio 0.25)
			(net 1 "GND")
			(pintype "passive")
		)
		(pad "2" smd roundrect
			(at 0.48 0 90)
			(size 0.59 0.64)
			(layers "F.Cu" "F.Mask" "F.Paste")
			(roundrect_rratio 0.25)
			(net 4 "+12V")
			(pintype "passive")
		)
	)
	(footprint "antmicro-footprints:SOD-523_NP"
		(layer "F.Cu")
		(at 179.705 66.802 90)
		(property "Reference" "D10"
			(at -7.874 0.381 90)
			(layer "F.SilkS")
			(effects
				(font
					(size 0.7 0.7)
					(thickness 0.15)
				)
				(justify right bottom)
			)
		)
		(property "Value" "ESD5B5_0ST1G"
			(at 0 1.499 90)
			(layer "F.Fab")
			(effects
				(font
					(size 0.7 0.7)
					(thickness 0.15)
				)
				(justify left bottom)
			)
		)
		(property "Datasheet" "https://www.onsemi.com/pdf/datasheet/esd5b5.0st1-d.pdf"
			(at 0 0 90)
			(layer "F.Fab")
			(hide yes)
			(effects
				(font
					(size 1.27 1.27)
					(thickness 0.15)
				)
			)
		)
		(property "Description" "Bidirectional TVS, 30 kV,  SOD-523, 5 V, 32 pF"
			(at 0 0 90)
			(layer "F.Fab")
			(hide yes)
			(effects
				(font
					(size 1.27 1.27)
					(thickness 0.15)
				)
			)
		)
		(property "Author" "Antmicro"
			(at 246.507 -112.903 0)
			(layer "F.Fab")
			(hide yes)
			(effects
				(font
					(size 1 1)
					(thickness 0.15)
				)
			)
		)
		(property "License" "Apache-2.0"
			(at 246.507 -112.903 0)
			(layer "F.Fab")
			(hide yes)
			(effects
				(font
					(size 1 1)
					(thickness 0.15)
				)
			)
		)
		(property "MPN" "ESD5B5.0ST1G"
			(at 246.507 -112.903 0)
			(layer "F.Fab")
			(hide yes)
			(effects
				(font
					(size 1 1)
					(thickness 0.15)
				)
			)
		)
		(property "Manufacturer" "ON Semiconductor"
			(at 246.507 -112.903 0)
			(layer "F.Fab")
			(hide yes)
			(effects
				(font
					(size 1 1)
					(thickness 0.15)
				)
			)
		)
		(sheetname "/Connectors/")
		(sheetfile "connectors.kicad_sch")
		(attr smd)
		(fp_rect
			(start -1 -0.6)
			(end 1 0.6)
			(stroke
				(width 0.05)
				(type solid)
			)
			(fill no)
			(layer "F.CrtYd")
		)
		(fp_line
			(start 0.65 -0.425)
			(end 0.65 0.423)
			(stroke
				(width 0.15)
				(type solid)
			)
			(layer "F.Fab")
		)
		(fp_line
			(start -0.652 -0.425)
			(end 0.65 -0.425)
			(stroke
				(width 0.15)
				(type solid)
			)
			(layer "F.Fab")
		)
		(fp_line
			(start -0.652 0.423)
			(end -0.652 -0.425)
			(stroke
				(width 0.15)
				(type solid)
			)
			(layer "F.Fab")
		)
		(fp_line
			(start -0.652 0.423)
			(end 0.65 0.423)
			(stroke
				(width 0.15)
				(type solid)
			)
			(layer "F.Fab")
		)
		(pad "1" smd roundrect
			(at -0.701 0 90)
			(size 0.5 0.6)
			(layers "F.Cu" "F.Mask" "F.Paste")
			(roundrect_rratio 0.25)
			(net 1 "GND")
			(pinfunction "C")
			(pintype "passive")
		)
		(pad "2" smd roundrect
			(at 0.699 0 90)
			(size 0.5 0.6)
			(layers "F.Cu" "F.Mask" "F.Paste")
			(roundrect_rratio 0.25)
			(net 45 "/Connectors/SCL_CAM")
			(pinfunction "A")
			(pintype "passive")
		)
	)
	(footprint "antmicro-footprints:L_Coilcraft-PFL1609"
		(layer "F.Cu")
		(at 163.02 53.594)
		(property "Reference" "L16"
			(at -1.476 1.397 0)
			(layer "F.SilkS")
			(effects
				(font
					(size 0.7 0.7)
					(thickness 0.15)
				)
				(justify left bottom)
			)
		)
		(property "Value" "L_470n_1A_Coilcraft-PFL1609"
			(at 0 2 0)
			(layer "F.Fab")
			(effects
				(font
					(size 0.7 0.7)
					(thickness 0.15)
				)
				(justify left bottom)
			)
		)
		(property "Datasheet" "https://www.coilcraft.com/getmedia/2f4cd442-d64d-4413-a518-12fcfd03318d/pfl1609.pdf"
			(at 0 0 0)
			(layer "F.Fab")
			(hide yes)
			(effects
				(font
					(size 1.27 1.27)
					(thickness 0.15)
				)
			)
		)
		(property "Description" "Power Inductor (SMT), 6.8 µH, 9.2 A, Shielded, 12.8 A, XAL7070"
			(at 0 0 0)
			(layer "F.Fab")
			(hide yes)
			(effects
				(font
					(size 1.27 1.27)
					(thickness 0.15)
				)
			)
		)
		(property "Author" "Antmicro"
			(at 0 0 0)
			(layer "F.Fab")
			(hide yes)
			(effects
				(font
					(size 1 1)
					(thickness 0.15)
				)
			)
		)
		(property "IMax" "1 A"
			(at 0 0 0)
			(layer "F.Fab")
			(hide yes)
			(effects
				(font
					(size 1 1)
					(thickness 0.15)
				)
			)
		)
		(property "ISat" "0.99 A"
			(at 0 0 0)
			(layer "F.Fab")
			(hide yes)
			(effects
				(font
					(size 1 1)
					(thickness 0.15)
				)
			)
		)
		(property "License" "Apache-2.0"
			(at 0 0 0)
			(layer "F.Fab")
			(hide yes)
			(effects
				(font
					(size 1 1)
					(thickness 0.15)
				)
			)
		)
		(property "MPN" "PFL1609-471"
			(at 0 0 0)
			(layer "F.Fab")
			(hide yes)
			(effects
				(font
					(size 1 1)
					(thickness 0.15)
				)
			)
		)
		(property "Manufacturer" "Coilcraft"
			(at 0 0 0)
			(layer "F.Fab")
			(hide yes)
			(effects
				(font
					(size 1 1)
					(thickness 0.15)
				)
			)
		)
		(property "Size" "1.07x1.8"
			(at 0 0 0)
			(layer "F.Fab")
			(hide yes)
			(effects
				(font
					(size 1 1)
					(thickness 0.15)
				)
			)
		)
		(property "Val" "470n/0.99A"
			(at 0 0 0)
			(layer "F.Fab")
			(hide yes)
			(effects
				(font
					(size 1 1)
					(thickness 0.15)
				)
			)
		)
		(sheetname "/Power/")
		(sheetfile "power.kicad_sch")
		(attr smd)
		(fp_line
			(start -0.23 -0.45)
			(end 0.23 -0.45)
			(stroke
				(width 0.15)
				(type solid)
			)
			(layer "F.SilkS")
		)
		(fp_line
			(start -0.23 0.45)
			(end 0.23 0.45)
			(stroke
				(width 0.15)
				(type solid)
			)
			(layer "F.SilkS")
		)
		(fp_rect
			(start -1.2 -0.84)
			(end 1.2 0.84)
			(stroke
				(width 0.05)
				(type solid)
			)
			(fill no)
			(layer "F.CrtYd")
		)
		(fp_rect
			(start -0.9 -0.535)
			(end 0.9 0.535)
			(stroke
				(width 0.15)
				(type solid)
			)
			(fill no)
			(layer "F.Fab")
		)
		(pad "1" smd roundrect
			(at -0.635 0)
			(size 0.64 1.02)
			(layers "F.Cu" "F.Mask" "F.Paste")
			(roundrect_rratio 0.15)
			(net 62 "Net-(L12-Pad2)")
			(pintype "passive")
		)
		(pad "2" smd roundrect
			(at 0.635 0)
			(size 0.64 1.02)
			(layers "F.Cu" "F.Mask" "F.Paste")
			(roundrect_rratio 0.15)
			(net 117 "/Connectors/PoCD")
			(pintype "passive")
		)
	)
	(footprint "antmicro-footprints:C_0603_1608Metric"
		(layer "F.Cu")
		(at 126.674 83.162 90)
		(descr "Capacitor SMD 0603")
		(tags "capacitor 0603")
		(property "Reference" "C18"
			(at -0.5564 2.2056 90)
			(layer "F.SilkS")
			(effects
				(font
					(size 0.7 0.7)
					(thickness 0.15)
				)
				(justify left bottom)
			)
		)
		(property "Value" "C_10u_25V_0603"
			(at -1.42757 1.770288 90)
			(layer "F.Fab")
			(effects
				(font
					(size 0.7 0.7)
					(thickness 0.15)
				)
				(justify left bottom)
			)
		)
		(property "Datasheet" "https://product.tdk.com/en/search/capacitor/ceramic/mlcc/info?part_no=C1608X5R1E106M080AC"
			(at 0 0 90)
			(layer "F.Fab")
			(hide yes)
			(effects
				(font
					(size 1.27 1.27)
					(thickness 0.15)
				)
			)
		)
		(property "Description" "SMD Multilayer Ceramic Capacitor, 10 µF, 25 V, 0603 [1608 Metric], ± 20%, X5R, C"
			(at 0 0 90)
			(layer "F.Fab")
			(hide yes)
			(effects
				(font
					(size 1.27 1.27)
					(thickness 0.15)
				)
			)
		)
		(property "Author" "Antmicro"
			(at 209.836 -43.512 0)
			(layer "F.Fab")
			(hide yes)
			(effects
				(font
					(size 1 1)
					(thickness 0.15)
				)
			)
		)
		(property "Dielectric" ""
			(at 209.836 -43.512 0)
			(layer "F.Fab")
			(hide yes)
			(effects
				(font
					(size 1 1)
					(thickness 0.15)
				)
			)
		)
		(property "License" "Apache-2.0"
			(at 209.836 -43.512 0)
			(layer "F.Fab")
			(hide yes)
			(effects
				(font
					(size 1 1)
					(thickness 0.15)
				)
			)
		)
		(property "MPN" "C1608X5R1E106M080AC"
			(at 209.836 -43.512 0)
			(layer "F.Fab")
			(hide yes)
			(effects
				(font
					(size 1 1)
					(thickness 0.15)
				)
			)
		)
		(property "Manufacturer" "TDK"
			(at 209.836 -43.512 0)
			(layer "F.Fab")
			(hide yes)
			(effects
				(font
					(size 1 1)
					(thickness 0.15)
				)
			)
		)
		(property "Val" "10u"
			(at 209.836 -43.512 0)
			(layer "F.Fab")
			(hide yes)
			(effects
				(font
					(size 1 1)
					(thickness 0.15)
				)
			)
		)
		(property "Voltage" "25V"
			(at 209.836 -43.512 0)
			(layer "F.Fab")
			(hide yes)
			(effects
				(font
					(size 1 1)
					(thickness 0.15)
				)
			)
		)
		(sheetname "/Power/")
		(sheetfile "power.kicad_sch")
		(attr smd)
		(fp_line
			(start -0.15 -0.4)
			(end 0.15 -0.4)
			(stroke
				(width 0.15)
				(type solid)
			)
			(layer "F.SilkS")
		)
		(fp_line
			(start -0.15 0.4)
			(end 0.15 0.4)
			(stroke
				(width 0.15)
				(type solid)
			)
			(layer "F.SilkS")
		)
		(fp_rect
			(start -1.25 -0.65)
			(end 1.25 0.65)
			(stroke
				(width 0.05)
				(type solid)
			)
			(fill no)
			(layer "F.CrtYd")
		)
		(fp_rect
			(start -0.8 -0.4)
			(end 0.8 0.4)
			(stroke
				(width 0.15)
				(type solid)
			)
			(fill no)
			(layer "F.Fab")
		)
		(pad "1" smd roundrect
			(at -0.7 0 90)
			(size 0.8 1)
			(layers "F.Cu" "F.Mask" "F.Paste")
			(roundrect_rratio 0.2)
			(net 1 "GND")
			(pintype "passive")
		)
		(pad "2" smd roundrect
			(at 0.7 0 90)
			(size 0.8 1)
			(layers "F.Cu" "F.Mask" "F.Paste")
			(roundrect_rratio 0.2)
			(net 4 "+12V")
			(pintype "passive")
		)
	)
	(footprint "antmicro-footprints:R_0402_1005Metric"
		(layer "F.Cu")
		(at 119.149 84.328)
		(descr "Resistor SMD 0402")
		(tags "resistor SMD 0402")
		(property "Reference" "R65"
			(at -3.325 0.508 0)
			(layer "F.SilkS")
			(effects
				(font
					(size 0.7 0.7)
					(thickness 0.15)
				)
				(justify left bottom)
			)
		)
		(property "Value" "R_10k_0402"
			(at -1.011843 1.772047 0)
			(layer "F.Fab")
			(effects
				(font
					(size 0.7 0.7)
					(thickness 0.15)
				)
				(justify left bottom)
			)
		)
		(property "Datasheet" "https://www.bourns.com/docs/product-datasheets/cr.pdf"
			(at 0 0 0)
			(layer "F.Fab")
			(hide yes)
			(effects
				(font
					(size 1.27 1.27)
					(thickness 0.15)
				)
			)
		)
		(property "Description" "SMD Chip Resistor, 10 kohm, ± 1%, 62.5 mW, 0402 [1005 Metric], Thick Film, General Purpose"
			(at 0 0 0)
			(layer "F.Fab")
			(hide yes)
			(effects
				(font
					(size 1.27 1.27)
					(thickness 0.15)
				)
			)
		)
		(property "Author" "Antmicro"
			(at 0 0 0)
			(layer "F.Fab")
			(hide yes)
			(effects
				(font
					(size 1 1)
					(thickness 0.15)
				)
			)
		)
		(property "License" "Apache-2.0"
			(at 0 0 0)
			(layer "F.Fab")
			(hide yes)
			(effects
				(font
					(size 1 1)
					(thickness 0.15)
				)
			)
		)
		(property "MPN" "CR0402-FX-1002GLF"
			(at 0 0 0)
			(layer "F.Fab")
			(hide yes)
			(effects
				(font
					(size 1 1)
					(thickness 0.15)
				)
			)
		)
		(property "Manufacturer" "Bourns"
			(at 0 0 0)
			(layer "F.Fab")
			(hide yes)
			(effects
				(font
					(size 1 1)
					(thickness 0.15)
				)
			)
		)
		(property "Tolerance" "1%"
			(at 0 0 0)
			(layer "F.Fab")
			(hide yes)
			(effects
				(font
					(size 1 1)
					(thickness 0.15)
				)
			)
		)
		(property "Val" "10k"
			(at 0 0 0)
			(layer "F.Fab")
			(hide yes)
			(effects
				(font
					(size 1 1)
					(thickness 0.15)
				)
			)
		)
		(sheetname "/Power/")
		(sheetfile "power.kicad_sch")
		(attr smd)
		(fp_rect
			(start -0.925 -0.47)
			(end 0.925 0.47)
			(stroke
				(width 0.05)
				(type default)
			)
			(fill no)
			(layer "F.CrtYd")
		)
		(fp_rect
			(start -0.5 -0.25)
			(end 0.5 0.25)
			(stroke
				(width 0.15)
				(type solid)
			)
			(fill no)
			(layer "F.Fab")
		)
		(pad "1" smd roundrect
			(at -0.48 0)
			(size 0.59 0.64)
			(layers "F.Cu" "F.Mask" "F.Paste")
			(roundrect_rratio 0.25)
			(net 1 "GND")
			(pintype "passive")
		)
		(pad "2" smd roundrect
			(at 0.48 0)
			(size 0.59 0.64)
			(layers "F.Cu" "F.Mask" "F.Paste")
			(roundrect_rratio 0.25)
			(net 68 "/Power/EN_1V2")
			(pintype "passive")
		)
	)
	(footprint "antmicro-footprints:TP_SMD_0.75mm"
		(layer "F.Cu")
		(at 146.812 74.422)
		(property "Reference" "TP2"
			(at -2.99467 1.167469 0)
			(layer "F.SilkS")
			(hide yes)
			(effects
				(font
					(size 0.7 0.7)
					(thickness 0.15)
				)
				(justify left bottom)
			)
		)
		(property "Value" "TP_0.75mm_SMD"
			(at 0 1.2 0)
			(layer "F.Fab")
			(effects
				(font
					(size 0.7 0.7)
					(thickness 0.15)
				)
				(justify left bottom)
			)
		)
		(property "Description" "SMT test point"
			(at 0 0 0)
			(layer "F.Fab")
			(hide yes)
			(effects
				(font
					(size 1.27 1.27)
					(thickness 0.15)
				)
			)
		)
		(property "Author" "Antmicro"
			(at 0 0 0)
			(layer "F.Fab")
			(hide yes)
			(effects
				(font
					(size 1 1)
					(thickness 0.15)
				)
			)
		)
		(property "License" "Apache-2.0"
			(at 0 0 0)
			(layer "F.Fab")
			(hide yes)
			(effects
				(font
					(size 1 1)
					(thickness 0.15)
				)
			)
		)
		(property "MPN" ""
			(at 0 0 0)
			(layer "F.Fab")
			(hide yes)
			(effects
				(font
					(size 1 1)
					(thickness 0.15)
				)
			)
		)
		(property "Manufacturer" ""
			(at 0 0 0)
			(layer "F.Fab")
			(hide yes)
			(effects
				(font
					(size 1 1)
					(thickness 0.15)
				)
			)
		)
		(sheetname "/Connectors/")
		(sheetfile "connectors.kicad_sch")
		(fp_circle
			(center 0 0)
			(end 0.475 0)
			(stroke
				(width 0.05)
				(type default)
			)
			(fill no)
			(layer "F.CrtYd")
		)
		(pad "1" smd circle
			(at 0 0)
			(size 0.75 0.75)
			(layers "F.Cu" "F.Mask")
			(net 85 "/Connectors/MFP5")
			(pinfunction "1")
			(pintype "passive")
		)
	)
	(footprint "antmicro-footprints:C_0402_1005Metric"
		(layer "F.Cu")
		(at 146.994 66.5485 90)
		(descr "Capacitor SMD 0402")
		(tags "capacitor SMD 0402")
		(property "Reference" "C8"
			(at -1.3965 1.215 90)
			(layer "F.SilkS")
			(effects
				(font
					(size 0.7 0.7)
					(thickness 0.15)
				)
				(justify left bottom)
			)
		)
		(property "Value" "C_100n_0402"
			(at -1.022927 2.155213 90)
			(layer "F.Fab")
			(effects
				(font
					(size 0.7 0.7)
					(thickness 0.15)
				)
				(justify left bottom)
			)
		)
		(property "Datasheet" "https://www.murata.com/products/productdetail?partno=GRM155R61H104KE14%23"
			(at 0 0 90)
			(layer "F.Fab")
			(hide yes)
			(effects
				(font
					(size 1.27 1.27)
					(thickness 0.15)
				)
			)
		)
		(property "Description" "SMD Multilayer Ceramic Capacitor, 0.1 µF, 50 V, 0402 [1005 Metric], ± 10%, X5R, GRM Series"
			(at 0 0 90)
			(layer "F.Fab")
			(hide yes)
			(effects
				(font
					(size 1.27 1.27)
					(thickness 0.15)
				)
			)
		)
		(property "Author" "Antmicro"
			(at 213.5425 -80.4455 0)
			(layer "F.Fab")
			(hide yes)
			(effects
				(font
					(size 1 1)
					(thickness 0.15)
				)
			)
		)
		(property "Dielectric" "X5R"
			(at 213.5425 -80.4455 0)
			(layer "F.Fab")
			(hide yes)
			(effects
				(font
					(size 1 1)
					(thickness 0.15)
				)
			)
		)
		(property "License" "Apache-2.0"
			(at 213.5425 -80.4455 0)
			(layer "F.Fab")
			(hide yes)
			(effects
				(font
					(size 1 1)
					(thickness 0.15)
				)
			)
		)
		(property "MPN" "GRM155R61H104KE14D"
			(at 213.5425 -80.4455 0)
			(layer "F.Fab")
			(hide yes)
			(effects
				(font
					(size 1 1)
					(thickness 0.15)
				)
			)
		)
		(property "Manufacturer" "Murata"
			(at 213.5425 -80.4455 0)
			(layer "F.Fab")
			(hide yes)
			(effects
				(font
					(size 1 1)
					(thickness 0.15)
				)
			)
		)
		(property "Val" "100n"
			(at 213.5425 -80.4455 0)
			(layer "F.Fab")
			(hide yes)
			(effects
				(font
					(size 1 1)
					(thickness 0.15)
				)
			)
		)
		(property "Voltage" "50V"
			(at 213.5425 -80.4455 0)
			(layer "F.Fab")
			(hide yes)
			(effects
				(font
					(size 1 1)
					(thickness 0.15)
				)
			)
		)
		(sheetname "/Power/")
		(sheetfile "power.kicad_sch")
		(attr smd)
		(fp_rect
			(start -0.925 -0.47)
			(end 0.925 0.47)
			(stroke
				(width 0.05)
				(type default)
			)
			(fill no)
			(layer "F.CrtYd")
		)
		(fp_line
			(start 0.504 -0.25)
			(end 0.504 0.248)
			(stroke
				(width 0.15)
				(type solid)
			)
			(layer "F.Fab")
		)
		(fp_line
			(start -0.494 -0.25)
			(end 0.504 -0.25)
			(stroke
				(width 0.15)
				(type solid)
			)
			(layer "F.Fab")
		)
		(fp_line
			(start 0.504 0.248)
			(end -0.494 0.248)
			(stroke
				(width 0.15)
				(type solid)
			)
			(layer "F.Fab")
		)
		(fp_line
			(start -0.494 0.248)
			(end -0.494 -0.25)
			(stroke
				(width 0.15)
				(type solid)
			)
			(layer "F.Fab")
		)
		(pad "1" smd roundrect
			(at -0.48 0 90)
			(size 0.59 0.64)
			(layers "F.Cu" "F.Mask" "F.Paste")
			(roundrect_rratio 0.25)
			(net 1 "GND")
			(pintype "passive")
		)
		(pad "2" smd roundrect
			(at 0.48 0 90)
			(size 0.59 0.64)
			(layers "F.Cu" "F.Mask" "F.Paste")
			(roundrect_rratio 0.25)
			(net 4 "+12V")
			(pintype "passive")
		)
	)
	(footprint "antmicro-footprints:R_0402_1005Metric"
		(layer "F.Cu")
		(at 170.688 66.818)
		(descr "Resistor SMD 0402")
		(tags "resistor SMD 0402")
		(property "Reference" "R67"
			(at -3.148968 0.328135 0)
			(layer "F.SilkS")
			(effects
				(font
					(size 0.7 0.7)
					(thickness 0.15)
				)
				(justify left bottom)
			)
		)
		(property "Value" "R_100R_0402"
			(at -1.011843 1.772047 0)
			(layer "F.Fab")
			(effects
				(font
					(size 0.7 0.7)
					(thickness 0.15)
				)
				(justify left bottom)
			)
		)
		(property "Datasheet" "https://www.bourns.com/docs/product-datasheets/cr.pdf"
			(at 0 0 0)
			(layer "F.Fab")
			(hide yes)
			(effects
				(font
					(size 1.27 1.27)
					(thickness 0.15)
				)
			)
		)
		(property "Description" "SMD Chip Resistor, 100 ohm, ± 1%, 62.5 mW, 0402 [1005 Metric], Thick Film, General Purpose"
			(at 0 0 0)
			(layer "F.Fab")
			(hide yes)
			(effects
				(font
					(size 1.27 1.27)
					(thickness 0.15)
				)
			)
		)
		(property "Author" "Antmicro"
			(at 0 0 0)
			(layer "F.Fab")
			(hide yes)
			(effects
				(font
					(size 1 1)
					(thickness 0.15)
				)
			)
		)
		(property "License" "Apache-2.0"
			(at 0 0 0)
			(layer "F.Fab")
			(hide yes)
			(effects
				(font
					(size 1 1)
					(thickness 0.15)
				)
			)
		)
		(property "MPN" "CR0402-FX-1000GLF"
			(at 0 0 0)
			(layer "F.Fab")
			(hide yes)
			(effects
				(font
					(size 1 1)
					(thickness 0.15)
				)
			)
		)
		(property "Manufacturer" "Bourns"
			(at 0 0 0)
			(layer "F.Fab")
			(hide yes)
			(effects
				(font
					(size 1 1)
					(thickness 0.15)
				)
			)
		)
		(property "Tolerance" "1%"
			(at 0 0 0)
			(layer "F.Fab")
			(hide yes)
			(effects
				(font
					(size 1 1)
					(thickness 0.15)
				)
			)
		)
		(property "Val" "100R"
			(at 0 0 0)
			(layer "F.Fab")
			(hide yes)
			(effects
				(font
					(size 1 1)
					(thickness 0.15)
				)
			)
		)
		(sheetname "/Connectors/")
		(sheetfile "connectors.kicad_sch")
		(attr smd)
		(fp_rect
			(start -0.925 -0.47)
			(end 0.925 0.47)
			(stroke
				(width 0.05)
				(type default)
			)
			(fill no)
			(layer "F.CrtYd")
		)
		(fp_rect
			(start -0.5 -0.25)
			(end 0.5 0.25)
			(stroke
				(width 0.15)
				(type solid)
			)
			(fill no)
			(layer "F.Fab")
		)
		(pad "1" smd roundrect
			(at -0.48 0)
			(size 0.59 0.64)
			(layers "F.Cu" "F.Mask" "F.Paste")
			(roundrect_rratio 0.25)
			(net 121 "/Connectors/SCL")
			(pintype "passive")
		)
		(pad "2" smd roundrect
			(at 0.48 0)
			(size 0.59 0.64)
			(layers "F.Cu" "F.Mask" "F.Paste")
			(roundrect_rratio 0.25)
			(net 134 "Net-(U8-A_{2})")
			(pintype "passive")
		)
	)
	(footprint "antmicro-footprints:SOD-523_NP"
		(layer "F.Cu")
		(at 177.038 69.088)
		(property "Reference" "D6"
			(at -2.54 0.508 0)
			(layer "F.SilkS")
			(effects
				(font
					(size 0.7 0.7)
					(thickness 0.15)
				)
				(justify left bottom)
			)
		)
		(property "Value" "ESD5B5_0ST1G"
			(at 0 1.499 0)
			(layer "F.Fab")
			(effects
				(font
					(size 0.7 0.7)
					(thickness 0.15)
				)
				(justify left bottom)
			)
		)
		(property "Datasheet" "https://www.onsemi.com/pdf/datasheet/esd5b5.0st1-d.pdf"
			(at 0 0 0)
			(layer "F.Fab")
			(hide yes)
			(effects
				(font
					(size 1.27 1.27)
					(thickness 0.15)
				)
			)
		)
		(property "Description" "Bidirectional TVS, 30 kV,  SOD-523, 5 V, 32 pF"
			(at 0 0 0)
			(layer "F.Fab")
			(hide yes)
			(effects
				(font
					(size 1.27 1.27)
					(thickness 0.15)
				)
			)
		)
		(property "Author" "Antmicro"
			(at 0 0 0)
			(layer "F.Fab")
			(hide yes)
			(effects
				(font
					(size 1 1)
					(thickness 0.15)
				)
			)
		)
		(property "License" "Apache-2.0"
			(at 0 0 0)
			(layer "F.Fab")
			(hide yes)
			(effects
				(font
					(size 1 1)
					(thickness 0.15)
				)
			)
		)
		(property "MPN" "ESD5B5.0ST1G"
			(at 0 0 0)
			(layer "F.Fab")
			(hide yes)
			(effects
				(font
					(size 1 1)
					(thickness 0.15)
				)
			)
		)
		(property "Manufacturer" "ON Semiconductor"
			(at 0 0 0)
			(layer "F.Fab")
			(hide yes)
			(effects
				(font
					(size 1 1)
					(thickness 0.15)
				)
			)
		)
		(sheetname "/Connectors/")
		(sheetfile "connectors.kicad_sch")
		(attr smd)
		(fp_rect
			(start -1 -0.6)
			(end 1 0.6)
			(stroke
				(width 0.05)
				(type solid)
			)
			(fill no)
			(layer "F.CrtYd")
		)
		(fp_line
			(start -0.652 -0.425)
			(end 0.65 -0.425)
			(stroke
				(width 0.15)
				(type solid)
			)
			(layer "F.Fab")
		)
		(fp_line
			(start -0.652 0.423)
			(end -0.652 -0.425)
			(stroke
				(width 0.15)
				(type solid)
			)
			(layer "F.Fab")
		)
		(fp_line
			(start -0.652 0.423)
			(end 0.65 0.423)
			(stroke
				(width 0.15)
				(type solid)
			)
			(layer "F.Fab")
		)
		(fp_line
			(start 0.65 -0.425)
			(end 0.65 0.423)
			(stroke
				(width 0.15)
				(type solid)
			)
			(layer "F.Fab")
		)
		(pad "1" smd roundrect
			(at -0.701 0)
			(size 0.5 0.6)
			(layers "F.Cu" "F.Mask" "F.Paste")
			(roundrect_rratio 0.25)
			(net 1 "GND")
			(pinfunction "C")
			(pintype "passive")
		)
		(pad "2" smd roundrect
			(at 0.699 0)
			(size 0.5 0.6)
			(layers "F.Cu" "F.Mask" "F.Paste")
			(roundrect_rratio 0.25)
			(net 67 "/Connectors/VSYNC_CAM0")
			(pinfunction "A")
			(pintype "passive")
		)
	)
	(footprint "antmicro-footprints:R_0402_1005Metric"
		(layer "F.Cu")
		(at 181.356 69.192)
		(descr "Resistor SMD 0402")
		(tags "resistor SMD 0402")
		(property "Reference" "R9"
			(at -1.279 9.1162 0)
			(layer "F.SilkS")
			(effects
				(font
					(size 0.7 0.7)
					(thickness 0.15)
				)
				(justify left bottom)
			)
		)
		(property "Value" "R_100R_0402"
			(at -1.011843 1.772047 0)
			(layer "F.Fab")
			(effects
				(font
					(size 0.7 0.7)
					(thickness 0.15)
				)
				(justify left bottom)
			)
		)
		(property "Datasheet" "https://www.bourns.com/docs/product-datasheets/cr.pdf"
			(at 0 0 0)
			(layer "F.Fab")
			(hide yes)
			(effects
				(font
					(size 1.27 1.27)
					(thickness 0.15)
				)
			)
		)
		(property "Description" "SMD Chip Resistor, 100 ohm, ± 1%, 62.5 mW, 0402 [1005 Metric], Thick Film, General Purpose"
			(at 0 0 0)
			(layer "F.Fab")
			(hide yes)
			(effects
				(font
					(size 1.27 1.27)
					(thickness 0.15)
				)
			)
		)
		(property "Author" "Antmicro"
			(at 0 0 0)
			(layer "F.Fab")
			(hide yes)
			(effects
				(font
					(size 1 1)
					(thickness 0.15)
				)
			)
		)
		(property "License" "Apache-2.0"
			(at 0 0 0)
			(layer "F.Fab")
			(hide yes)
			(effects
				(font
					(size 1 1)
					(thickness 0.15)
				)
			)
		)
		(property "MPN" "CR0402-FX-1000GLF"
			(at 0 0 0)
			(layer "F.Fab")
			(hide yes)
			(effects
				(font
					(size 1 1)
					(thickness 0.15)
				)
			)
		)
		(property "Manufacturer" "Bourns"
			(at 0 0 0)
			(layer "F.Fab")
			(hide yes)
			(effects
				(font
					(size 1 1)
					(thickness 0.15)
				)
			)
		)
		(property "Tolerance" "1%"
			(at 0 0 0)
			(layer "F.Fab")
			(hide yes)
			(effects
				(font
					(size 1 1)
					(thickness 0.15)
				)
			)
		)
		(property "Val" "100R"
			(at 0 0 0)
			(layer "F.Fab")
			(hide yes)
			(effects
				(font
					(size 1 1)
					(thickness 0.15)
				)
			)
		)
		(sheetname "/Connectors/")
		(sheetfile "connectors.kicad_sch")
		(attr smd)
		(fp_rect
			(start -0.925 -0.47)
			(end 0.925 0.47)
			(stroke
				(width 0.05)
				(type default)
			)
			(fill no)
			(layer "F.CrtYd")
		)
		(fp_rect
			(start -0.5 -0.25)
			(end 0.5 0.25)
			(stroke
				(width 0.15)
				(type solid)
			)
			(fill no)
			(layer "F.Fab")
		)
		(pad "1" smd roundrect
			(at -0.48 0)
			(size 0.59 0.64)
			(layers "F.Cu" "F.Mask" "F.Paste")
			(roundrect_rratio 0.25)
			(net 67 "/Connectors/VSYNC_CAM0")
			(pintype "passive")
		)
		(pad "2" smd roundrect
			(at 0.48 0)
			(size 0.59 0.64)
			(layers "F.Cu" "F.Mask" "F.Paste")
			(roundrect_rratio 0.25)
			(net 35 "Net-(J6-Pad32)")
			(pintype "passive")
		)
	)
	(footprint "antmicro-footprints:TP_SMD_0.75mm"
		(layer "F.Cu")
		(at 153.924 97.89)
		(property "Reference" "TP9"
			(at 0 -0.6 0)
			(layer "F.SilkS")
			(hide yes)
			(effects
				(font
					(size 0.7 0.7)
					(thickness 0.15)
				)
				(justify left bottom)
			)
		)
		(property "Value" "TP_0.75mm_SMD"
			(at 0 1.2 0)
			(layer "F.Fab")
			(effects
				(font
					(size 0.7 0.7)
					(thickness 0.15)
				)
				(justify left bottom)
			)
		)
		(property "Description" "SMT test point"
			(at 0 0 0)
			(layer "F.Fab")
			(hide yes)
			(effects
				(font
					(size 1.27 1.27)
					(thickness 0.15)
				)
			)
		)
		(property "Author" "Antmicro"
			(at 0 0 0)
			(layer "F.Fab")
			(hide yes)
			(effects
				(font
					(size 1 1)
					(thickness 0.15)
				)
			)
		)
		(property "License" "Apache-2.0"
			(at 0 0 0)
			(layer "F.Fab")
			(hide yes)
			(effects
				(font
					(size 1 1)
					(thickness 0.15)
				)
			)
		)
		(property "MPN" ""
			(at 0 0 0)
			(layer "F.Fab")
			(hide yes)
			(effects
				(font
					(size 1 1)
					(thickness 0.15)
				)
			)
		)
		(property "Manufacturer" ""
			(at 0 0 0)
			(layer "F.Fab")
			(hide yes)
			(effects
				(font
					(size 1 1)
					(thickness 0.15)
				)
			)
		)
		(sheetname "/Power/")
		(sheetfile "power.kicad_sch")
		(fp_circle
			(center 0 0)
			(end 0.475 0)
			(stroke
				(width 0.05)
				(type default)
			)
			(fill no)
			(layer "F.CrtYd")
		)
		(pad "1" smd circle
			(at 0 0)
			(size 0.75 0.75)
			(layers "F.Cu" "F.Mask")
			(net 118 "/Connectors/DC_IN")
			(pinfunction "1")
			(pintype "passive")
		)
	)
	(footprint "antmicro-footprints:L_0806_2016Metric"
		(layer "F.Cu")
		(at 134.519 91.554 180)
		(property "Reference" "L18"
			(at -0.001 1.27 0)
			(layer "F.SilkS")
			(effects
				(font
					(size 0.7 0.7)
					(thickness 0.15)
				)
				(justify right bottom)
			)
		)
		(property "Value" "L_1u_2.6A_0806"
			(at 0 2 0)
			(layer "F.Fab")
			(effects
				(font
					(size 0.7 0.7)
					(thickness 0.15)
				)
				(justify right bottom)
			)
		)
		(property "Datasheet" "https://www.bourns.com/docs/Product-Datasheets/SRP2010.pdf"
			(at 0 0 180)
			(layer "F.Fab")
			(hide yes)
			(effects
				(font
					(size 1.27 1.27)
					(thickness 0.15)
				)
			)
		)
		(property "Description" "Wirewound Inductor, 1 µH, 0.072 ohm, 2.6 A, SRP2010"
			(at 0 0 180)
			(layer "F.Fab")
			(hide yes)
			(effects
				(font
					(size 1.27 1.27)
					(thickness 0.15)
				)
			)
		)
		(property "Author" "Antmicro"
			(at 269.038 183.108 0)
			(layer "F.Fab")
			(hide yes)
			(effects
				(font
					(size 1 1)
					(thickness 0.15)
				)
			)
		)
		(property "IMax" "2.6 A"
			(at 269.038 183.108 0)
			(layer "F.Fab")
			(hide yes)
			(effects
				(font
					(size 1 1)
					(thickness 0.15)
				)
			)
		)
		(property "ISat" "2.9 A"
			(at 269.038 183.108 0)
			(layer "F.Fab")
			(hide yes)
			(effects
				(font
					(size 1 1)
					(thickness 0.15)
				)
			)
		)
		(property "License" "Apache-2.0"
			(at 269.038 183.108 0)
			(layer "F.Fab")
			(hide yes)
			(effects
				(font
					(size 1 1)
					(thickness 0.15)
				)
			)
		)
		(property "MPN" "SRP2010-1R0M"
			(at 269.038 183.108 0)
			(layer "F.Fab")
			(hide yes)
			(effects
				(font
					(size 1 1)
					(thickness 0.15)
				)
			)
		)
		(property "Manufacturer" "Bourns"
			(at 269.038 183.108 0)
			(layer "F.Fab")
			(hide yes)
			(effects
				(font
					(size 1 1)
					(thickness 0.15)
				)
			)
		)
		(property "Size" "2.0x1.6"
			(at 269.038 183.108 0)
			(layer "F.Fab")
			(hide yes)
			(effects
				(font
					(size 1 1)
					(thickness 0.15)
				)
			)
		)
		(property "Val" "1u/2.6A"
			(at 269.038 183.108 0)
			(layer "F.Fab")
			(hide yes)
			(effects
				(font
					(size 1 1)
					(thickness 0.15)
				)
			)
		)
		(sheetname "/Power/")
		(sheetfile "power.kicad_sch")
		(attr smd)
		(fp_line
			(start -0.3 -0.9)
			(end 0.298 -0.9)
			(stroke
				(width 0.15)
				(type solid)
			)
			(layer "F.SilkS")
		)
		(fp_line
			(start -0.301 0.9)
			(end 0.299 0.9)
			(stroke
				(width 0.15)
				(type solid)
			)
			(layer "F.SilkS")
		)
		(fp_rect
			(start -1.75 -1.05)
			(end 1.75 1.05)
			(stroke
				(width 0.05)
				(type solid)
			)
			(fill no)
			(layer "F.CrtYd")
		)
		(fp_rect
			(start -0.951 -0.882)
			(end 0.949 0.875)
			(stroke
				(width 0.15)
				(type solid)
			)
			(fill no)
			(layer "F.Fab")
		)
		(pad "1" smd roundrect
			(at -1.1 -0.001 180)
			(size 1 1.8)
			(layers "F.Cu" "F.Mask" "F.Paste")
			(roundrect_rratio 0.15)
			(net 7 "/Power/SW_1V8")
			(pintype "passive")
		)
		(pad "2" smd roundrect
			(at 1.1 -0.001 180)
			(size 1 1.8)
			(layers "F.Cu" "F.Mask" "F.Paste")
			(roundrect_rratio 0.15)
			(net 10 "/Power/OUT_1V8")
			(pintype "passive")
		)
	)
	(footprint "antmicro-footprints:C_0402_1005Metric"
		(layer "F.Cu")
		(at 131.98 93.078 90)
		(descr "Capacitor SMD 0402")
		(tags "capacitor SMD 0402")
		(property "Reference" "C21"
			(at -0.394 -2.186 90)
			(layer "F.SilkS")
			(effects
				(font
					(size 0.7 0.7)
					(thickness 0.15)
				)
				(justify left bottom)
			)
		)
		(property "Value" "C_22u_0402"
			(at -1.022927 2.155213 90)
			(layer "F.Fab")
			(effects
				(font
					(size 0.7 0.7)
					(thickness 0.15)
				)
				(justify left bottom)
			)
		)
		(property "Datasheet" "https://www.murata.com/products/productdetail?partno=GRM158R60J226ME01%23"
			(at 0 0 90)
			(layer "F.Fab")
			(hide yes)
			(effects
				(font
					(size 1.27 1.27)
					(thickness 0.15)
				)
			)
		)
		(property "Description" "SMD Multilayer Ceramic Capacitor, 22 uF, 4 V, 0402 [1005 Metric], X6S"
			(at 0 0 90)
			(layer "F.Fab")
			(hide yes)
			(effects
				(font
					(size 1.27 1.27)
					(thickness 0.15)
				)
			)
		)
		(property "Author" "Antmicro"
			(at 225.058 -38.902 0)
			(layer "F.Fab")
			(hide yes)
			(effects
				(font
					(size 1 1)
					(thickness 0.15)
				)
			)
		)
		(property "Dielectric" ""
			(at 225.058 -38.902 0)
			(layer "F.Fab")
			(hide yes)
			(effects
				(font
					(size 1 1)
					(thickness 0.15)
				)
			)
		)
		(property "License" "Apache-2.0"
			(at 225.058 -38.902 0)
			(layer "F.Fab")
			(hide yes)
			(effects
				(font
					(size 1 1)
					(thickness 0.15)
				)
			)
		)
		(property "MPN" "GRM158R60J226ME01D"
			(at 225.058 -38.902 0)
			(layer "F.Fab")
			(hide yes)
			(effects
				(font
					(size 1 1)
					(thickness 0.15)
				)
			)
		)
		(property "Manufacturer" "Murata"
			(at 225.058 -38.902 0)
			(layer "F.Fab")
			(hide yes)
			(effects
				(font
					(size 1 1)
					(thickness 0.15)
				)
			)
		)
		(property "Val" "22u"
			(at 225.058 -38.902 0)
			(layer "F.Fab")
			(hide yes)
			(effects
				(font
					(size 1 1)
					(thickness 0.15)
				)
			)
		)
		(property "Voltage" ""
			(at 225.058 -38.902 0)
			(layer "F.Fab")
			(hide yes)
			(effects
				(font
					(size 1 1)
					(thickness 0.15)
				)
			)
		)
		(sheetname "/Power/")
		(sheetfile "power.kicad_sch")
		(attr smd)
		(fp_rect
			(start -0.925 -0.47)
			(end 0.925 0.47)
			(stroke
				(width 0.05)
				(type default)
			)
			(fill no)
			(layer "F.CrtYd")
		)
		(fp_line
			(start 0.504 -0.25)
			(end 0.504 0.248)
			(stroke
				(width 0.15)
				(type solid)
			)
			(layer "F.Fab")
		)
		(fp_line
			(start -0.494 -0.25)
			(end 0.504 -0.25)
			(stroke
				(width 0.15)
				(type solid)
			)
			(layer "F.Fab")
		)
		(fp_line
			(start 0.504 0.248)
			(end -0.494 0.248)
			(stroke
				(width 0.15)
				(type solid)
			)
			(layer "F.Fab")
		)
		(fp_line
			(start -0.494 0.248)
			(end -0.494 -0.25)
			(stroke
				(width 0.15)
				(type solid)
			)
			(layer "F.Fab")
		)
		(pad "1" smd roundrect
			(at -0.48 0 90)
			(size 0.59 0.64)
			(layers "F.Cu" "F.Mask" "F.Paste")
			(roundrect_rratio 0.25)
			(net 1 "GND")
			(pintype "passive")
		)
		(pad "2" smd roundrect
			(at 0.48 0 90)
			(size 0.59 0.64)
			(layers "F.Cu" "F.Mask" "F.Paste")
			(roundrect_rratio 0.25)
			(net 10 "/Power/OUT_1V8")
			(pintype "passive")
		)
	)
	(footprint "antmicro-footprints:R_0402_1005Metric"
		(layer "F.Cu")
		(at 140.208 79.502 -45)
		(descr "Resistor SMD 0402")
		(tags "resistor SMD 0402")
		(property "Reference" "R51"
			(at -1.422699 0.8457 315)
			(unlocked yes)
			(layer "F.SilkS")
			(effects
				(font
					(size 0.7 0.7)
					(thickness 0.15)
				)
				(justify right bottom)
			)
		)
		(property "Value" "R_10k_0402"
			(at -1.011843 1.772046 135)
			(layer "F.Fab")
			(effects
				(font
					(size 0.7 0.7)
					(thickness 0.15)
				)
				(justify right bottom)
			)
		)
		(property "Datasheet" "https://www.bourns.com/docs/product-datasheets/cr.pdf"
			(at 0 0 315)
			(layer "F.Fab")
			(hide yes)
			(effects
				(font
					(size 1.27 1.27)
					(thickness 0.15)
				)
			)
		)
		(property "Description" "SMD Chip Resistor, 10 kohm, ± 1%, 62.5 mW, 0402 [1005 Metric], Thick Film, General Purpose"
			(at 0 0 315)
			(layer "F.Fab")
			(hide yes)
			(effects
				(font
					(size 1.27 1.27)
					(thickness 0.15)
				)
			)
		)
		(property "Author" "Antmicro"
			(at -15.150431 122.427625 0)
			(layer "F.Fab")
			(hide yes)
			(effects
				(font
					(size 1 1)
					(thickness 0.15)
				)
			)
		)
		(property "License" "Apache-2.0"
			(at -15.150431 122.427625 0)
			(layer "F.Fab")
			(hide yes)
			(effects
				(font
					(size 1 1)
					(thickness 0.15)
				)
			)
		)
		(property "MPN" "CR0402-FX-1002GLF"
			(at -15.150431 122.427625 0)
			(layer "F.Fab")
			(hide yes)
			(effects
				(font
					(size 1 1)
					(thickness 0.15)
				)
			)
		)
		(property "Manufacturer" "Bourns"
			(at -15.150431 122.427625 0)
			(layer "F.Fab")
			(hide yes)
			(effects
				(font
					(size 1 1)
					(thickness 0.15)
				)
			)
		)
		(property "Tolerance" "1%"
			(at -15.150431 122.427625 0)
			(layer "F.Fab")
			(hide yes)
			(effects
				(font
					(size 1 1)
					(thickness 0.15)
				)
			)
		)
		(property "Val" "10k"
			(at -15.150431 122.427625 0)
			(layer "F.Fab")
			(hide yes)
			(effects
				(font
					(size 1 1)
					(thickness 0.15)
				)
			)
		)
		(sheetname "/Deserializer/")
		(sheetfile "deserializer.kicad_sch")
		(attr smd)
		(fp_poly
			(pts
				(xy -0.925 -0.47) (xy 0.925 -0.47) (xy 0.925 0.47) (xy -0.925 0.47)
			)
			(stroke
				(width 0.05)
				(type default)
			)
			(fill no)
			(layer "F.CrtYd")
		)
		(fp_poly
			(pts
				(xy -0.5 -0.25) (xy 0.5 -0.25) (xy 0.5 0.25) (xy -0.5 0.25)
			)
			(stroke
				(width 0.15)
				(type solid)
			)
			(fill no)
			(layer "F.Fab")
		)
		(pad "1" smd roundrect
			(at -0.48 0 315)
			(size 0.59 0.64)
			(layers "F.Cu" "F.Mask" "F.Paste")
			(roundrect_rratio 0.25)
			(net 1 "GND")
			(pintype "passive")
		)
		(pad "2" smd roundrect
			(at 0.48 0 315)
			(size 0.59 0.64)
			(layers "F.Cu" "F.Mask" "F.Paste")
			(roundrect_rratio 0.25)
			(net 77 "/Deserializer/CFG1")
			(pintype "passive")
		)
	)
	(footprint "antmicro-footprints:R_0402_1005Metric"
		(layer "F.Cu")
		(at 185.674 54.864)
		(descr "Resistor SMD 0402")
		(tags "resistor SMD 0402")
		(property "Reference" "R42"
			(at -2.413 2.159 0)
			(layer "F.SilkS")
			(effects
				(font
					(size 0.7 0.7)
					(thickness 0.15)
				)
				(justify left bottom)
			)
		)
		(property "Value" "R_6k8_0402"
			(at -1.011843 1.772047 0)
			(layer "F.Fab")
			(effects
				(font
					(size 0.7 0.7)
					(thickness 0.15)
				)
				(justify left bottom)
			)
		)
		(property "Datasheet" "https://www.bourns.com/docs/product-datasheets/cr.pdf"
			(at 0 0 0)
			(layer "F.Fab")
			(hide yes)
			(effects
				(font
					(size 1.27 1.27)
					(thickness 0.15)
				)
			)
		)
		(property "Description" "SMD Chip Resistor, 6.8 kohm, ± 1%, 63 mW, 0402 [1005 Metric], Thick Film, General Purpose"
			(at 0 0 0)
			(layer "F.Fab")
			(hide yes)
			(effects
				(font
					(size 1.27 1.27)
					(thickness 0.15)
				)
			)
		)
		(property "Author" "Antmicro"
			(at 0 0 0)
			(layer "F.Fab")
			(hide yes)
			(effects
				(font
					(size 1 1)
					(thickness 0.15)
				)
			)
		)
		(property "License" "Apache-2.0"
			(at 0 0 0)
			(layer "F.Fab")
			(hide yes)
			(effects
				(font
					(size 1 1)
					(thickness 0.15)
				)
			)
		)
		(property "MPN" "CR0402-FX-6801GLF"
			(at 0 0 0)
			(layer "F.Fab")
			(hide yes)
			(effects
				(font
					(size 1 1)
					(thickness 0.15)
				)
			)
		)
		(property "Manufacturer" "Bourns"
			(at 0 0 0)
			(layer "F.Fab")
			(hide yes)
			(effects
				(font
					(size 1 1)
					(thickness 0.15)
				)
			)
		)
		(property "Tolerance" "1%"
			(at 0 0 0)
			(layer "F.Fab")
			(hide yes)
			(effects
				(font
					(size 1 1)
					(thickness 0.15)
				)
			)
		)
		(property "Val" "6k8"
			(at 0 0 0)
			(layer "F.Fab")
			(hide yes)
			(effects
				(font
					(size 1 1)
					(thickness 0.15)
				)
			)
		)
		(sheetname "/Power/")
		(sheetfile "power.kicad_sch")
		(attr smd)
		(fp_rect
			(start -0.925 -0.47)
			(end 0.925 0.47)
			(stroke
				(width 0.05)
				(type default)
			)
			(fill no)
			(layer "F.CrtYd")
		)
		(fp_rect
			(start -0.5 -0.25)
			(end 0.5 0.25)
			(stroke
				(width 0.15)
				(type solid)
			)
			(fill no)
			(layer "F.Fab")
		)
		(pad "1" smd roundrect
			(at -0.48 0)
			(size 0.59 0.64)
			(layers "F.Cu" "F.Mask" "F.Paste")
			(roundrect_rratio 0.25)
			(net 1 "GND")
			(pintype "passive")
		)
		(pad "2" smd roundrect
			(at 0.48 0)
			(size 0.59 0.64)
			(layers "F.Cu" "F.Mask" "F.Paste")
			(roundrect_rratio 0.25)
			(net 74 "/Power/FFC_5V_ISET")
			(pintype "passive")
		)
	)
	(footprint "antmicro-footprints:C_0402_1005Metric"
		(layer "F.Cu")
		(at 140.589 75.819 135)
		(descr "Capacitor SMD 0402")
		(tags "capacitor SMD 0402")
		(property "Reference" "C32"
			(at 6.272037 -0.486489 315)
			(unlocked yes)
			(layer "F.SilkS")
			(effects
				(font
					(size 0.7 0.7)
					(thickness 0.15)
				)
				(justify left bottom)
			)
		)
		(property "Value" "C_100n_0402"
			(at -21.596927 15.617213 135)
			(layer "F.Fab")
			(effects
				(font
					(size 0.7 0.7)
					(thickness 0.15)
				)
				(justify left bottom)
			)
		)
		(property "Datasheet" "https://www.murata.com/products/productdetail?partno=GRM155R61H104KE14%23"
			(at 0 0 135)
			(layer "F.Fab")
			(hide yes)
			(effects
				(font
					(size 1.27 1.27)
					(thickness 0.15)
				)
			)
		)
		(property "Description" "SMD Multilayer Ceramic Capacitor, 0.1 µF, 50 V, 0402 [1005 Metric], ± 10%, X5R, GRM Series"
			(at 0 0 135)
			(layer "F.Fab")
			(hide yes)
			(effects
				(font
					(size 1.27 1.27)
					(thickness 0.15)
				)
			)
		)
		(property "Author" "Antmicro"
			(at 293.612564 30.019694 0)
			(layer "F.Fab")
			(hide yes)
			(effects
				(font
					(size 1 1)
					(thickness 0.15)
				)
			)
		)
		(property "Dielectric" "X5R"
			(at 293.612564 30.019694 0)
			(layer "F.Fab")
			(hide yes)
			(effects
				(font
					(size 1 1)
					(thickness 0.15)
				)
			)
		)
		(property "License" "Apache-2.0"
			(at 293.612564 30.019694 0)
			(layer "F.Fab")
			(hide yes)
			(effects
				(font
					(size 1 1)
					(thickness 0.15)
				)
			)
		)
		(property "MPN" "GRM155R61H104KE14D"
			(at 293.612564 30.019694 0)
			(layer "F.Fab")
			(hide yes)
			(effects
				(font
					(size 1 1)
					(thickness 0.15)
				)
			)
		)
		(property "Manufacturer" "Murata"
			(at 293.612564 30.019694 0)
			(layer "F.Fab")
			(hide yes)
			(effects
				(font
					(size 1 1)
					(thickness 0.15)
				)
			)
		)
		(property "Val" "100n"
			(at 293.612564 30.019694 0)
			(layer "F.Fab")
			(hide yes)
			(effects
				(font
					(size 1 1)
					(thickness 0.15)
				)
			)
		)
		(property "Voltage" "50V"
			(at 293.612564 30.019694 0)
			(layer "F.Fab")
			(hide yes)
			(effects
				(font
					(size 1 1)
					(thickness 0.15)
				)
			)
		)
		(sheetname "/Deserializer/")
		(sheetfile "deserializer.kicad_sch")
		(attr smd)
		(fp_poly
			(pts
				(xy -0.925 -0.47) (xy 0.925 -0.47) (xy 0.925 0.47) (xy -0.925 0.47)
			)
			(stroke
				(width 0.05)
				(type default)
			)
			(fill no)
			(layer "F.CrtYd")
		)
		(fp_line
			(start 0.504 -0.25)
			(end 0.504 0.248)
			(stroke
				(width 0.15)
				(type solid)
			)
			(layer "F.Fab")
		)
		(fp_line
			(start 0.504 0.248)
			(end -0.494 0.248)
			(stroke
				(width 0.15)
				(type solid)
			)
			(layer "F.Fab")
		)
		(fp_line
			(start -0.494 -0.25)
			(end 0.504 -0.25)
			(stroke
				(width 0.15)
				(type solid)
			)
			(layer "F.Fab")
		)
		(fp_line
			(start -0.494 0.248)
			(end -0.494 -0.25)
			(stroke
				(width 0.15)
				(type solid)
			)
			(layer "F.Fab")
		)
		(pad "1" smd roundrect
			(at -0.48 0 135)
			(size 0.59 0.64)
			(layers "F.Cu" "F.Mask" "F.Paste")
			(roundrect_rratio 0.25)
			(net 18 "/Deserializer/SIOA_N")
			(pintype "passive")
		)
		(pad "2" smd roundrect
			(at 0.48 0 135)
			(size 0.59 0.64)
			(layers "F.Cu" "F.Mask" "F.Paste")
			(roundrect_rratio 0.25)
			(net 19 "Net-(C32-Pad2)")
			(pintype "passive")
		)
	)
	(footprint "antmicro-footprints:C_0402_1005Metric"
		(layer "F.Cu")
		(at 137.567 92.824 90)
		(descr "Capacitor SMD 0402")
		(tags "capacitor SMD 0402")
		(property "Reference" "C19"
			(at 1.13 0.355 90)
			(layer "F.SilkS")
			(effects
				(font
					(size 0.7 0.7)
					(thickness 0.15)
				)
				(justify left bottom)
			)
		)
		(property "Value" "C_100n_0402"
			(at -1.022927 2.155213 90)
			(layer "F.Fab")
			(effects
				(font
					(size 0.7 0.7)
					(thickness 0.15)
				)
				(justify left bottom)
			)
		)
		(property "Datasheet" "https://www.murata.com/products/productdetail?partno=GRM155R61H104KE14%23"
			(at 0 0 90)
			(layer "F.Fab")
			(hide yes)
			(effects
				(font
					(size 1.27 1.27)
					(thickness 0.15)
				)
			)
		)
		(property "Description" "SMD Multilayer Ceramic Capacitor, 0.1 µF, 50 V, 0402 [1005 Metric], ± 10%, X5R, GRM Series"
			(at 0 0 90)
			(layer "F.Fab")
			(hide yes)
			(effects
				(font
					(size 1.27 1.27)
					(thickness 0.15)
				)
			)
		)
		(property "Author" "Antmicro"
			(at 230.391 -44.743 0)
			(layer "F.Fab")
			(hide yes)
			(effects
				(font
					(size 1 1)
					(thickness 0.15)
				)
			)
		)
		(property "Dielectric" "X5R"
			(at 230.391 -44.743 0)
			(layer "F.Fab")
			(hide yes)
			(effects
				(font
					(size 1 1)
					(thickness 0.15)
				)
			)
		)
		(property "License" "Apache-2.0"
			(at 230.391 -44.743 0)
			(layer "F.Fab")
			(hide yes)
			(effects
				(font
					(size 1 1)
					(thickness 0.15)
				)
			)
		)
		(property "MPN" "GRM155R61H104KE14D"
			(at 230.391 -44.743 0)
			(layer "F.Fab")
			(hide yes)
			(effects
				(font
					(size 1 1)
					(thickness 0.15)
				)
			)
		)
		(property "Manufacturer" "Murata"
			(at 230.391 -44.743 0)
			(layer "F.Fab")
			(hide yes)
			(effects
				(font
					(size 1 1)
					(thickness 0.15)
				)
			)
		)
		(property "Val" "100n"
			(at 230.391 -44.743 0)
			(layer "F.Fab")
			(hide yes)
			(effects
				(font
					(size 1 1)
					(thickness 0.15)
				)
			)
		)
		(property "Voltage" "50V"
			(at 230.391 -44.743 0)
			(layer "F.Fab")
			(hide yes)
			(effects
				(font
					(size 1 1)
					(thickness 0.15)
				)
			)
		)
		(sheetname "/Power/")
		(sheetfile "power.kicad_sch")
		(attr smd)
		(fp_rect
			(start -0.925 -0.47)
			(end 0.925 0.47)
			(stroke
				(width 0.05)
				(type default)
			)
			(fill no)
			(layer "F.CrtYd")
		)
		(fp_line
			(start 0.504 -0.25)
			(end 0.504 0.248)
			(stroke
				(width 0.15)
				(type solid)
			)
			(layer "F.Fab")
		)
		(fp_line
			(start -0.494 -0.25)
			(end 0.504 -0.25)
			(stroke
				(width 0.15)
				(type solid)
			)
			(layer "F.Fab")
		)
		(fp_line
			(start 0.504 0.248)
			(end -0.494 0.248)
			(stroke
				(width 0.15)
				(type solid)
			)
			(layer "F.Fab")
		)
		(fp_line
			(start -0.494 0.248)
			(end -0.494 -0.25)
			(stroke
				(width 0.15)
				(type solid)
			)
			(layer "F.Fab")
		)
		(pad "1" smd roundrect
			(at -0.48 0 90)
			(size 0.59 0.64)
			(layers "F.Cu" "F.Mask" "F.Paste")
			(roundrect_rratio 0.25)
			(net 6 "Net-(U4-BST)")
			(pintype "passive")
		)
		(pad "2" smd roundrect
			(at 0.48 0 90)
			(size 0.59 0.64)
			(layers "F.Cu" "F.Mask" "F.Paste")
			(roundrect_rratio 0.25)
			(net 7 "/Power/SW_1V8")
			(pintype "passive")
		)
	)
	(footprint "antmicro-footprints:LED_0603_1608Metric_G"
		(layer "F.Cu")
		(at 158.496 96.1 90)
		(descr "LED SMD 0603 Green")
		(tags "LED SMD 0603 Green")
		(property "Reference" "D14"
			(at -1.916665 -40.079333 0)
			(layer "F.SilkS")
			(effects
				(font
					(size 0.7 0.7)
					(thickness 0.15)
				)
				(justify right bottom)
			)
		)
		(property "Value" "LED_G_0603_LTST-C190GKT"
			(at -0.001 1.599 90)
			(layer "F.Fab")
			(effects
				(font
					(size 0.7 0.7)
					(thickness 0.15)
				)
				(justify left bottom)
			)
		)
		(property "Datasheet" "https://media.digikey.com/pdf/Data%20Sheets/Lite-On%20PDFs/LTST-C190GKT.pdf"
			(at 0 0 90)
			(layer "F.Fab")
			(hide yes)
			(effects
				(font
					(size 1.27 1.27)
					(thickness 0.15)
				)
			)
		)
		(property "Description" "LED, Green, SMD, 0603, 20 mA, 2.1 V, 569 nm"
			(at 0 0 90)
			(layer "F.Fab")
			(hide yes)
			(effects
				(font
					(size 1.27 1.27)
					(thickness 0.15)
				)
			)
		)
		(property "Author" "Antmicro"
			(at 254.596 -62.396 0)
			(layer "F.Fab")
			(hide yes)
			(effects
				(font
					(size 1 1)
					(thickness 0.15)
				)
			)
		)
		(property "Color" "Green"
			(at 254.596 -62.396 0)
			(layer "F.Fab")
			(hide yes)
			(effects
				(font
					(size 1 1)
					(thickness 0.15)
				)
			)
		)
		(property "License" "Apache-2.0"
			(at 254.596 -62.396 0)
			(layer "F.Fab")
			(hide yes)
			(effects
				(font
					(size 1 1)
					(thickness 0.15)
				)
			)
		)
		(property "MPN" "LTST-C190GKT"
			(at 254.596 -62.396 0)
			(layer "F.Fab")
			(hide yes)
			(effects
				(font
					(size 1 1)
					(thickness 0.15)
				)
			)
		)
		(property "Manufacturer" "Lite-On"
			(at 254.596 -62.396 0)
			(layer "F.Fab")
			(hide yes)
			(effects
				(font
					(size 1 1)
					(thickness 0.15)
				)
			)
		)
		(property "VSD_class" "LED"
			(at 254.596 -62.396 0)
			(layer "F.Fab")
			(hide yes)
			(effects
				(font
					(size 1 1)
					(thickness 0.15)
				)
			)
		)
		(sheetname "/Connectors/")
		(sheetfile "connectors.kicad_sch")
		(attr smd)
		(fp_line
			(start 0.22 -0.35)
			(end -0.22 -0.35)
			(stroke
				(width 0.15)
				(type solid)
			)
			(layer "F.SilkS")
		)
		(fp_line
			(start -1.18 -0.319)
			(end -1.18 0.321)
			(stroke
				(width 0.15)
				(type solid)
			)
			(layer "F.SilkS")
		)
		(fp_line
			(start 0.105328 0.001008)
			(end 0.24 0.001)
			(stroke
				(width 0.1)
				(type solid)
			)
			(layer "F.SilkS")
		)
		(fp_line
			(start -0.094672 0.001008)
			(end 0.105328 -0.198992)
			(stroke
				(width 0.1)
				(type solid)
			)
			(layer "F.SilkS")
		)
		(fp_line
			(start -0.094672 0.001008)
			(end -0.24 0.001008)
			(stroke
				(width 0.1)
				(type solid)
			)
			(layer "F.SilkS")
		)
		(fp_line
			(start 0.105328 0.201008)
			(end 0.105328 -0.198992)
			(stroke
				(width 0.1)
				(type solid)
			)
			(layer "F.SilkS")
		)
		(fp_line
			(start 0.105328 0.201008)
			(end -0.094672 0.001008)
			(stroke
				(width 0.1)
				(type solid)
			)
			(layer "F.SilkS")
		)
		(fp_line
			(start -0.094672 0.201008)
			(end -0.094672 -0.198992)
			(stroke
				(width 0.1)
				(type solid)
			)
			(layer "F.SilkS")
		)
		(fp_line
			(start 0.22 0.35)
			(end -0.22 0.35)
			(stroke
				(width 0.15)
				(type solid)
			)
			(layer "F.SilkS")
		)
		(fp_rect
			(start 1.25 0.65)
			(end -1.25 -0.65)
			(stroke
				(width 0.05)
				(type solid)
			)
			(fill no)
			(layer "F.CrtYd")
		)
		(fp_line
			(start 0.201 -0.202)
			(end -0.101 0)
			(stroke
				(width 0.15)
				(type solid)
			)
			(layer "F.Fab")
		)
		(fp_line
			(start -0.199 -0.202)
			(end -0.199 0.1)
			(stroke
				(width 0.15)
				(type solid)
			)
			(layer "F.Fab")
		)
		(fp_line
			(start 0.599 0)
			(end 0.201 0)
			(stroke
				(width 0.15)
				(type solid)
			)
			(layer "F.Fab")
		)
		(fp_line
			(start 0.201 0)
			(end 0.201 -0.202)
			(stroke
				(width 0.15)
				(type solid)
			)
			(layer "F.Fab")
		)
		(fp_line
			(start -0.101 0)
			(end 0.201 0.2)
			(stroke
				(width 0.15)
				(type solid)
			)
			(layer "F.Fab")
		)
		(fp_line
			(start -0.199 0)
			(end -0.597 0)
			(stroke
				(width 0.15)
				(type solid)
			)
			(layer "F.Fab")
		)
		(fp_line
			(start 0.201 0.2)
			(end 0.201 0)
			(stroke
				(width 0.15)
				(type solid)
			)
			(layer "F.Fab")
		)
		(fp_line
			(start -0.199 0.2)
			(end -0.199 0.1)
			(stroke
				(width 0.15)
				(type solid)
			)
			(layer "F.Fab")
		)
		(fp_rect
			(start 0.848 0.4)
			(end -0.85 -0.402)
			(stroke
				(width 0.15)
				(type solid)
			)
			(fill no)
			(layer "F.Fab")
		)
		(pad "1" smd roundrect
			(at -0.7 0 270)
			(size 0.8 1)
			(layers "F.Cu" "F.Mask" "F.Paste")
			(roundrect_rratio 0.2)
			(net 111 "Net-(D14-C)")
			(pinfunction "C")
			(pintype "passive")
		)
		(pad "2" smd roundrect
			(at 0.7 0 270)
			(size 0.8 1)
			(layers "F.Cu" "F.Mask" "F.Paste")
			(roundrect_rratio 0.2)
			(net 110 "Net-(D14-A)")
			(pinfunction "A")
			(pintype "passive")
		)
	)
	(footprint "antmicro-footprints:R_0402_1005Metric"
		(layer "F.Cu")
		(at 154.178 74.676 45)
		(descr "Resistor SMD 0402")
		(tags "resistor SMD 0402")
		(property "Reference" "R46"
			(at 4.003639 0.193747 45)
			(layer "F.SilkS")
			(effects
				(font
					(size 0.7 0.7)
					(thickness 0.15)
				)
				(justify left bottom)
			)
		)
		(property "Value" "R_49R9_0402"
			(at -1.011843 1.772046 45)
			(layer "F.Fab")
			(effects
				(font
					(size 0.7 0.7)
					(thickness 0.15)
				)
				(justify left bottom)
			)
		)
		(property "Datasheet" "https://www.bourns.com/docs/product-datasheets/cr.pdf"
			(at 0 0 45)
			(layer "F.Fab")
			(hide yes)
			(effects
				(font
					(size 1.27 1.27)
					(thickness 0.15)
				)
			)
		)
		(property "Description" "SMD Chip Resistor, 49.9 ohm, ± 1%, 62.5 mW, 0402 [1005 Metric], Thick Film, General Purpose"
			(at 0 0 45)
			(layer "F.Fab")
			(hide yes)
			(effects
				(font
					(size 1.27 1.27)
					(thickness 0.15)
				)
			)
		)
		(property "Author" "Antmicro"
			(at 97.961596 -87.148215 0)
			(layer "F.Fab")
			(hide yes)
			(effects
				(font
					(size 1 1)
					(thickness 0.15)
				)
			)
		)
		(property "License" "Apache-2.0"
			(at 97.961596 -87.148215 0)
			(layer "F.Fab")
			(hide yes)
			(effects
				(font
					(size 1 1)
					(thickness 0.15)
				)
			)
		)
		(property "MPN" "CR0402-FX-49R9GLF"
			(at 97.961596 -87.148215 0)
			(layer "F.Fab")
			(hide yes)
			(effects
				(font
					(size 1 1)
					(thickness 0.15)
				)
			)
		)
		(property "Manufacturer" "Bourns"
			(at 97.961596 -87.148215 0)
			(layer "F.Fab")
			(hide yes)
			(effects
				(font
					(size 1 1)
					(thickness 0.15)
				)
			)
		)
		(property "Tolerance" "1%"
			(at 97.961596 -87.148215 0)
			(layer "F.Fab")
			(hide yes)
			(effects
				(font
					(size 1 1)
					(thickness 0.15)
				)
			)
		)
		(property "Val" "49R9"
			(at 97.961596 -87.148215 0)
			(layer "F.Fab")
			(hide yes)
			(effects
				(font
					(size 1 1)
					(thickness 0.15)
				)
			)
		)
		(sheetname "/Deserializer/")
		(sheetfile "deserializer.kicad_sch")
		(attr smd)
		(fp_poly
			(pts
				(xy -0.925 -0.47) (xy 0.925 -0.47) (xy 0.925 0.47) (xy -0.925 0.47)
			)
			(stroke
				(width 0.05)
				(type default)
			)
			(fill no)
			(layer "F.CrtYd")
		)
		(fp_poly
			(pts
				(xy -0.5 -0.25) (xy 0.5 -0.25) (xy 0.5 0.25) (xy -0.5 0.25)
			)
			(stroke
				(width 0.15)
				(type solid)
			)
			(fill no)
			(layer "F.Fab")
		)
		(pad "1" smd roundrect
			(at -0.48 0 45)
			(size 0.59 0.64)
			(layers "F.Cu" "F.Mask" "F.Paste")
			(roundrect_rratio 0.25)
			(net 25 "Net-(C35-Pad2)")
			(pintype "passive")
		)
		(pad "2" smd roundrect
			(at 0.48 0 45)
			(size 0.59 0.64)
			(layers "F.Cu" "F.Mask" "F.Paste")
			(roundrect_rratio 0.25)
			(net 1 "GND")
			(pintype "passive")
		)
	)
	(footprint "antmicro-footprints:R_0402_1005Metric"
		(layer "F.Cu")
		(at 181.356 68.144)
		(descr "Resistor SMD 0402")
		(tags "resistor SMD 0402")
		(property "Reference" "R10"
			(at -1.279 9.1482 0)
			(layer "F.SilkS")
			(effects
				(font
					(size 0.7 0.7)
					(thickness 0.15)
				)
				(justify left bottom)
			)
		)
		(property "Value" "R_100R_0402"
			(at -1.011843 1.772047 0)
			(layer "F.Fab")
			(effects
				(font
					(size 0.7 0.7)
					(thickness 0.15)
				)
				(justify left bottom)
			)
		)
		(property "Datasheet" "https://www.bourns.com/docs/product-datasheets/cr.pdf"
			(at 0 0 0)
			(layer "F.Fab")
			(hide yes)
			(effects
				(font
					(size 1.27 1.27)
					(thickness 0.15)
				)
			)
		)
		(property "Description" "SMD Chip Resistor, 100 ohm, ± 1%, 62.5 mW, 0402 [1005 Metric], Thick Film, General Purpose"
			(at 0 0 0)
			(layer "F.Fab")
			(hide yes)
			(effects
				(font
					(size 1.27 1.27)
					(thickness 0.15)
				)
			)
		)
		(property "Author" "Antmicro"
			(at 0 0 0)
			(layer "F.Fab")
			(hide yes)
			(effects
				(font
					(size 1 1)
					(thickness 0.15)
				)
			)
		)
		(property "License" "Apache-2.0"
			(at 0 0 0)
			(layer "F.Fab")
			(hide yes)
			(effects
				(font
					(size 1 1)
					(thickness 0.15)
				)
			)
		)
		(property "MPN" "CR0402-FX-1000GLF"
			(at 0 0 0)
			(layer "F.Fab")
			(hide yes)
			(effects
				(font
					(size 1 1)
					(thickness 0.15)
				)
			)
		)
		(property "Manufacturer" "Bourns"
			(at 0 0 0)
			(layer "F.Fab")
			(hide yes)
			(effects
				(font
					(size 1 1)
					(thickness 0.15)
				)
			)
		)
		(property "Tolerance" "1%"
			(at 0 0 0)
			(layer "F.Fab")
			(hide yes)
			(effects
				(font
					(size 1 1)
					(thickness 0.15)
				)
			)
		)
		(property "Val" "100R"
			(at 0 0 0)
			(layer "F.Fab")
			(hide yes)
			(effects
				(font
					(size 1 1)
					(thickness 0.15)
				)
			)
		)
		(sheetname "/Connectors/")
		(sheetfile "connectors.kicad_sch")
		(attr smd)
		(fp_rect
			(start -0.925 -0.47)
			(end 0.925 0.47)
			(stroke
				(width 0.05)
				(type default)
			)
			(fill no)
			(layer "F.CrtYd")
		)
		(fp_rect
			(start -0.5 -0.25)
			(end 0.5 0.25)
			(stroke
				(width 0.15)
				(type solid)
			)
			(fill no)
			(layer "F.Fab")
		)
		(pad "1" smd roundrect
			(at -0.48 0)
			(size 0.59 0.64)
			(layers "F.Cu" "F.Mask" "F.Paste")
			(roundrect_rratio 0.25)
			(net 66 "/Connectors/VSYNC_CAM1")
			(pintype "passive")
		)
		(pad "2" smd roundrect
			(at 0.48 0)
			(size 0.59 0.64)
			(layers "F.Cu" "F.Mask" "F.Paste")
			(roundrect_rratio 0.25)
			(net 37 "Net-(J6-Pad34)")
			(pintype "passive")
		)
	)
	(footprint "antmicro-footprints:R_0402_1005Metric"
		(layer "F.Cu")
		(at 181.356 66.04)
		(descr "Resistor SMD 0402")
		(tags "resistor SMD 0402")
		(property "Reference" "R13"
			(at -1.278 9.2202 0)
			(layer "F.SilkS")
			(effects
				(font
					(size 0.7 0.7)
					(thickness 0.15)
				)
				(justify left bottom)
			)
		)
		(property "Value" "R_100R_0402"
			(at -1.011843 1.772047 0)
			(layer "F.Fab")
			(effects
				(font
					(size 0.7 0.7)
					(thickness 0.15)
				)
				(justify left bottom)
			)
		)
		(property "Datasheet" "https://www.bourns.com/docs/product-datasheets/cr.pdf"
			(at 0 0 0)
			(layer "F.Fab")
			(hide yes)
			(effects
				(font
					(size 1.27 1.27)
					(thickness 0.15)
				)
			)
		)
		(property "Description" "SMD Chip Resistor, 100 ohm, ± 1%, 62.5 mW, 0402 [1005 Metric], Thick Film, General Purpose"
			(at 0 0 0)
			(layer "F.Fab")
			(hide yes)
			(effects
				(font
					(size 1.27 1.27)
					(thickness 0.15)
				)
			)
		)
		(property "Author" "Antmicro"
			(at 0 0 0)
			(layer "F.Fab")
			(hide yes)
			(effects
				(font
					(size 1 1)
					(thickness 0.15)
				)
			)
		)
		(property "License" "Apache-2.0"
			(at 0 0 0)
			(layer "F.Fab")
			(hide yes)
			(effects
				(font
					(size 1 1)
					(thickness 0.15)
				)
			)
		)
		(property "MPN" "CR0402-FX-1000GLF"
			(at 0 0 0)
			(layer "F.Fab")
			(hide yes)
			(effects
				(font
					(size 1 1)
					(thickness 0.15)
				)
			)
		)
		(property "Manufacturer" "Bourns"
			(at 0 0 0)
			(layer "F.Fab")
			(hide yes)
			(effects
				(font
					(size 1 1)
					(thickness 0.15)
				)
			)
		)
		(property "Tolerance" "1%"
			(at 0 0 0)
			(layer "F.Fab")
			(hide yes)
			(effects
				(font
					(size 1 1)
					(thickness 0.15)
				)
			)
		)
		(property "Val" "100R"
			(at 0 0 0)
			(layer "F.Fab")
			(hide yes)
			(effects
				(font
					(size 1 1)
					(thickness 0.15)
				)
			)
		)
		(sheetname "/Connectors/")
		(sheetfile "connectors.kicad_sch")
		(attr smd)
		(fp_rect
			(start -0.925 -0.47)
			(end 0.925 0.47)
			(stroke
				(width 0.05)
				(type default)
			)
			(fill no)
			(layer "F.CrtYd")
		)
		(fp_rect
			(start -0.5 -0.25)
			(end 0.5 0.25)
			(stroke
				(width 0.15)
				(type solid)
			)
			(fill no)
			(layer "F.Fab")
		)
		(pad "1" smd roundrect
			(at -0.48 0)
			(size 0.59 0.64)
			(layers "F.Cu" "F.Mask" "F.Paste")
			(roundrect_rratio 0.25)
			(net 45 "/Connectors/SCL_CAM")
			(pintype "passive")
		)
		(pad "2" smd roundrect
			(at 0.48 0)
			(size 0.59 0.64)
			(layers "F.Cu" "F.Mask" "F.Paste")
			(roundrect_rratio 0.25)
			(net 120 "/Connectors/SCL_CAM0")
			(pintype "passive")
		)
	)
	(footprint "antmicro-footprints:Conn_FAKRA_7-2287906-0"
		(layer "F.Cu")
		(at 129.286 38.348)
		(descr "Connector FAKRA, 5 pins")
		(property "Reference" "J2"
			(at 5.054 5.3 0)
			(layer "F.SilkS")
			(effects
				(font
					(size 0.7 0.7)
					(thickness 0.15)
				)
				(justify left bottom)
			)
		)
		(property "Value" "Conn_FAKRA_59S2AQ-40MT5-Z_1"
			(at -6.55 15.019 0)
			(layer "F.Fab")
			(effects
				(font
					(size 0.7 0.7)
					(thickness 0.15)
				)
				(justify left bottom)
			)
		)
		(property ki_fp_filters "*BNC* *SMA* *SMB* *SMC* *Cinch*")
		(sheetname "/Connectors/")
		(sheetfile "connectors.kicad_sch")
		(attr through_hole)
		(fp_line
			(start -4.572 0.94)
			(end -4.572 13.919)
			(stroke
				(width 0.15)
				(type solid)
			)
			(layer "F.SilkS")
		)
		(fp_line
			(start -4.572 13.919)
			(end 4.572 13.919)
			(stroke
				(width 0.15)
				(type solid)
			)
			(layer "F.SilkS")
		)
		(fp_line
			(start 4.572 0.94)
			(end -4.572 0.94)
			(stroke
				(width 0.15)
				(type solid)
			)
			(layer "F.SilkS")
		)
		(fp_line
			(start 4.572 13.919)
			(end 4.572 0.94)
			(stroke
				(width 0.15)
				(type solid)
			)
			(layer "F.SilkS")
		)
		(fp_rect
			(start -5.14 -12.64)
			(end 5.131 14.164)
			(stroke
				(width 0.05)
				(type solid)
			)
			(fill no)
			(layer "F.CrtYd")
		)
		(fp_text user "${REFERENCE}"
			(at -6.55 18.619 0)
			(layer "F.Fab")
			(effects
				(font
					(size 0.7 0.7)
					(thickness 0.15)
				)
				(justify left bottom)
			)
		)
		(fp_text user "License: Apache-2.0"
			(at -6.55 16.219 0)
			(layer "F.Fab")
			(effects
				(font
					(size 0.7 0.7)
					(thickness 0.15)
				)
				(justify left bottom)
			)
		)
		(fp_text user "Author: Antmicro"
			(at -6.55 17.419 0)
			(layer "F.Fab")
			(effects
				(font
					(size 0.7 0.7)
					(thickness 0.15)
				)
				(justify left bottom)
			)
		)
		(pad "1" smd roundrect
			(at 0 3.62 270)
			(size 4.79 1.9)
			(layers "F.Cu" "F.Mask" "F.Paste")
			(roundrect_rratio 0.25)
			(net 114 "/Connectors/PoCA")
			(pinfunction "1")
			(pintype "passive")
		)
		(pad "2" thru_hole circle
			(at -3 3.315 270)
			(size 1.8 1.8)
			(drill 1.45)
			(layers "*.Cu" "*.Mask")
			(remove_unused_layers no)
			(net 1 "GND")
			(pinfunction "2")
			(pintype "passive")
		)
		(pad "2" smd roundrect
			(at -2.9975 3.7175 270)
			(size 4.985 1.8)
			(layers "F.Cu" "F.Mask" "F.Paste")
			(roundrect_rratio 0.25)
			(net 1 "GND")
			(pinfunction "2")
			(pintype "passive")
		)
		(pad "3" thru_hole circle
			(at -3 10.315 270)
			(size 1.8 1.8)
			(drill 1.45)
			(layers "*.Cu" "*.Mask")
			(remove_unused_layers no)
			(net 1 "GND")
			(pinfunction "3")
			(pintype "passive")
		)
		(pad "3" smd roundrect
			(at -3 10.815 270)
			(size 5.6 1.8)
			(layers "F.Cu" "F.Mask" "F.Paste")
			(roundrect_rratio 0.25)
			(net 1 "GND")
			(pinfunction "3")
			(pintype "passive")
		)
		(pad "4" thru_hole circle
			(at 3 10.315 270)
			(size 1.8 1.8)
			(drill 1.45)
			(layers "*.Cu" "*.Mask")
			(remove_unused_layers no)
			(net 1 "GND")
			(pinfunction "4")
			(pintype "passive")
		)
		(pad "4" smd roundrect
			(at 3 10.815 270)
			(size 5.6 1.8)
			(layers "F.Cu" "F.Mask" "F.Paste")
			(roundrect_rratio 0.25)
			(net 1 "GND")
			(pinfunction "4")
			(pintype "passive")
		)
		(pad "5" thru_hole circle
			(at 3 3.315 270)
			(size 1.8 1.8)
			(drill 1.45)
			(layers "*.Cu" "*.Mask")
			(remove_unused_layers no)
			(net 1 "GND")
			(pinfunction "5")
			(pintype "passive")
		)
		(pad "5" smd roundrect
			(at 3 3.72 270)
			(size 4.99 1.8)
			(layers "F.Cu" "F.Mask" "F.Paste")
			(roundrect_rratio 0.25)
			(net 1 "GND")
			(pinfunction "5")
			(pintype "passive")
		)
	)
	(footprint "antmicro-footprints:C_0402_1005Metric"
		(layer "F.Cu")
		(at 149.733 71.6788 90)
		(descr "Capacitor SMD 0402")
		(tags "capacitor SMD 0402")
		(property "Reference" "C56"
			(at 1.0668 0.381 90)
			(layer "F.SilkS")
			(effects
				(font
					(size 0.7 0.7)
					(thickness 0.15)
				)
				(justify left bottom)
			)
		)
		(property "Value" "C_33p_0402"
			(at -1.022927 2.155213 90)
			(layer "F.Fab")
			(effects
				(font
					(size 0.7 0.7)
					(thickness 0.15)
				)
				(justify left bottom)
			)
		)
		(property "Datasheet" "https://spicat.kyocera-avx.com/product/mlcc/chartview/04025A330FAT2A/"
			(at 0 0 90)
			(layer "F.Fab")
			(hide yes)
			(effects
				(font
					(size 1.27 1.27)
					(thickness 0.15)
				)
			)
		)
		(property "Description" "SMD Multilayer Ceramic Capacitor, 33 pF, 50 V, 0402 [1005 Metric], ± 5%, C0G / NP0, MC"
			(at 0 0 90)
			(layer "F.Fab")
			(hide yes)
			(effects
				(font
					(size 1.27 1.27)
					(thickness 0.15)
				)
			)
		)
		(property "Author" "Antmicro"
			(at 221.4118 -78.0542 0)
			(layer "F.Fab")
			(hide yes)
			(effects
				(font
					(size 1 1)
					(thickness 0.15)
				)
			)
		)
		(property "Dielectric" ""
			(at 221.4118 -78.0542 0)
			(layer "F.Fab")
			(hide yes)
			(effects
				(font
					(size 1 1)
					(thickness 0.15)
				)
			)
		)
		(property "License" "Apache-2.0"
			(at 221.4118 -78.0542 0)
			(layer "F.Fab")
			(hide yes)
			(effects
				(font
					(size 1 1)
					(thickness 0.15)
				)
			)
		)
		(property "MPN" "04025A330FAT2A"
			(at 221.4118 -78.0542 0)
			(layer "F.Fab")
			(hide yes)
			(effects
				(font
					(size 1 1)
					(thickness 0.15)
				)
			)
		)
		(property "Manufacturer" "KYOCERA AVX"
			(at 221.4118 -78.0542 0)
			(layer "F.Fab")
			(hide yes)
			(effects
				(font
					(size 1 1)
					(thickness 0.15)
				)
			)
		)
		(property "Val" "33p"
			(at 221.4118 -78.0542 0)
			(layer "F.Fab")
			(hide yes)
			(effects
				(font
					(size 1 1)
					(thickness 0.15)
				)
			)
		)
		(property "Voltage" ""
			(at 221.4118 -78.0542 0)
			(layer "F.Fab")
			(hide yes)
			(effects
				(font
					(size 1 1)
					(thickness 0.15)
				)
			)
		)
		(sheetname "/Deserializer/")
		(sheetfile "deserializer.kicad_sch")
		(attr smd)
		(fp_rect
			(start -0.925 -0.47)
			(end 0.925 0.47)
			(stroke
				(width 0.05)
				(type default)
			)
			(fill no)
			(layer "F.CrtYd")
		)
		(fp_line
			(start 0.504 -0.25)
			(end 0.504 0.248)
			(stroke
				(width 0.15)
				(type solid)
			)
			(layer "F.Fab")
		)
		(fp_line
			(start -0.494 -0.25)
			(end 0.504 -0.25)
			(stroke
				(width 0.15)
				(type solid)
			)
			(layer "F.Fab")
		)
		(fp_line
			(start 0.504 0.248)
			(end -0.494 0.248)
			(stroke
				(width 0.15)
				(type solid)
			)
			(layer "F.Fab")
		)
		(fp_line
			(start -0.494 0.248)
			(end -0.494 -0.25)
			(stroke
				(width 0.15)
				(type solid)
			)
			(layer "F.Fab")
		)
		(pad "1" smd roundrect
			(at -0.48 0 90)
			(size 0.59 0.64)
			(layers "F.Cu" "F.Mask" "F.Paste")
			(roundrect_rratio 0.25)
			(net 1 "GND")
			(pintype "passive")
		)
		(pad "2" smd roundrect
			(at 0.48 0 90)
			(size 0.59 0.64)
			(layers "F.Cu" "F.Mask" "F.Paste")
			(roundrect_rratio 0.25)
			(net 12 "/Deserializer/X1")
			(pintype "passive")
		)
	)
	(footprint "antmicro-footprints:R_0402_1005Metric"
		(layer "F.Cu")
		(at 184.077 54.7648 90)
		(descr "Resistor SMD 0402")
		(tags "resistor SMD 0402")
		(property "Reference" "R34"
			(at -1.293 -0.689 90)
			(layer "F.SilkS")
			(effects
				(font
					(size 0.7 0.7)
					(thickness 0.15)
				)
				(justify left bottom)
			)
		)
		(property "Value" "R_10k_0402"
			(at -1.011843 1.772047 90)
			(layer "F.Fab")
			(effects
				(font
					(size 0.7 0.7)
					(thickness 0.15)
				)
				(justify left bottom)
			)
		)
		(property "Datasheet" "https://www.bourns.com/docs/product-datasheets/cr.pdf"
			(at 0 0 90)
			(layer "F.Fab")
			(hide yes)
			(effects
				(font
					(size 1.27 1.27)
					(thickness 0.15)
				)
			)
		)
		(property "Description" "SMD Chip Resistor, 10 kohm, ± 1%, 62.5 mW, 0402 [1005 Metric], Thick Film, General Purpose"
			(at 0 0 90)
			(layer "F.Fab")
			(hide yes)
			(effects
				(font
					(size 1.27 1.27)
					(thickness 0.15)
				)
			)
		)
		(property "Author" "Antmicro"
			(at 238.8418 -129.3122 0)
			(layer "F.Fab")
			(hide yes)
			(effects
				(font
					(size 1 1)
					(thickness 0.15)
				)
			)
		)
		(property "License" "Apache-2.0"
			(at 238.8418 -129.3122 0)
			(layer "F.Fab")
			(hide yes)
			(effects
				(font
					(size 1 1)
					(thickness 0.15)
				)
			)
		)
		(property "MPN" "CR0402-FX-1002GLF"
			(at 238.8418 -129.3122 0)
			(layer "F.Fab")
			(hide yes)
			(effects
				(font
					(size 1 1)
					(thickness 0.15)
				)
			)
		)
		(property "Manufacturer" "Bourns"
			(at 238.8418 -129.3122 0)
			(layer "F.Fab")
			(hide yes)
			(effects
				(font
					(size 1 1)
					(thickness 0.15)
				)
			)
		)
		(property "Tolerance" "1%"
			(at 238.8418 -129.3122 0)
			(layer "F.Fab")
			(hide yes)
			(effects
				(font
					(size 1 1)
					(thickness 0.15)
				)
			)
		)
		(property "Val" "10k"
			(at 238.8418 -129.3122 0)
			(layer "F.Fab")
			(hide yes)
			(effects
				(font
					(size 1 1)
					(thickness 0.15)
				)
			)
		)
		(sheetname "/Power/")
		(sheetfile "power.kicad_sch")
		(attr smd exclude_from_pos_files exclude_from_bom dnp)
		(fp_rect
			(start -0.925 -0.47)
			(end 0.925 0.47)
			(stroke
				(width 0.05)
				(type default)
			)
			(fill no)
			(layer "F.CrtYd")
		)
		(fp_rect
			(start -0.5 -0.25)
			(end 0.5 0.25)
			(stroke
				(width 0.15)
				(type solid)
			)
			(fill no)
			(layer "F.Fab")
		)
		(pad "1" smd roundrect
			(at -0.48 0 90)
			(size 0.59 0.64)
			(layers "F.Cu" "F.Mask" "F.Paste")
			(roundrect_rratio 0.25)
			(net 1 "GND")
			(pintype "passive")
		)
		(pad "2" smd roundrect
			(at 0.48 0 90)
			(size 0.59 0.64)
			(layers "F.Cu" "F.Mask" "F.Paste")
			(roundrect_rratio 0.25)
			(net 63 "/Power/FFC_5V_EN")
			(pintype "passive")
		)
	)
	(footprint "antmicro-footprints:R_0402_1005Metric"
		(layer "F.Cu")
		(at 119.149 85.344 180)
		(descr "Resistor SMD 0402")
		(tags "resistor SMD 0402")
		(property "Reference" "R31"
			(at 1.039 -0.508 0)
			(layer "F.SilkS")
			(effects
				(font
					(size 0.7 0.7)
					(thickness 0.15)
				)
				(justify right bottom)
			)
		)
		(property "Value" "R_10k_0402"
			(at -1.011843 1.772047 0)
			(layer "F.Fab")
			(effects
				(font
					(size 0.7 0.7)
					(thickness 0.15)
				)
				(justify right bottom)
			)
		)
		(property "Datasheet" "https://www.bourns.com/docs/product-datasheets/cr.pdf"
			(at 0 0 180)
			(layer "F.Fab")
			(hide yes)
			(effects
				(font
					(size 1.27 1.27)
					(thickness 0.15)
				)
			)
		)
		(property "Description" "SMD Chip Resistor, 10 kohm, ± 1%, 62.5 mW, 0402 [1005 Metric], Thick Film, General Purpose"
			(at 0 0 180)
			(layer "F.Fab")
			(hide yes)
			(effects
				(font
					(size 1.27 1.27)
					(thickness 0.15)
				)
			)
		)
		(property "Author" "Antmicro"
			(at 238.298 170.688 0)
			(layer "F.Fab")
			(hide yes)
			(effects
				(font
					(size 1 1)
					(thickness 0.15)
				)
			)
		)
		(property "License" "Apache-2.0"
			(at 238.298 170.688 0)
			(layer "F.Fab")
			(hide yes)
			(effects
				(font
					(size 1 1)
					(thickness 0.15)
				)
			)
		)
		(property "MPN" "CR0402-FX-1002GLF"
			(at 238.298 170.688 0)
			(layer "F.Fab")
			(hide yes)
			(effects
				(font
					(size 1 1)
					(thickness 0.15)
				)
			)
		)
		(property "Manufacturer" "Bourns"
			(at 238.298 170.688 0)
			(layer "F.Fab")
			(hide yes)
			(effects
				(font
					(size 1 1)
					(thickness 0.15)
				)
			)
		)
		(property "Tolerance" "1%"
			(at 238.298 170.688 0)
			(layer "F.Fab")
			(hide yes)
			(effects
				(font
					(size 1 1)
					(thickness 0.15)
				)
			)
		)
		(property "Val" "10k"
			(at 238.298 170.688 0)
			(layer "F.Fab")
			(hide yes)
			(effects
				(font
					(size 1 1)
					(thickness 0.15)
				)
			)
		)
		(sheetname "/Power/")
		(sheetfile "power.kicad_sch")
		(attr smd)
		(fp_rect
			(start -0.925 -0.47)
			(end 0.925 0.47)
			(stroke
				(width 0.05)
				(type default)
			)
			(fill no)
			(layer "F.CrtYd")
		)
		(fp_rect
			(start -0.5 -0.25)
			(end 0.5 0.25)
			(stroke
				(width 0.15)
				(type solid)
			)
			(fill no)
			(layer "F.Fab")
		)
		(pad "1" smd roundrect
			(at -0.48 0 180)
			(size 0.59 0.64)
			(layers "F.Cu" "F.Mask" "F.Paste")
			(roundrect_rratio 0.25)
			(net 68 "/Power/EN_1V2")
			(pintype "passive")
		)
		(pad "2" smd roundrect
			(at 0.48 0 180)
			(size 0.59 0.64)
			(layers "F.Cu" "F.Mask" "F.Paste")
			(roundrect_rratio 0.25)
			(net 4 "+12V")
			(pintype "passive")
		)
	)
	(footprint "antmicro-footprints:C_0402_1005Metric"
		(layer "F.Cu")
		(at 157.154 66.548 90)
		(descr "Capacitor SMD 0402")
		(tags "capacitor SMD 0402")
		(property "Reference" "C9"
			(at -1.397 -0.563 90)
			(layer "F.SilkS")
			(effects
				(font
					(size 0.7 0.7)
					(thickness 0.15)
				)
				(justify left bottom)
			)
		)
		(property "Value" "C_100n_0402"
			(at -1.022927 2.155213 90)
			(layer "F.Fab")
			(effects
				(font
					(size 0.7 0.7)
					(thickness 0.15)
				)
				(justify left bottom)
			)
		)
		(property "Datasheet" "https://www.murata.com/products/productdetail?partno=GRM155R61H104KE14%23"
			(at 0 0 90)
			(layer "F.Fab")
			(hide yes)
			(effects
				(font
					(size 1.27 1.27)
					(thickness 0.15)
				)
			)
		)
		(property "Description" "SMD Multilayer Ceramic Capacitor, 0.1 µF, 50 V, 0402 [1005 Metric], ± 10%, X5R, GRM Series"
			(at 0 0 90)
			(layer "F.Fab")
			(hide yes)
			(effects
				(font
					(size 1.27 1.27)
					(thickness 0.15)
				)
			)
		)
		(property "Author" "Antmicro"
			(at 223.702 -90.606 0)
			(layer "F.Fab")
			(hide yes)
			(effects
				(font
					(size 1 1)
					(thickness 0.15)
				)
			)
		)
		(property "Dielectric" "X5R"
			(at 223.702 -90.606 0)
			(layer "F.Fab")
			(hide yes)
			(effects
				(font
					(size 1 1)
					(thickness 0.15)
				)
			)
		)
		(property "License" "Apache-2.0"
			(at 223.702 -90.606 0)
			(layer "F.Fab")
			(hide yes)
			(effects
				(font
					(size 1 1)
					(thickness 0.15)
				)
			)
		)
		(property "MPN" "GRM155R61H104KE14D"
			(at 223.702 -90.606 0)
			(layer "F.Fab")
			(hide yes)
			(effects
				(font
					(size 1 1)
					(thickness 0.15)
				)
			)
		)
		(property "Manufacturer" "Murata"
			(at 223.702 -90.606 0)
			(layer "F.Fab")
			(hide yes)
			(effects
				(font
					(size 1 1)
					(thickness 0.15)
				)
			)
		)
		(property "Val" "100n"
			(at 223.702 -90.606 0)
			(layer "F.Fab")
			(hide yes)
			(effects
				(font
					(size 1 1)
					(thickness 0.15)
				)
			)
		)
		(property "Voltage" "50V"
			(at 223.702 -90.606 0)
			(layer "F.Fab")
			(hide yes)
			(effects
				(font
					(size 1 1)
					(thickness 0.15)
				)
			)
		)
		(sheetname "/Power/")
		(sheetfile "power.kicad_sch")
		(attr smd)
		(fp_rect
			(start -0.925 -0.47)
			(end 0.925 0.47)
			(stroke
				(width 0.05)
				(type default)
			)
			(fill no)
			(layer "F.CrtYd")
		)
		(fp_line
			(start 0.504 -0.25)
			(end 0.504 0.248)
			(stroke
				(width 0.15)
				(type solid)
			)
			(layer "F.Fab")
		)
		(fp_line
			(start -0.494 -0.25)
			(end 0.504 -0.25)
			(stroke
				(width 0.15)
				(type solid)
			)
			(layer "F.Fab")
		)
		(fp_line
			(start 0.504 0.248)
			(end -0.494 0.248)
			(stroke
				(width 0.15)
				(type solid)
			)
			(layer "F.Fab")
		)
		(fp_line
			(start -0.494 0.248)
			(end -0.494 -0.25)
			(stroke
				(width 0.15)
				(type solid)
			)
			(layer "F.Fab")
		)
		(pad "1" smd roundrect
			(at -0.48 0 90)
			(size 0.59 0.64)
			(layers "F.Cu" "F.Mask" "F.Paste")
			(roundrect_rratio 0.25)
			(net 1 "GND")
			(pintype "passive")
		)
		(pad "2" smd roundrect
			(at 0.48 0 90)
			(size 0.59 0.64)
			(layers "F.Cu" "F.Mask" "F.Paste")
			(roundrect_rratio 0.25)
			(net 4 "+12V")
			(pintype "passive")
		)
	)
	(footprint "antmicro-footprints:R_0402_1005Metric"
		(layer "F.Cu")
		(at 162.052 61.976 90)
		(descr "Resistor SMD 0402")
		(tags "resistor SMD 0402")
		(property "Reference" "R22"
			(at -1.122484 1.27 90)
			(layer "F.SilkS")
			(effects
				(font
					(size 0.7 0.7)
					(thickness 0.15)
				)
				(justify left bottom)
			)
		)
		(property "Value" "R_5k1_0402"
			(at -1.011843 1.772047 90)
			(layer "F.Fab")
			(effects
				(font
					(size 0.7 0.7)
					(thickness 0.15)
				)
				(justify left bottom)
			)
		)
		(property "Datasheet" "https://www.bourns.com/docs/product-datasheets/cr.pdf"
			(at 0 0 90)
			(layer "F.Fab")
			(hide yes)
			(effects
				(font
					(size 1.27 1.27)
					(thickness 0.15)
				)
			)
		)
		(property "Description" "SMD Chip Resistor, 5.1 kohm, ± 1%, 63 mW, 0402 [1005 Metric], Thick Film, General Purpose"
			(at 0 0 90)
			(layer "F.Fab")
			(hide yes)
			(effects
				(font
					(size 1.27 1.27)
					(thickness 0.15)
				)
			)
		)
		(property "Author" "Antmicro"
			(at 224.028 -100.076 0)
			(layer "F.Fab")
			(hide yes)
			(effects
				(font
					(size 1 1)
					(thickness 0.15)
				)
			)
		)
		(property "License" "Apache-2.0"
			(at 224.028 -100.076 0)
			(layer "F.Fab")
			(hide yes)
			(effects
				(font
					(size 1 1)
					(thickness 0.15)
				)
			)
		)
		(property "MPN" "CR0402-FX-5101GLF"
			(at 224.028 -100.076 0)
			(layer "F.Fab")
			(hide yes)
			(effects
				(font
					(size 1 1)
					(thickness 0.15)
				)
			)
		)
		(property "Manufacturer" "Bourns"
			(at 224.028 -100.076 0)
			(layer "F.Fab")
			(hide yes)
			(effects
				(font
					(size 1 1)
					(thickness 0.15)
				)
			)
		)
		(property "Tolerance" "1%"
			(at 224.028 -100.076 0)
			(layer "F.Fab")
			(hide yes)
			(effects
				(font
					(size 1 1)
					(thickness 0.15)
				)
			)
		)
		(property "Val" "5k1"
			(at 224.028 -100.076 0)
			(layer "F.Fab")
			(hide yes)
			(effects
				(font
					(size 1 1)
					(thickness 0.15)
				)
			)
		)
		(sheetname "/Power/")
		(sheetfile "power.kicad_sch")
		(attr smd)
		(fp_rect
			(start -0.925 -0.47)
			(end 0.925 0.47)
			(stroke
				(width 0.05)
				(type default)
			)
			(fill no)
			(layer "F.CrtYd")
		)
		(fp_rect
			(start -0.5 -0.25)
			(end 0.5 0.25)
			(stroke
				(width 0.15)
				(type solid)
			)
			(fill no)
			(layer "F.Fab")
		)
		(pad "1" smd roundrect
			(at -0.48 0 90)
			(size 0.59 0.64)
			(layers "F.Cu" "F.Mask" "F.Paste")
			(roundrect_rratio 0.25)
			(net 4 "+12V")
			(pintype "passive")
		)
		(pad "2" smd roundrect
			(at 0.48 0 90)
			(size 0.59 0.64)
			(layers "F.Cu" "F.Mask" "F.Paste")
			(roundrect_rratio 0.25)
			(net 54 "Net-(L4-Pad2)")
			(pintype "passive")
		)
	)
	(footprint "antmicro-footprints:R_0402_1005Metric"
		(layer "F.Cu")
		(at 178.482 64.108 90)
		(descr "Resistor SMD 0402")
		(tags "resistor SMD 0402")
		(property "Reference" "R63"
			(at -10.568 0.588 90)
			(layer "F.SilkS")
			(effects
				(font
					(size 0.7 0.7)
					(thickness 0.15)
				)
				(justify left bottom)
			)
		)
		(property "Value" "R_2k2_0402"
			(at -1.011843 1.772047 90)
			(layer "F.Fab")
			(effects
				(font
					(size 0.7 0.7)
					(thickness 0.15)
				)
				(justify left bottom)
			)
		)
		(property "Datasheet" "https://www.bourns.com/docs/product-datasheets/cr.pdf"
			(at 0 0 90)
			(layer "F.Fab")
			(hide yes)
			(effects
				(font
					(size 1.27 1.27)
					(thickness 0.15)
				)
			)
		)
		(property "Description" "SMD Chip Resistor, 2.2 kohm, ± 1%, 62.5 mW, 0402 [1005 Metric], Thick Film, General Purpose"
			(at 0 0 90)
			(layer "F.Fab")
			(hide yes)
			(effects
				(font
					(size 1.27 1.27)
					(thickness 0.15)
				)
			)
		)
		(property "Author" "Antmicro"
			(at 242.59 -114.374 0)
			(layer "F.Fab")
			(hide yes)
			(effects
				(font
					(size 1 1)
					(thickness 0.15)
				)
			)
		)
		(property "License" "Apache-2.0"
			(at 242.59 -114.374 0)
			(layer "F.Fab")
			(hide yes)
			(effects
				(font
					(size 1 1)
					(thickness 0.15)
				)
			)
		)
		(property "MPN" "CR0402-FX-2201GLF"
			(at 242.59 -114.374 0)
			(layer "F.Fab")
			(hide yes)
			(effects
				(font
					(size 1 1)
					(thickness 0.15)
				)
			)
		)
		(property "Manufacturer" "Bourns"
			(at 242.59 -114.374 0)
			(layer "F.Fab")
			(hide yes)
			(effects
				(font
					(size 1 1)
					(thickness 0.15)
				)
			)
		)
		(property "Tolerance" "1%"
			(at 242.59 -114.374 0)
			(layer "F.Fab")
			(hide yes)
			(effects
				(font
					(size 1 1)
					(thickness 0.15)
				)
			)
		)
		(property "Val" "2k2"
			(at 242.59 -114.374 0)
			(layer "F.Fab")
			(hide yes)
			(effects
				(font
					(size 1 1)
					(thickness 0.15)
				)
			)
		)
		(sheetname "/Connectors/")
		(sheetfile "connectors.kicad_sch")
		(attr smd exclude_from_pos_files exclude_from_bom dnp)
		(fp_rect
			(start -0.925 -0.47)
			(end 0.925 0.47)
			(stroke
				(width 0.05)
				(type default)
			)
			(fill no)
			(layer "F.CrtYd")
		)
		(fp_rect
			(start -0.5 -0.25)
			(end 0.5 0.25)
			(stroke
				(width 0.15)
				(type solid)
			)
			(fill no)
			(layer "F.Fab")
		)
		(pad "1" smd roundrect
			(at -0.48 0 90)
			(size 0.59 0.64)
			(layers "F.Cu" "F.Mask" "F.Paste")
			(roundrect_rratio 0.25)
			(net 44 "/Connectors/SDA_CAM")
			(pintype "passive")
		)
		(pad "2" smd roundrect
			(at 0.48 0 90)
			(size 0.59 0.64)
			(layers "F.Cu" "F.Mask" "F.Paste")
			(roundrect_rratio 0.25)
			(net 50 "/Connectors/FFC_3V3")
			(pintype "passive")
		)
	)
	(footprint "antmicro-footprints:R_0603_1608Metric"
		(layer "F.Cu")
		(at 126.674 88.242 -90)
		(descr "Resistor SMD 0603")
		(tags "resistor SMD 0603")
		(property "Reference" "R41"
			(at -1.016 -1.524 90)
			(layer "F.SilkS")
			(effects
				(font
					(size 0.7 0.7)
					(thickness 0.15)
				)
				(justify right bottom)
			)
		)
		(property "Value" "R_0R_22.4A_0603"
			(at 0 1.6 90)
			(layer "F.Fab")
			(effects
				(font
					(size 0.7 0.7)
					(thickness 0.15)
				)
				(justify right bottom)
			)
		)
		(property "Datasheet" "https://fscdn.rohm.com/en/products/databook/datasheet/passive/resistor/chip_resistor/pmr-jpw-e.pdf"
			(at 0 0 270)
			(layer "F.Fab")
			(hide yes)
			(effects
				(font
					(size 1.27 1.27)
					(thickness 0.15)
				)
			)
		)
		(property "Description" "SMD Chip Resistor"
			(at 0 0 270)
			(layer "F.Fab")
			(hide yes)
			(effects
				(font
					(size 1.27 1.27)
					(thickness 0.15)
				)
			)
		)
		(property "Author" "Antmicro"
			(at 38.432 214.916 0)
			(layer "F.Fab")
			(hide yes)
			(effects
				(font
					(size 1 1)
					(thickness 0.15)
				)
			)
		)
		(property "License" "Apache-2.0"
			(at 38.432 214.916 0)
			(layer "F.Fab")
			(hide yes)
			(effects
				(font
					(size 1 1)
					(thickness 0.15)
				)
			)
		)
		(property "MPN" "PMR03EZPJ000"
			(at 38.432 214.916 0)
			(layer "F.Fab")
			(hide yes)
			(effects
				(font
					(size 1 1)
					(thickness 0.15)
				)
			)
		)
		(property "Manufacturer" "ROHM Semiconductor"
			(at 38.432 214.916 0)
			(layer "F.Fab")
			(hide yes)
			(effects
				(font
					(size 1 1)
					(thickness 0.15)
				)
			)
		)
		(property "Max. Curr." "22.4A"
			(at 38.432 214.916 0)
			(layer "F.Fab")
			(hide yes)
			(effects
				(font
					(size 1 1)
					(thickness 0.15)
				)
			)
		)
		(property "Tolerance" "template_tolerance"
			(at 38.432 214.916 0)
			(layer "F.Fab")
			(hide yes)
			(effects
				(font
					(size 1 1)
					(thickness 0.15)
				)
			)
		)
		(property "Val" "0R"
			(at 38.432 214.916 0)
			(layer "F.Fab")
			(hide yes)
			(effects
				(font
					(size 1 1)
					(thickness 0.15)
				)
			)
		)
		(sheetname "/Power/")
		(sheetfile "power.kicad_sch")
		(attr smd)
		(fp_line
			(start -0.15 0.4)
			(end 0.15 0.4)
			(stroke
				(width 0.15)
				(type solid)
			)
			(layer "F.SilkS")
		)
		(fp_line
			(start -0.15 -0.4)
			(end 0.15 -0.4)
			(stroke
				(width 0.15)
				(type solid)
			)
			(layer "F.SilkS")
		)
		(fp_rect
			(start -1.25 -0.65)
			(end 1.25 0.65)
			(stroke
				(width 0.05)
				(type solid)
			)
			(fill no)
			(layer "F.CrtYd")
		)
		(fp_rect
			(start -0.8 -0.4)
			(end 0.8 0.4)
			(stroke
				(width 0.15)
				(type solid)
			)
			(fill no)
			(layer "F.Fab")
		)
		(pad "1" smd roundrect
			(at -0.7 0 270)
			(size 0.8 1)
			(layers "F.Cu" "F.Mask" "F.Paste")
			(roundrect_rratio 0.2)
			(net 11 "/Power/OUT_1V2")
			(pintype "passive")
		)
		(pad "2" smd roundrect
			(at 0.7 0 270)
			(size 0.8 1)
			(layers "F.Cu" "F.Mask" "F.Paste")
			(roundrect_rratio 0.2)
			(net 73 "+1V2")
			(pintype "passive")
		)
	)
	(footprint "antmicro-footprints:R_0402_1005Metric"
		(layer "F.Cu")
		(at 179.837 68.834 -90)
		(descr "Resistor SMD 0402")
		(tags "resistor SMD 0402")
		(property "Reference" "R8"
			(at 8.1078 -0.249 90)
			(layer "F.SilkS")
			(effects
				(font
					(size 0.7 0.7)
					(thickness 0.15)
				)
				(justify right bottom)
			)
		)
		(property "Value" "R_200R_0402"
			(at -1.011843 1.772047 90)
			(layer "F.Fab")
			(effects
				(font
					(size 0.7 0.7)
					(thickness 0.15)
				)
				(justify right bottom)
			)
		)
		(property "Datasheet" "https://www.bourns.com/docs/product-datasheets/cr.pdf"
			(at 0 0 270)
			(layer "F.Fab")
			(hide yes)
			(effects
				(font
					(size 1.27 1.27)
					(thickness 0.15)
				)
			)
		)
		(property "Description" "SMD Chip Resistor, 200 ohm, ± 1%, 62.5 mW, 0402 [1005 Metric], Thick Film, General Purpose"
			(at 0 0 270)
			(layer "F.Fab")
			(hide yes)
			(effects
				(font
					(size 1.27 1.27)
					(thickness 0.15)
				)
			)
		)
		(property "Author" "Antmicro"
			(at 111.003 248.671 0)
			(layer "F.Fab")
			(hide yes)
			(effects
				(font
					(size 1 1)
					(thickness 0.15)
				)
			)
		)
		(property "License" "Apache-2.0"
			(at 111.003 248.671 0)
			(layer "F.Fab")
			(hide yes)
			(effects
				(font
					(size 1 1)
					(thickness 0.15)
				)
			)
		)
		(property "MPN" "CR0402-FX-2000GLF"
			(at 111.003 248.671 0)
			(layer "F.Fab")
			(hide yes)
			(effects
				(font
					(size 1 1)
					(thickness 0.15)
				)
			)
		)
		(property "Manufacturer" "Bourns"
			(at 111.003 248.671 0)
			(layer "F.Fab")
			(hide yes)
			(effects
				(font
					(size 1 1)
					(thickness 0.15)
				)
			)
		)
		(property "Tolerance" "1%"
			(at 111.003 248.671 0)
			(layer "F.Fab")
			(hide yes)
			(effects
				(font
					(size 1 1)
					(thickness 0.15)
				)
			)
		)
		(property "Val" "200R"
			(at 111.003 248.671 0)
			(layer "F.Fab")
			(hide yes)
			(effects
				(font
					(size 1 1)
					(thickness 0.15)
				)
			)
		)
		(sheetname "/Connectors/")
		(sheetfile "connectors.kicad_sch")
		(attr smd exclude_from_pos_files exclude_from_bom dnp)
		(fp_rect
			(start -0.925 -0.47)
			(end 0.925 0.47)
			(stroke
				(width 0.05)
				(type default)
			)
			(fill no)
			(layer "F.CrtYd")
		)
		(fp_rect
			(start -0.5 -0.25)
			(end 0.5 0.25)
			(stroke
				(width 0.15)
				(type solid)
			)
			(fill no)
			(layer "F.Fab")
		)
		(pad "1" smd roundrect
			(at -0.48 0 270)
			(size 0.59 0.64)
			(layers "F.Cu" "F.Mask" "F.Paste")
			(roundrect_rratio 0.25)
			(net 66 "/Connectors/VSYNC_CAM1")
			(pintype "passive")
		)
		(pad "2" smd roundrect
			(at 0.48 0 270)
			(size 0.59 0.64)
			(layers "F.Cu" "F.Mask" "F.Paste")
			(roundrect_rratio 0.25)
			(net 67 "/Connectors/VSYNC_CAM0")
			(pintype "passive")
		)
	)
	(footprint "antmicro-footprints:L_Coilcraft-1210POC"
		(layer "F.Cu")
		(at 148.336 56.642 90)
		(property "Reference" "L7"
			(at -0.635 -1.7 90)
			(layer "F.SilkS")
			(effects
				(font
					(size 0.7 0.7)
					(thickness 0.15)
				)
				(justify left bottom)
			)
		)
		(property "Value" "L_6u8_1A_Coilcraft-1210POC"
			(at 0 2.4 90)
			(layer "F.Fab")
			(effects
				(font
					(size 0.7 0.7)
					(thickness 0.15)
				)
				(justify left bottom)
			)
		)
		(property "Datasheet" "https://www.coilcraft.com/getmedia/5e8de018-68c5-4442-84ce-d5212c44660c/1210poc.pdf"
			(at 0 0 90)
			(layer "F.Fab")
			(hide yes)
			(effects
				(font
					(size 1.27 1.27)
					(thickness 0.15)
				)
			)
		)
		(property "Description" "Power Inductor (SMT), 6.8 µH, 9.2 A, Shielded, 12.8 A, XAL7070"
			(at 0 0 90)
			(layer "F.Fab")
			(hide yes)
			(effects
				(font
					(size 1.27 1.27)
					(thickness 0.15)
				)
			)
		)
		(property "Author" "Antmicro"
			(at 204.978 -91.694 0)
			(layer "F.Fab")
			(hide yes)
			(effects
				(font
					(size 1 1)
					(thickness 0.15)
				)
			)
		)
		(property "IMax" "1.36 A"
			(at 204.978 -91.694 0)
			(layer "F.Fab")
			(hide yes)
			(effects
				(font
					(size 1 1)
					(thickness 0.15)
				)
			)
		)
		(property "ISat" "1 A"
			(at 204.978 -91.694 0)
			(layer "F.Fab")
			(hide yes)
			(effects
				(font
					(size 1 1)
					(thickness 0.15)
				)
			)
		)
		(property "License" "Apache-2.0"
			(at 204.978 -91.694 0)
			(layer "F.Fab")
			(hide yes)
			(effects
				(font
					(size 1 1)
					(thickness 0.15)
				)
			)
		)
		(property "MPN" "1210POC-682"
			(at 204.978 -91.694 0)
			(layer "F.Fab")
			(hide yes)
			(effects
				(font
					(size 1 1)
					(thickness 0.15)
				)
			)
		)
		(property "Manufacturer" "Coilcraft"
			(at 204.978 -91.694 0)
			(layer "F.Fab")
			(hide yes)
			(effects
				(font
					(size 1 1)
					(thickness 0.15)
				)
			)
		)
		(property "Size" "2.67x3.3"
			(at 204.978 -91.694 0)
			(layer "F.Fab")
			(hide yes)
			(effects
				(font
					(size 1 1)
					(thickness 0.15)
				)
			)
		)
		(property "Val" "6u8/1A"
			(at 204.978 -91.694 0)
			(layer "F.Fab")
			(hide yes)
			(effects
				(font
					(size 1 1)
					(thickness 0.15)
				)
			)
		)
		(sheetname "/Power/")
		(sheetfile "power.kicad_sch")
		(attr smd)
		(fp_line
			(start -0.7 -1.4)
			(end 0.7 -1.4)
			(stroke
				(width 0.15)
				(type solid)
			)
			(layer "F.SilkS")
		)
		(fp_line
			(start -0.7 1.4)
			(end 0.7 1.4)
			(stroke
				(width 0.15)
				(type solid)
			)
			(layer "F.SilkS")
		)
		(fp_rect
			(start -1.9 -1.585)
			(end 1.9 1.585)
			(stroke
				(width 0.05)
				(type solid)
			)
			(fill no)
			(layer "F.CrtYd")
		)
		(fp_line
			(start 1.65 -1.335)
			(end -1.65 -1.335)
			(stroke
				(width 0.15)
				(type solid)
			)
			(layer "F.Fab")
		)
		(fp_line
			(start 1.65 1.335)
			(end 1.65 -1.335)
			(stroke
				(width 0.15)
				(type solid)
			)
			(layer "F.Fab")
		)
		(fp_line
			(start 1.65 1.335)
			(end -1.65 1.335)
			(stroke
				(width 0.15)
				(type solid)
			)
			(layer "F.Fab")
		)
		(fp_line
			(start -1.65 1.335)
			(end -1.65 -1.335)
			(stroke
				(width 0.15)
				(type solid)
			)
			(layer "F.Fab")
		)
		(pad "1" smd rect
			(at -1.27 0 90)
			(size 0.65 2.65)
			(layers "F.Cu" "F.Mask" "F.Paste")
			(net 53 "Net-(L3-Pad2)")
			(pintype "passive")
		)
		(pad "2" smd rect
			(at 1.27 0 90)
			(size 0.65 2.65)
			(layers "F.Cu" "F.Mask" "F.Paste")
			(net 57 "Net-(L11-Pad1)")
			(pintype "passive")
		)
	)
	(footprint "antmicro-footprints:TP_SMD_0.75mm"
		(layer "F.Cu")
		(at 142.748 97.78)
		(property "Reference" "TP15"
			(at 0 -0.6 0)
			(layer "F.SilkS")
			(hide yes)
			(effects
				(font
					(size 0.7 0.7)
					(thickness 0.15)
				)
				(justify left bottom)
			)
		)
		(property "Value" "TP_0.75mm_SMD"
			(at 0 1.2 0)
			(layer "F.Fab")
			(effects
				(font
					(size 0.7 0.7)
					(thickness 0.15)
				)
				(justify left bottom)
			)
		)
		(property "Description" "SMT test point"
			(at 0 0 0)
			(layer "F.Fab")
			(hide yes)
			(effects
				(font
					(size 1.27 1.27)
					(thickness 0.15)
				)
			)
		)
		(property "Author" "Antmicro"
			(at 0 0 0)
			(layer "F.Fab")
			(hide yes)
			(effects
				(font
					(size 1 1)
					(thickness 0.15)
				)
			)
		)
		(property "License" "Apache-2.0"
			(at 0 0 0)
			(layer "F.Fab")
			(hide yes)
			(effects
				(font
					(size 1 1)
					(thickness 0.15)
				)
			)
		)
		(property "MPN" ""
			(at 0 0 0)
			(layer "F.Fab")
			(hide yes)
			(effects
				(font
					(size 1 1)
					(thickness 0.15)
				)
			)
		)
		(property "Manufacturer" ""
			(at 0 0 0)
			(layer "F.Fab")
			(hide yes)
			(effects
				(font
					(size 1 1)
					(thickness 0.15)
				)
			)
		)
		(sheetname "/Power/")
		(sheetfile "power.kicad_sch")
		(fp_circle
			(center 0 0)
			(end 0.475 0)
			(stroke
				(width 0.05)
				(type default)
			)
			(fill no)
			(layer "F.CrtYd")
		)
		(pad "1" smd circle
			(at 0 0)
			(size 0.75 0.75)
			(layers "F.Cu" "F.Mask")
			(net 1 "GND")
			(pinfunction "1")
			(pintype "passive")
		)
	)
	(footprint "antmicro-footprints:SOD-523_NP"
		(layer "F.Cu")
		(at 178.054 67.31 -90)
		(property "Reference" "D7"
			(at -0.85 0.607653 90)
			(layer "F.SilkS")
			(effects
				(font
					(size 0.7 0.7)
					(thickness 0.15)
				)
				(justify right bottom)
			)
		)
		(property "Value" "ESD5B5_0ST1G"
			(at 0 1.499 90)
			(layer "F.Fab")
			(effects
				(font
					(size 0.7 0.7)
					(thickness 0.15)
				)
				(justify right bottom)
			)
		)
		(property "Datasheet" "https://www.onsemi.com/pdf/datasheet/esd5b5.0st1-d.pdf"
			(at 0 0 270)
			(layer "F.Fab")
			(hide yes)
			(effects
				(font
					(size 1.27 1.27)
					(thickness 0.15)
				)
			)
		)
		(property "Description" "Bidirectional TVS, 30 kV,  SOD-523, 5 V, 32 pF"
			(at 0 0 270)
			(layer "F.Fab")
			(hide yes)
			(effects
				(font
					(size 1.27 1.27)
					(thickness 0.15)
				)
			)
		)
		(property "Author" "Antmicro"
			(at 110.744 245.364 0)
			(layer "F.Fab")
			(hide yes)
			(effects
				(font
					(size 1 1)
					(thickness 0.15)
				)
			)
		)
		(property "License" "Apache-2.0"
			(at 110.744 245.364 0)
			(layer "F.Fab")
			(hide yes)
			(effects
				(font
					(size 1 1)
					(thickness 0.15)
				)
			)
		)
		(property "MPN" "ESD5B5.0ST1G"
			(at 110.744 245.364 0)
			(layer "F.Fab")
			(hide yes)
			(effects
				(font
					(size 1 1)
					(thickness 0.15)
				)
			)
		)
		(property "Manufacturer" "ON Semiconductor"
			(at 110.744 245.364 0)
			(layer "F.Fab")
			(hide yes)
			(effects
				(font
					(size 1 1)
					(thickness 0.15)
				)
			)
		)
		(sheetname "/Connectors/")
		(sheetfile "connectors.kicad_sch")
		(attr smd)
		(fp_rect
			(start -1 -0.6)
			(end 1 0.6)
			(stroke
				(width 0.05)
				(type solid)
			)
			(fill no)
			(layer "F.CrtYd")
		)
		(fp_line
			(start -0.652 0.423)
			(end 0.65 0.423)
			(stroke
				(width 0.15)
				(type solid)
			)
			(layer "F.Fab")
		)
		(fp_line
			(start -0.652 0.423)
			(end -0.652 -0.425)
			(stroke
				(width 0.15)
				(type solid)
			)
			(layer "F.Fab")
		)
		(fp_line
			(start -0.652 -0.425)
			(end 0.65 -0.425)
			(stroke
				(width 0.15)
				(type solid)
			)
			(layer "F.Fab")
		)
		(fp_line
			(start 0.65 -0.425)
			(end 0.65 0.423)
			(stroke
				(width 0.15)
				(type solid)
			)
			(layer "F.Fab")
		)
		(pad "1" smd roundrect
			(at -0.701 0 270)
			(size 0.5 0.6)
			(layers "F.Cu" "F.Mask" "F.Paste")
			(roundrect_rratio 0.25)
			(net 1 "GND")
			(pinfunction "C")
			(pintype "passive")
		)
		(pad "2" smd roundrect
			(at 0.699 0 270)
			(size 0.5 0.6)
			(layers "F.Cu" "F.Mask" "F.Paste")
			(roundrect_rratio 0.25)
			(net 66 "/Connectors/VSYNC_CAM1")
			(pinfunction "A")
			(pintype "passive")
		)
	)
	(footprint "antmicro-footprints:C_0402_1005Metric"
		(layer "F.Cu")
		(at 182.132 60.1975 -90)
		(descr "Capacitor SMD 0402")
		(tags "capacitor SMD 0402")
		(property "Reference" "C5"
			(at -0.7615 0.522 90)
			(layer "F.SilkS")
			(effects
				(font
					(size 0.7 0.7)
					(thickness 0.15)
				)
				(justify right bottom)
			)
		)
		(property "Value" "C_1u_0402"
			(at -1.022927 2.155213 90)
			(layer "F.Fab")
			(effects
				(font
					(size 0.7 0.7)
					(thickness 0.15)
				)
				(justify right bottom)
			)
		)
		(property "Datasheet" "https://product.tdk.com/en/search/capacitor/ceramic/mlcc/info?part_no=C1005X6S1A105K050BC"
			(at 0 0 270)
			(layer "F.Fab")
			(hide yes)
			(effects
				(font
					(size 1.27 1.27)
					(thickness 0.15)
				)
			)
		)
		(property "Description" "SMD Multilayer Ceramic Capacitor, 1 µF, 10 V, 0402 [1005 Metric], ± 10%, X6S, C"
			(at 0 0 270)
			(layer "F.Fab")
			(hide yes)
			(effects
				(font
					(size 1.27 1.27)
					(thickness 0.15)
				)
			)
		)
		(property "Author" "Antmicro"
			(at 121.9345 242.3295 0)
			(layer "F.Fab")
			(hide yes)
			(effects
				(font
					(size 1 1)
					(thickness 0.15)
				)
			)
		)
		(property "Dielectric" ""
			(at 121.9345 242.3295 0)
			(layer "F.Fab")
			(hide yes)
			(effects
				(font
					(size 1 1)
					(thickness 0.15)
				)
			)
		)
		(property "License" "Apache-2.0"
			(at 121.9345 242.3295 0)
			(layer "F.Fab")
			(hide yes)
			(effects
				(font
					(size 1 1)
					(thickness 0.15)
				)
			)
		)
		(property "MPN" "C1005X6S1A105K050BC"
			(at 121.9345 242.3295 0)
			(layer "F.Fab")
			(hide yes)
			(effects
				(font
					(size 1 1)
					(thickness 0.15)
				)
			)
		)
		(property "Manufacturer" "TDK"
			(at 121.9345 242.3295 0)
			(layer "F.Fab")
			(hide yes)
			(effects
				(font
					(size 1 1)
					(thickness 0.15)
				)
			)
		)
		(property "Val" "1u"
			(at 121.9345 242.3295 0)
			(layer "F.Fab")
			(hide yes)
			(effects
				(font
					(size 1 1)
					(thickness 0.15)
				)
			)
		)
		(property "Voltage" ""
			(at 121.9345 242.3295 0)
			(layer "F.Fab")
			(hide yes)
			(effects
				(font
					(size 1 1)
					(thickness 0.15)
				)
			)
		)
		(sheetname "/Connectors/")
		(sheetfile "connectors.kicad_sch")
		(attr smd)
		(fp_rect
			(start -0.925 -0.47)
			(end 0.925 0.47)
			(stroke
				(width 0.05)
				(type default)
			)
			(fill no)
			(layer "F.CrtYd")
		)
		(fp_line
			(start -0.494 0.248)
			(end -0.494 -0.25)
			(stroke
				(width 0.15)
				(type solid)
			)
			(layer "F.Fab")
		)
		(fp_line
			(start 0.504 0.248)
			(end -0.494 0.248)
			(stroke
				(width 0.15)
				(type solid)
			)
			(layer "F.Fab")
		)
		(fp_line
			(start -0.494 -0.25)
			(end 0.504 -0.25)
			(stroke
				(width 0.15)
				(type solid)
			)
			(layer "F.Fab")
		)
		(fp_line
			(start 0.504 -0.25)
			(end 0.504 0.248)
			(stroke
				(width 0.15)
				(type solid)
			)
			(layer "F.Fab")
		)
		(pad "1" smd roundrect
			(at -0.48 0 270)
			(size 0.59 0.64)
			(layers "F.Cu" "F.Mask" "F.Paste")
			(roundrect_rratio 0.25)
			(net 1 "GND")
			(pintype "passive")
		)
		(pad "2" smd roundrect
			(at 0.48 0 270)
			(size 0.59 0.64)
			(layers "F.Cu" "F.Mask" "F.Paste")
			(roundrect_rratio 0.25)
			(net 113 "/Connectors/FFC_5V")
			(pintype "passive")
		)
	)
	(footprint "antmicro-footprints:R_0402_1005Metric"
		(layer "F.Cu")
		(at 170.68 69.857)
		(descr "Resistor SMD 0402")
		(tags "resistor SMD 0402")
		(property "Reference" "R68"
			(at -3.140968 0.337135 0)
			(layer "F.SilkS")
			(effects
				(font
					(size 0.7 0.7)
					(thickness 0.15)
				)
				(justify left bottom)
			)
		)
		(property "Value" "R_100R_0402"
			(at -1.011843 1.772047 0)
			(layer "F.Fab")
			(effects
				(font
					(size 0.7 0.7)
					(thickness 0.15)
				)
				(justify left bottom)
			)
		)
		(property "Datasheet" "https://www.bourns.com/docs/product-datasheets/cr.pdf"
			(at 0 0 0)
			(layer "F.Fab")
			(hide yes)
			(effects
				(font
					(size 1.27 1.27)
					(thickness 0.15)
				)
			)
		)
		(property "Description" "SMD Chip Resistor, 100 ohm, ± 1%, 62.5 mW, 0402 [1005 Metric], Thick Film, General Purpose"
			(at 0 0 0)
			(layer "F.Fab")
			(hide yes)
			(effects
				(font
					(size 1.27 1.27)
					(thickness 0.15)
				)
			)
		)
		(property "Author" "Antmicro"
			(at 0 0 0)
			(layer "F.Fab")
			(hide yes)
			(effects
				(font
					(size 1 1)
					(thickness 0.15)
				)
			)
		)
		(property "License" "Apache-2.0"
			(at 0 0 0)
			(layer "F.Fab")
			(hide yes)
			(effects
				(font
					(size 1 1)
					(thickness 0.15)
				)
			)
		)
		(property "MPN" "CR0402-FX-1000GLF"
			(at 0 0 0)
			(layer "F.Fab")
			(hide yes)
			(effects
				(font
					(size 1 1)
					(thickness 0.15)
				)
			)
		)
		(property "Manufacturer" "Bourns"
			(at 0 0 0)
			(layer "F.Fab")
			(hide yes)
			(effects
				(font
					(size 1 1)
					(thickness 0.15)
				)
			)
		)
		(property "Tolerance" "1%"
			(at 0 0 0)
			(layer "F.Fab")
			(hide yes)
			(effects
				(font
					(size 1 1)
					(thickness 0.15)
				)
			)
		)
		(property "Val" "100R"
			(at 0 0 0)
			(layer "F.Fab")
			(hide yes)
			(effects
				(font
					(size 1 1)
					(thickness 0.15)
				)
			)
		)
		(sheetname "/Connectors/")
		(sheetfile "connectors.kicad_sch")
		(attr smd exclude_from_pos_files exclude_from_bom dnp)
		(fp_rect
			(start -0.925 -0.47)
			(end 0.925 0.47)
			(stroke
				(width 0.05)
				(type default)
			)
			(fill no)
			(layer "F.CrtYd")
		)
		(fp_rect
			(start -0.5 -0.25)
			(end 0.5 0.25)
			(stroke
				(width 0.15)
				(type solid)
			)
			(fill no)
			(layer "F.Fab")
		)
		(pad "1" smd roundrect
			(at -0.48 0)
			(size 0.59 0.64)
			(layers "F.Cu" "F.Mask" "F.Paste")
			(roundrect_rratio 0.25)
			(net 86 "/Connectors/MFP7")
			(pintype "passive")
		)
		(pad "2" smd roundrect
			(at 0.48 0)
			(size 0.59 0.64)
			(layers "F.Cu" "F.Mask" "F.Paste")
			(roundrect_rratio 0.25)
			(net 133 "Net-(U8-A_{1})")
			(pintype "passive")
		)
	)
	(footprint "antmicro-footprints:L_Coilcraft-1210POC"
		(layer "F.Cu")
		(at 124.968 56.642 90)
		(property "Reference" "L5"
			(at -0.635 -1.778 90)
			(layer "F.SilkS")
			(effects
				(font
					(size 0.7 0.7)
					(thickness 0.15)
				)
				(justify left bottom)
			)
		)
		(property "Value" "L_6u8_1A_Coilcraft-1210POC"
			(at 0 2.4 90)
			(layer "F.Fab")
			(effects
				(font
					(size 0.7 0.7)
					(thickness 0.15)
				)
				(justify left bottom)
			)
		)
		(property "Datasheet" "https://www.coilcraft.com/getmedia/5e8de018-68c5-4442-84ce-d5212c44660c/1210poc.pdf"
			(at 0 0 90)
			(layer "F.Fab")
			(hide yes)
			(effects
				(font
					(size 1.27 1.27)
					(thickness 0.15)
				)
			)
		)
		(property "Description" "Power Inductor (SMT), 6.8 µH, 9.2 A, Shielded, 12.8 A, XAL7070"
			(at 0 0 90)
			(layer "F.Fab")
			(hide yes)
			(effects
				(font
					(size 1.27 1.27)
					(thickness 0.15)
				)
			)
		)
		(property "Author" "Antmicro"
			(at 181.61 -68.326 0)
			(layer "F.Fab")
			(hide yes)
			(effects
				(font
					(size 1 1)
					(thickness 0.15)
				)
			)
		)
		(property "IMax" "1.36 A"
			(at 181.61 -68.326 0)
			(layer "F.Fab")
			(hide yes)
			(effects
				(font
					(size 1 1)
					(thickness 0.15)
				)
			)
		)
		(property "ISat" "1 A"
			(at 181.61 -68.326 0)
			(layer "F.Fab")
			(hide yes)
			(effects
				(font
					(size 1 1)
					(thickness 0.15)
				)
			)
		)
		(property "License" "Apache-2.0"
			(at 181.61 -68.326 0)
			(layer "F.Fab")
			(hide yes)
			(effects
				(font
					(size 1 1)
					(thickness 0.15)
				)
			)
		)
		(property "MPN" "1210POC-682"
			(at 181.61 -68.326 0)
			(layer "F.Fab")
			(hide yes)
			(effects
				(font
					(size 1 1)
					(thickness 0.15)
				)
			)
		)
		(property "Manufacturer" "Coilcraft"
			(at 181.61 -68.326 0)
			(layer "F.Fab")
			(hide yes)
			(effects
				(font
					(size 1 1)
					(thickness 0.15)
				)
			)
		)
		(property "Size" "2.67x3.3"
			(at 181.61 -68.326 0)
			(layer "F.Fab")
			(hide yes)
			(effects
				(font
					(size 1 1)
					(thickness 0.15)
				)
			)
		)
		(property "Val" "6u8/1A"
			(at 181.61 -68.326 0)
			(layer "F.Fab")
			(hide yes)
			(effects
				(font
					(size 1 1)
					(thickness 0.15)
				)
			)
		)
		(sheetname "/Power/")
		(sheetfile "power.kicad_sch")
		(attr smd)
		(fp_line
			(start -0.7 -1.4)
			(end 0.7 -1.4)
			(stroke
				(width 0.15)
				(type solid)
			)
			(layer "F.SilkS")
		)
		(fp_line
			(start -0.7 1.4)
			(end 0.7 1.4)
			(stroke
				(width 0.15)
				(type solid)
			)
			(layer "F.SilkS")
		)
		(fp_rect
			(start -1.9 -1.585)
			(end 1.9 1.585)
			(stroke
				(width 0.05)
				(type solid)
			)
			(fill no)
			(layer "F.CrtYd")
		)
		(fp_line
			(start 1.65 -1.335)
			(end -1.65 -1.335)
			(stroke
				(width 0.15)
				(type solid)
			)
			(layer "F.Fab")
		)
		(fp_line
			(start 1.65 1.335)
			(end 1.65 -1.335)
			(stroke
				(width 0.15)
				(type solid)
			)
			(layer "F.Fab")
		)
		(fp_line
			(start 1.65 1.335)
			(end -1.65 1.335)
			(stroke
				(width 0.15)
				(type solid)
			)
			(layer "F.Fab")
		)
		(fp_line
			(start -1.65 1.335)
			(end -1.65 -1.335)
			(stroke
				(width 0.15)
				(type solid)
			)
			(layer "F.Fab")
		)
		(pad "1" smd rect
			(at -1.27 0 90)
			(size 0.65 2.65)
			(layers "F.Cu" "F.Mask" "F.Paste")
			(net 51 "Net-(L1-Pad2)")
			(pintype "passive")
		)
		(pad "2" smd rect
			(at 1.27 0 90)
			(size 0.65 2.65)
			(layers "F.Cu" "F.Mask" "F.Paste")
			(net 55 "Net-(L5-Pad2)")
			(pintype "passive")
		)
	)
	(footprint "antmicro-footprints:C_0402_1005Metric"
		(layer "F.Cu")
		(at 188.649 53.3088 -90)
		(descr "Capacitor SMD 0402")
		(tags "capacitor SMD 0402")
		(property "Reference" "C23"
			(at -1.086714 -1.359362 90)
			(layer "F.SilkS")
			(effects
				(font
					(size 0.7 0.7)
					(thickness 0.15)
				)
				(justify right bottom)
			)
		)
		(property "Value" "C_100n_0402"
			(at -1.022927 2.155213 90)
			(layer "F.Fab")
			(effects
				(font
					(size 0.7 0.7)
					(thickness 0.15)
				)
				(justify right bottom)
			)
		)
		(property "Datasheet" "https://www.murata.com/products/productdetail?partno=GRM155R61H104KE14%23"
			(at 0 0 270)
			(layer "F.Fab")
			(hide yes)
			(effects
				(font
					(size 1.27 1.27)
					(thickness 0.15)
				)
			)
		)
		(property "Description" "SMD Multilayer Ceramic Capacitor, 0.1 µF, 50 V, 0402 [1005 Metric], ± 10%, X5R, GRM Series"
			(at 0 0 270)
			(layer "F.Fab")
			(hide yes)
			(effects
				(font
					(size 1.27 1.27)
					(thickness 0.15)
				)
			)
		)
		(property "Author" "Antmicro"
			(at 135.3402 241.9578 0)
			(layer "F.Fab")
			(hide yes)
			(effects
				(font
					(size 1 1)
					(thickness 0.15)
				)
			)
		)
		(property "Dielectric" "X5R"
			(at 135.3402 241.9578 0)
			(layer "F.Fab")
			(hide yes)
			(effects
				(font
					(size 1 1)
					(thickness 0.15)
				)
			)
		)
		(property "License" "Apache-2.0"
			(at 135.3402 241.9578 0)
			(layer "F.Fab")
			(hide yes)
			(effects
				(font
					(size 1 1)
					(thickness 0.15)
				)
			)
		)
		(property "MPN" "GRM155R61H104KE14D"
			(at 135.3402 241.9578 0)
			(layer "F.Fab")
			(hide yes)
			(effects
				(font
					(size 1 1)
					(thickness 0.15)
				)
			)
		)
		(property "Manufacturer" "Murata"
			(at 135.3402 241.9578 0)
			(layer "F.Fab")
			(hide yes)
			(effects
				(font
					(size 1 1)
					(thickness 0.15)
				)
			)
		)
		(property "Val" "100n"
			(at 135.3402 241.9578 0)
			(layer "F.Fab")
			(hide yes)
			(effects
				(font
					(size 1 1)
					(thickness 0.15)
				)
			)
		)
		(property "Voltage" "50V"
			(at 135.3402 241.9578 0)
			(layer "F.Fab")
			(hide yes)
			(effects
				(font
					(size 1 1)
					(thickness 0.15)
				)
			)
		)
		(sheetname "/Power/")
		(sheetfile "power.kicad_sch")
		(attr smd)
		(fp_rect
			(start -0.925 -0.47)
			(end 0.925 0.47)
			(stroke
				(width 0.05)
				(type default)
			)
			(fill no)
			(layer "F.CrtYd")
		)
		(fp_line
			(start -0.494 0.248)
			(end -0.494 -0.25)
			(stroke
				(width 0.15)
				(type solid)
			)
			(layer "F.Fab")
		)
		(fp_line
			(start 0.504 0.248)
			(end -0.494 0.248)
			(stroke
				(width 0.15)
				(type solid)
			)
			(layer "F.Fab")
		)
		(fp_line
			(start -0.494 -0.25)
			(end 0.504 -0.25)
			(stroke
				(width 0.15)
				(type solid)
			)
			(layer "F.Fab")
		)
		(fp_line
			(start 0.504 -0.25)
			(end 0.504 0.248)
			(stroke
				(width 0.15)
				(type solid)
			)
			(layer "F.Fab")
		)
		(pad "1" smd roundrect
			(at -0.48 0 270)
			(size 0.59 0.64)
			(layers "F.Cu" "F.Mask" "F.Paste")
			(roundrect_rratio 0.25)
			(net 1 "GND")
			(pintype "passive")
		)
		(pad "2" smd roundrect
			(at 0.48 0 270)
			(size 0.59 0.64)
			(layers "F.Cu" "F.Mask" "F.Paste")
			(roundrect_rratio 0.25)
			(net 113 "/Connectors/FFC_5V")
			(pintype "passive")
		)
	)
	(footprint "antmicro-footprints:R_0603_1608Metric"
		(layer "F.Cu")
		(at 172.05 56.95 -90)
		(descr "Resistor SMD 0603")
		(tags "resistor SMD 0603")
		(property "Reference" "R18"
			(at -1.454542 0.649954 90)
			(layer "F.SilkS")
			(effects
				(font
					(size 0.7 0.7)
					(thickness 0.15)
				)
				(justify right bottom)
			)
		)
		(property "Value" "R_0R_22.4A_0603"
			(at 0 1.6 90)
			(layer "F.Fab")
			(effects
				(font
					(size 0.7 0.7)
					(thickness 0.15)
				)
				(justify right bottom)
			)
		)
		(property "Datasheet" "https://fscdn.rohm.com/en/products/databook/datasheet/passive/resistor/chip_resistor/pmr-jpw-e.pdf"
			(at 0 0 270)
			(layer "F.Fab")
			(hide yes)
			(effects
				(font
					(size 1.27 1.27)
					(thickness 0.15)
				)
			)
		)
		(property "Description" "SMD Chip Resistor"
			(at 0 0 270)
			(layer "F.Fab")
			(hide yes)
			(effects
				(font
					(size 1.27 1.27)
					(thickness 0.15)
				)
			)
		)
		(property "Author" "Antmicro"
			(at 115.1 229 0)
			(layer "F.Fab")
			(hide yes)
			(effects
				(font
					(size 1 1)
					(thickness 0.15)
				)
			)
		)
		(property "License" "Apache-2.0"
			(at 115.1 229 0)
			(layer "F.Fab")
			(hide yes)
			(effects
				(font
					(size 1 1)
					(thickness 0.15)
				)
			)
		)
		(property "MPN" "PMR03EZPJ000"
			(at 115.1 229 0)
			(layer "F.Fab")
			(hide yes)
			(effects
				(font
					(size 1 1)
					(thickness 0.15)
				)
			)
		)
		(property "Manufacturer" "ROHM Semiconductor"
			(at 115.1 229 0)
			(layer "F.Fab")
			(hide yes)
			(effects
				(font
					(size 1 1)
					(thickness 0.15)
				)
			)
		)
		(property "Max. Curr." "22.4A"
			(at 115.1 229 0)
			(layer "F.Fab")
			(hide yes)
			(effects
				(font
					(size 1 1)
					(thickness 0.15)
				)
			)
		)
		(property "Tolerance" "template_tolerance"
			(at 115.1 229 0)
			(layer "F.Fab")
			(hide yes)
			(effects
				(font
					(size 1 1)
					(thickness 0.15)
				)
			)
		)
		(property "Val" "0R"
			(at 115.1 229 0)
			(layer "F.Fab")
			(hide yes)
			(effects
				(font
					(size 1 1)
					(thickness 0.15)
				)
			)
		)
		(sheetname "/Power/")
		(sheetfile "power.kicad_sch")
		(attr smd exclude_from_pos_files exclude_from_bom dnp)
		(fp_line
			(start -0.15 0.4)
			(end 0.15 0.4)
			(stroke
				(width 0.15)
				(type solid)
			)
			(layer "F.SilkS")
		)
		(fp_line
			(start -0.15 -0.4)
			(end 0.15 -0.4)
			(stroke
				(width 0.15)
				(type solid)
			)
			(layer "F.SilkS")
		)
		(fp_rect
			(start -1.25 -0.65)
			(end 1.25 0.65)
			(stroke
				(width 0.05)
				(type solid)
			)
			(fill no)
			(layer "F.CrtYd")
		)
		(fp_rect
			(start -0.8 -0.4)
			(end 0.8 0.4)
			(stroke
				(width 0.15)
				(type solid)
			)
			(fill no)
			(layer "F.Fab")
		)
		(pad "1" smd roundrect
			(at -0.7 0 270)
			(size 0.8 1)
			(layers "F.Cu" "F.Mask" "F.Paste")
			(roundrect_rratio 0.2)
			(net 118 "/Connectors/DC_IN")
			(pintype "passive")
		)
		(pad "2" smd roundrect
			(at 0.7 0 270)
			(size 0.8 1)
			(layers "F.Cu" "F.Mask" "F.Paste")
			(roundrect_rratio 0.2)
			(net 4 "+12V")
			(pintype "passive")
		)
	)
	(footprint "antmicro-footprints:C_0603_1608Metric"
		(layer "F.Cu")
		(at 188.976 50.8 90)
		(descr "Capacitor SMD 0603")
		(tags "capacitor 0603")
		(property "Reference" "C60"
			(at 1.27 0.254 90)
			(layer "F.SilkS")
			(effects
				(font
					(size 0.7 0.7)
					(thickness 0.15)
				)
				(justify left bottom)
			)
		)
		(property "Value" "C_10u_25V_0603"
			(at -1.42757 1.770288 90)
			(layer "F.Fab")
			(effects
				(font
					(size 0.7 0.7)
					(thickness 0.15)
				)
				(justify left bottom)
			)
		)
		(property "Datasheet" "https://product.tdk.com/en/search/capacitor/ceramic/mlcc/info?part_no=C1608X5R1E106M080AC"
			(at 0 0 90)
			(layer "F.Fab")
			(hide yes)
			(effects
				(font
					(size 1.27 1.27)
					(thickness 0.15)
				)
			)
		)
		(property "Description" "SMD Multilayer Ceramic Capacitor, 10 µF, 25 V, 0603 [1608 Metric], ± 20%, X5R, C"
			(at 0 0 90)
			(layer "F.Fab")
			(hide yes)
			(effects
				(font
					(size 1.27 1.27)
					(thickness 0.15)
				)
			)
		)
		(property "Author" "Antmicro"
			(at 239.776 -138.176 0)
			(layer "F.Fab")
			(hide yes)
			(effects
				(font
					(size 1 1)
					(thickness 0.15)
				)
			)
		)
		(property "Dielectric" ""
			(at 239.776 -138.176 0)
			(layer "F.Fab")
			(hide yes)
			(effects
				(font
					(size 1 1)
					(thickness 0.15)
				)
			)
		)
		(property "License" "Apache-2.0"
			(at 239.776 -138.176 0)
			(layer "F.Fab")
			(hide yes)
			(effects
				(font
					(size 1 1)
					(thickness 0.15)
				)
			)
		)
		(property "MPN" "C1608X5R1E106M080AC"
			(at 239.776 -138.176 0)
			(layer "F.Fab")
			(hide yes)
			(effects
				(font
					(size 1 1)
					(thickness 0.15)
				)
			)
		)
		(property "Manufacturer" "TDK"
			(at 239.776 -138.176 0)
			(layer "F.Fab")
			(hide yes)
			(effects
				(font
					(size 1 1)
					(thickness 0.15)
				)
			)
		)
		(property "Val" "10u"
			(at 239.776 -138.176 0)
			(layer "F.Fab")
			(hide yes)
			(effects
				(font
					(size 1 1)
					(thickness 0.15)
				)
			)
		)
		(property "Voltage" "25V"
			(at 239.776 -138.176 0)
			(layer "F.Fab")
			(hide yes)
			(effects
				(font
					(size 1 1)
					(thickness 0.15)
				)
			)
		)
		(sheetname "/Power/")
		(sheetfile "power.kicad_sch")
		(attr smd)
		(fp_line
			(start -0.15 -0.4)
			(end 0.15 -0.4)
			(stroke
				(width 0.15)
				(type solid)
			)
			(layer "F.SilkS")
		)
		(fp_line
			(start -0.15 0.4)
			(end 0.15 0.4)
			(stroke
				(width 0.15)
				(type solid)
			)
			(layer "F.SilkS")
		)
		(fp_rect
			(start -1.25 -0.65)
			(end 1.25 0.65)
			(stroke
				(width 0.05)
				(type solid)
			)
			(fill no)
			(layer "F.CrtYd")
		)
		(fp_rect
			(start -0.8 -0.4)
			(end 0.8 0.4)
			(stroke
				(width 0.15)
				(type solid)
			)
			(fill no)
			(layer "F.Fab")
		)
		(pad "1" smd roundrect
			(at -0.7 0 90)
			(size 0.8 1)
			(layers "F.Cu" "F.Mask" "F.Paste")
			(roundrect_rratio 0.2)
			(net 1 "GND")
			(pintype "passive")
		)
		(pad "2" smd roundrect
			(at 0.7 0 90)
			(size 0.8 1)
			(layers "F.Cu" "F.Mask" "F.Paste")
			(roundrect_rratio 0.2)
			(net 5 "+5V")
			(pintype "passive")
		)
	)
	(footprint "antmicro-footprints:R_0402_1005Metric"
		(layer "F.Cu")
		(at 181.356 65.024)
		(descr "Resistor SMD 0402")
		(tags "resistor SMD 0402")
		(property "Reference" "R12"
			(at -1.247 9.2202 0)
			(layer "F.SilkS")
			(effects
				(font
					(size 0.7 0.7)
					(thickness 0.15)
				)
				(justify left bottom)
			)
		)
		(property "Value" "R_100R_0402"
			(at -1.011843 1.772047 0)
			(layer "F.Fab")
			(effects
				(font
					(size 0.7 0.7)
					(thickness 0.15)
				)
				(justify left bottom)
			)
		)
		(property "Datasheet" "https://www.bourns.com/docs/product-datasheets/cr.pdf"
			(at 0 0 0)
			(layer "F.Fab")
			(hide yes)
			(effects
				(font
					(size 1.27 1.27)
					(thickness 0.15)
				)
			)
		)
		(property "Description" "SMD Chip Resistor, 100 ohm, ± 1%, 62.5 mW, 0402 [1005 Metric], Thick Film, General Purpose"
			(at 0 0 0)
			(layer "F.Fab")
			(hide yes)
			(effects
				(font
					(size 1.27 1.27)
					(thickness 0.15)
				)
			)
		)
		(property "Author" "Antmicro"
			(at 0 0 0)
			(layer "F.Fab")
			(hide yes)
			(effects
				(font
					(size 1 1)
					(thickness 0.15)
				)
			)
		)
		(property "License" "Apache-2.0"
			(at 0 0 0)
			(layer "F.Fab")
			(hide yes)
			(effects
				(font
					(size 1 1)
					(thickness 0.15)
				)
			)
		)
		(property "MPN" "CR0402-FX-1000GLF"
			(at 0 0 0)
			(layer "F.Fab")
			(hide yes)
			(effects
				(font
					(size 1 1)
					(thickness 0.15)
				)
			)
		)
		(property "Manufacturer" "Bourns"
			(at 0 0 0)
			(layer "F.Fab")
			(hide yes)
			(effects
				(font
					(size 1 1)
					(thickness 0.15)
				)
			)
		)
		(property "Tolerance" "1%"
			(at 0 0 0)
			(layer "F.Fab")
			(hide yes)
			(effects
				(font
					(size 1 1)
					(thickness 0.15)
				)
			)
		)
		(property "Val" "100R"
			(at 0 0 0)
			(layer "F.Fab")
			(hide yes)
			(effects
				(font
					(size 1 1)
					(thickness 0.15)
				)
			)
		)
		(sheetname "/Connectors/")
		(sheetfile "connectors.kicad_sch")
		(attr smd)
		(fp_rect
			(start -0.925 -0.47)
			(end 0.925 0.47)
			(stroke
				(width 0.05)
				(type default)
			)
			(fill no)
			(layer "F.CrtYd")
		)
		(fp_rect
			(start -0.5 -0.25)
			(end 0.5 0.25)
			(stroke
				(width 0.15)
				(type solid)
			)
			(fill no)
			(layer "F.Fab")
		)
		(pad "1" smd roundrect
			(at -0.48 0)
			(size 0.59 0.64)
			(layers "F.Cu" "F.Mask" "F.Paste")
			(roundrect_rratio 0.25)
			(net 44 "/Connectors/SDA_CAM")
			(pintype "passive")
		)
		(pad "2" smd roundrect
			(at 0.48 0)
			(size 0.59 0.64)
			(layers "F.Cu" "F.Mask" "F.Paste")
			(roundrect_rratio 0.25)
			(net 42 "/Connectors/SDA_CAM1")
			(pintype "passive")
		)
	)
	(footprint "antmicro-footprints:R_0402_1005Metric"
		(layer "F.Cu")
		(at 139.192 56.642 90)
		(descr "Resistor SMD 0402")
		(tags "resistor SMD 0402")
		(property "Reference" "R25"
			(at -1.122484 1.262 90)
			(layer "F.SilkS")
			(effects
				(font
					(size 0.7 0.7)
					(thickness 0.15)
				)
				(justify left bottom)
			)
		)
		(property "Value" "R_5k1_0402"
			(at -1.011843 1.772047 90)
			(layer "F.Fab")
			(effects
				(font
					(size 0.7 0.7)
					(thickness 0.15)
				)
				(justify left bottom)
			)
		)
		(property "Datasheet" "https://www.bourns.com/docs/product-datasheets/cr.pdf"
			(at 0 0 90)
			(layer "F.Fab")
			(hide yes)
			(effects
				(font
					(size 1.27 1.27)
					(thickness 0.15)
				)
			)
		)
		(property "Description" "SMD Chip Resistor, 5.1 kohm, ± 1%, 63 mW, 0402 [1005 Metric], Thick Film, General Purpose"
			(at 0 0 90)
			(layer "F.Fab")
			(hide yes)
			(effects
				(font
					(size 1.27 1.27)
					(thickness 0.15)
				)
			)
		)
		(property "Author" "Antmicro"
			(at 195.834 -82.55 0)
			(layer "F.Fab")
			(hide yes)
			(effects
				(font
					(size 1 1)
					(thickness 0.15)
				)
			)
		)
		(property "License" "Apache-2.0"
			(at 195.834 -82.55 0)
			(layer "F.Fab")
			(hide yes)
			(effects
				(font
					(size 1 1)
					(thickness 0.15)
				)
			)
		)
		(property "MPN" "CR0402-FX-5101GLF"
			(at 195.834 -82.55 0)
			(layer "F.Fab")
			(hide yes)
			(effects
				(font
					(size 1 1)
					(thickness 0.15)
				)
			)
		)
		(property "Manufacturer" "Bourns"
			(at 195.834 -82.55 0)
			(layer "F.Fab")
			(hide yes)
			(effects
				(font
					(size 1 1)
					(thickness 0.15)
				)
			)
		)
		(property "Tolerance" "1%"
			(at 195.834 -82.55 0)
			(layer "F.Fab")
			(hide yes)
			(effects
				(font
					(size 1 1)
					(thickness 0.15)
				)
			)
		)
		(property "Val" "5k1"
			(at 195.834 -82.55 0)
			(layer "F.Fab")
			(hide yes)
			(effects
				(font
					(size 1 1)
					(thickness 0.15)
				)
			)
		)
		(sheetname "/Power/")
		(sheetfile "power.kicad_sch")
		(attr smd)
		(fp_rect
			(start -0.925 -0.47)
			(end 0.925 0.47)
			(stroke
				(width 0.05)
				(type default)
			)
			(fill no)
			(layer "F.CrtYd")
		)
		(fp_rect
			(start -0.5 -0.25)
			(end 0.5 0.25)
			(stroke
				(width 0.15)
				(type solid)
			)
			(fill no)
			(layer "F.Fab")
		)
		(pad "1" smd roundrect
			(at -0.48 0 90)
			(size 0.59 0.64)
			(layers "F.Cu" "F.Mask" "F.Paste")
			(roundrect_rratio 0.25)
			(net 52 "Net-(L2-Pad2)")
			(pintype "passive")
		)
		(pad "2" smd roundrect
			(at 0.48 0 90)
			(size 0.59 0.64)
			(layers "F.Cu" "F.Mask" "F.Paste")
			(roundrect_rratio 0.25)
			(net 56 "Net-(L10-Pad1)")
			(pintype "passive")
		)
	)
	(footprint "antmicro-footprints:L_Coilcraft-MSS6132T"
		(layer "F.Cu")
		(at 146.558 61.976 90)
		(property "Reference" "L3"
			(at -0.635 -3.429 90)
			(layer "F.SilkS")
			(effects
				(font
					(size 0.7 0.7)
					(thickness 0.15)
				)
				(justify left bottom)
			)
		)
		(property "Value" "L_22u_1.12A_Coilcraft-MSS6132T"
			(at -0.508 4.826 90)
			(layer "F.Fab")
			(effects
				(font
					(size 0.7 0.7)
					(thickness 0.15)
				)
				(justify left bottom)
			)
		)
		(property "Datasheet" "https://www.coilcraft.com/getmedia/d035c9b3-191d-46aa-ab3f-5c1a849157c1/mss6132t.pdf"
			(at 0 0 90)
			(layer "F.Fab")
			(hide yes)
			(effects
				(font
					(size 1.27 1.27)
					(thickness 0.15)
				)
			)
		)
		(property "Description" "Power Inductor (SMT), 22 µH, 1.85 A, Shielded, 2.45 A, WE-MAPI"
			(at 0 0 90)
			(layer "F.Fab")
			(hide yes)
			(effects
				(font
					(size 1.27 1.27)
					(thickness 0.15)
				)
			)
		)
		(property "Author" "Antmicro"
			(at 208.534 -84.582 0)
			(layer "F.Fab")
			(hide yes)
			(effects
				(font
					(size 1 1)
					(thickness 0.15)
				)
			)
		)
		(property "IMax" "1.45A"
			(at 208.534 -84.582 0)
			(layer "F.Fab")
			(hide yes)
			(effects
				(font
					(size 1 1)
					(thickness 0.15)
				)
			)
		)
		(property "ISat" "1.12A"
			(at 208.534 -84.582 0)
			(layer "F.Fab")
			(hide yes)
			(effects
				(font
					(size 1 1)
					(thickness 0.15)
				)
			)
		)
		(property "License" "Apache-2.0"
			(at 208.534 -84.582 0)
			(layer "F.Fab")
			(hide yes)
			(effects
				(font
					(size 1 1)
					(thickness 0.15)
				)
			)
		)
		(property "MPN" "MSS6132T-223"
			(at 208.534 -84.582 0)
			(layer "F.Fab")
			(hide yes)
			(effects
				(font
					(size 1 1)
					(thickness 0.15)
				)
			)
		)
		(property "Manufacturer" "Coilcraft"
			(at 208.534 -84.582 0)
			(layer "F.Fab")
			(hide yes)
			(effects
				(font
					(size 1 1)
					(thickness 0.15)
				)
			)
		)
		(property "Size" "6.1x6.1"
			(at 208.534 -84.582 0)
			(layer "F.Fab")
			(hide yes)
			(effects
				(font
					(size 1 1)
					(thickness 0.15)
				)
			)
		)
		(property "Val" "22u/1.12A"
			(at 208.534 -84.582 0)
			(layer "F.Fab")
			(hide yes)
			(effects
				(font
					(size 1 1)
					(thickness 0.15)
				)
			)
		)
		(sheetname "/Power/")
		(sheetfile "power.kicad_sch")
		(attr smd)
		(fp_line
			(start -0.8 -3.05)
			(end 0.8 -3.05)
			(stroke
				(width 0.15)
				(type solid)
			)
			(layer "F.SilkS")
		)
		(fp_line
			(start -0.8 3.05)
			(end 0.8 3.05)
			(stroke
				(width 0.15)
				(type solid)
			)
			(layer "F.SilkS")
		)
		(fp_rect
			(start -3.35 -3.35)
			(end 3.35 3.35)
			(stroke
				(width 0.05)
				(type solid)
			)
			(fill no)
			(layer "F.CrtYd")
		)
		(fp_rect
			(start -3.1 -3.1)
			(end 3.1 3.1)
			(stroke
				(width 0.15)
				(type solid)
			)
			(fill no)
			(layer "F.Fab")
		)
		(pad "1" smd custom
			(at -2.71 0 180)
			(size 6 0.575)
			(layers "F.Cu" "F.Mask" "F.Paste")
			(net 4 "+12V")
			(pintype "passive")
			(options
				(clearance outline)
				(anchor rect)
			)
			(primitives
				(gr_poly
					(pts
						(xy 2.4 1.71) (xy 2.117646 1.21) (xy 1.9 0.96) (xy 1.65 0.71) (xy 1.2 0.41) (xy 0.4 0.11) (xy 0.4 0.01)
						(xy 2.9 0) (xy 2.9 1.71)
					)
					(width 0.2)
					(fill yes)
				)
				(gr_poly
					(pts
						(xy -2.4 1.731128) (xy -2.117646 1.231128) (xy -1.9 0.981128) (xy -1.65 0.731128) (xy -1.2 0.431128)
						(xy -0.4 0.131128) (xy -0.4 0.031128) (xy -2.9 0.021128) (xy -2.9 1.731128)
					)
					(width 0.2)
					(fill yes)
				)
			)
		)
		(pad "2" smd custom
			(at 2.71 0)
			(size 6 0.575)
			(layers "F.Cu" "F.Mask" "F.Paste")
			(net 53 "Net-(L3-Pad2)")
			(pintype "passive")
			(options
				(clearance outline)
				(anchor rect)
			)
			(primitives
				(gr_poly
					(pts
						(xy -2.4 1.731128) (xy -2.117646 1.231128) (xy -1.9 0.981128) (xy -1.65 0.731128) (xy -1.2 0.431128)
						(xy -0.4 0.131128) (xy -0.4 0.031128) (xy -2.9 0.021128) (xy -2.9 1.731128)
					)
					(width 0.2)
					(fill yes)
				)
				(gr_poly
					(pts
						(xy 2.4 1.71) (xy 2.117646 1.21) (xy 1.9 0.96) (xy 1.65 0.71) (xy 1.2 0.41) (xy 0.4 0.11) (xy 0.4 0.01)
						(xy 2.9 0) (xy 2.9 1.71)
					)
					(width 0.2)
					(fill yes)
				)
			)
		)
	)
	(footprint "antmicro-footprints:TP_SMD_0.75mm"
		(layer "F.Cu")
		(at 149.352 97.89)
		(property "Reference" "TP10"
			(at 0 -0.6 0)
			(layer "F.SilkS")
			(hide yes)
			(effects
				(font
					(size 0.7 0.7)
					(thickness 0.15)
				)
				(justify left bottom)
			)
		)
		(property "Value" "TP_0.75mm_SMD"
			(at 0 1.2 0)
			(layer "F.Fab")
			(effects
				(font
					(size 0.7 0.7)
					(thickness 0.15)
				)
				(justify left bottom)
			)
		)
		(property "Description" "SMT test point"
			(at 0 0 0)
			(layer "F.Fab")
			(hide yes)
			(effects
				(font
					(size 1.27 1.27)
					(thickness 0.15)
				)
			)
		)
		(property "Author" "Antmicro"
			(at 0 0 0)
			(layer "F.Fab")
			(hide yes)
			(effects
				(font
					(size 1 1)
					(thickness 0.15)
				)
			)
		)
		(property "License" "Apache-2.0"
			(at 0 0 0)
			(layer "F.Fab")
			(hide yes)
			(effects
				(font
					(size 1 1)
					(thickness 0.15)
				)
			)
		)
		(property "MPN" ""
			(at 0 0 0)
			(layer "F.Fab")
			(hide yes)
			(effects
				(font
					(size 1 1)
					(thickness 0.15)
				)
			)
		)
		(property "Manufacturer" ""
			(at 0 0 0)
			(layer "F.Fab")
			(hide yes)
			(effects
				(font
					(size 1 1)
					(thickness 0.15)
				)
			)
		)
		(sheetname "/Power/")
		(sheetfile "power.kicad_sch")
		(fp_circle
			(center 0 0)
			(end 0.475 0)
			(stroke
				(width 0.05)
				(type default)
			)
			(fill no)
			(layer "F.CrtYd")
		)
		(pad "1" smd circle
			(at 0 0)
			(size 0.75 0.75)
			(layers "F.Cu" "F.Mask")
			(net 4 "+12V")
			(pinfunction "1")
			(pintype "passive")
		)
	)
	(footprint "antmicro-footprints:C_0402_1005Metric"
		(layer "F.Cu")
		(at 134.294 66.548 90)
		(descr "Capacitor SMD 0402")
		(tags "capacitor SMD 0402")
		(property "Reference" "C7"
			(at -1.397 -0.563 90)
			(layer "F.SilkS")
			(effects
				(font
					(size 0.7 0.7)
					(thickness 0.15)
				)
				(justify left bottom)
			)
		)
		(property "Value" "C_100n_0402"
			(at -1.022927 2.155213 90)
			(layer "F.Fab")
			(effects
				(font
					(size 0.7 0.7)
					(thickness 0.15)
				)
				(justify left bottom)
			)
		)
		(property "Datasheet" "https://www.murata.com/products/productdetail?partno=GRM155R61H104KE14%23"
			(at 0 0 90)
			(layer "F.Fab")
			(hide yes)
			(effects
				(font
					(size 1.27 1.27)
					(thickness 0.15)
				)
			)
		)
		(property "Description" "SMD Multilayer Ceramic Capacitor, 0.1 µF, 50 V, 0402 [1005 Metric], ± 10%, X5R, GRM Series"
			(at 0 0 90)
			(layer "F.Fab")
			(hide yes)
			(effects
				(font
					(size 1.27 1.27)
					(thickness 0.15)
				)
			)
		)
		(property "Author" "Antmicro"
			(at 200.842 -67.746 0)
			(layer "F.Fab")
			(hide yes)
			(effects
				(font
					(size 1 1)
					(thickness 0.15)
				)
			)
		)
		(property "Dielectric" "X5R"
			(at 200.842 -67.746 0)
			(layer "F.Fab")
			(hide yes)
			(effects
				(font
					(size 1 1)
					(thickness 0.15)
				)
			)
		)
		(property "License" "Apache-2.0"
			(at 200.842 -67.746 0)
			(layer "F.Fab")
			(hide yes)
			(effects
				(font
					(size 1 1)
					(thickness 0.15)
				)
			)
		)
		(property "MPN" "GRM155R61H104KE14D"
			(at 200.842 -67.746 0)
			(layer "F.Fab")
			(hide yes)
			(effects
				(font
					(size 1 1)
					(thickness 0.15)
				)
			)
		)
		(property "Manufacturer" "Murata"
			(at 200.842 -67.746 0)
			(layer "F.Fab")
			(hide yes)
			(effects
				(font
					(size 1 1)
					(thickness 0.15)
				)
			)
		)
		(property "Val" "100n"
			(at 200.842 -67.746 0)
			(layer "F.Fab")
			(hide yes)
			(effects
				(font
					(size 1 1)
					(thickness 0.15)
				)
			)
		)
		(property "Voltage" "50V"
			(at 200.842 -67.746 0)
			(layer "F.Fab")
			(hide yes)
			(effects
				(font
					(size 1 1)
					(thickness 0.15)
				)
			)
		)
		(sheetname "/Power/")
		(sheetfile "power.kicad_sch")
		(attr smd)
		(fp_rect
			(start -0.925 -0.47)
			(end 0.925 0.47)
			(stroke
				(width 0.05)
				(type default)
			)
			(fill no)
			(layer "F.CrtYd")
		)
		(fp_line
			(start 0.504 -0.25)
			(end 0.504 0.248)
			(stroke
				(width 0.15)
				(type solid)
			)
			(layer "F.Fab")
		)
		(fp_line
			(start -0.494 -0.25)
			(end 0.504 -0.25)
			(stroke
				(width 0.15)
				(type solid)
			)
			(layer "F.Fab")
		)
		(fp_line
			(start 0.504 0.248)
			(end -0.494 0.248)
			(stroke
				(width 0.15)
				(type solid)
			)
			(layer "F.Fab")
		)
		(fp_line
			(start -0.494 0.248)
			(end -0.494 -0.25)
			(stroke
				(width 0.15)
				(type solid)
			)
			(layer "F.Fab")
		)
		(pad "1" smd roundrect
			(at -0.48 0 90)
			(size 0.59 0.64)
			(layers "F.Cu" "F.Mask" "F.Paste")
			(roundrect_rratio 0.25)
			(net 1 "GND")
			(pintype "passive")
		)
		(pad "2" smd roundrect
			(at 0.48 0 90)
			(size 0.59 0.64)
			(layers "F.Cu" "F.Mask" "F.Paste")
			(roundrect_rratio 0.25)
			(net 4 "+12V")
			(pintype "passive")
		)
	)
	(footprint "antmicro-footprints:R_0402_1005Metric"
		(layer "F.Cu")
		(at 150.614 61.976 90)
		(descr "Resistor SMD 0402")
		(tags "resistor SMD 0402")
		(property "Reference" "R21"
			(at -1.1405 1.27 90)
			(layer "F.SilkS")
			(effects
				(font
					(size 0.7 0.7)
					(thickness 0.15)
				)
				(justify left bottom)
			)
		)
		(property "Value" "R_5k1_0402"
			(at -1.011843 1.772047 90)
			(layer "F.Fab")
			(effects
				(font
					(size 0.7 0.7)
					(thickness 0.15)
				)
				(justify left bottom)
			)
		)
		(property "Datasheet" "https://www.bourns.com/docs/product-datasheets/cr.pdf"
			(at 0 0 90)
			(layer "F.Fab")
			(hide yes)
			(effects
				(font
					(size 1.27 1.27)
					(thickness 0.15)
				)
			)
		)
		(property "Description" "SMD Chip Resistor, 5.1 kohm, ± 1%, 63 mW, 0402 [1005 Metric], Thick Film, General Purpose"
			(at 0 0 90)
			(layer "F.Fab")
			(hide yes)
			(effects
				(font
					(size 1.27 1.27)
					(thickness 0.15)
				)
			)
		)
		(property "Author" "Antmicro"
			(at 212.59 -88.638 0)
			(layer "F.Fab")
			(hide yes)
			(effects
				(font
					(size 1 1)
					(thickness 0.15)
				)
			)
		)
		(property "License" "Apache-2.0"
			(at 212.59 -88.638 0)
			(layer "F.Fab")
			(hide yes)
			(effects
				(font
					(size 1 1)
					(thickness 0.15)
				)
			)
		)
		(property "MPN" "CR0402-FX-5101GLF"
			(at 212.59 -88.638 0)
			(layer "F.Fab")
			(hide yes)
			(effects
				(font
					(size 1 1)
					(thickness 0.15)
				)
			)
		)
		(property "Manufacturer" "Bourns"
			(at 212.59 -88.638 0)
			(layer "F.Fab")
			(hide yes)
			(effects
				(font
					(size 1 1)
					(thickness 0.15)
				)
			)
		)
		(property "Tolerance" "1%"
			(at 212.59 -88.638 0)
			(layer "F.Fab")
			(hide yes)
			(effects
				(font
					(size 1 1)
					(thickness 0.15)
				)
			)
		)
		(property "Val" "5k1"
			(at 212.59 -88.638 0)
			(layer "F.Fab")
			(hide yes)
			(effects
				(font
					(size 1 1)
					(thickness 0.15)
				)
			)
		)
		(sheetname "/Power/")
		(sheetfile "power.kicad_sch")
		(attr smd)
		(fp_rect
			(start -0.925 -0.47)
			(end 0.925 0.47)
			(stroke
				(width 0.05)
				(type default)
			)
			(fill no)
			(layer "F.CrtYd")
		)
		(fp_rect
			(start -0.5 -0.25)
			(end 0.5 0.25)
			(stroke
				(width 0.15)
				(type solid)
			)
			(fill no)
			(layer "F.Fab")
		)
		(pad "1" smd roundrect
			(at -0.48 0 90)
			(size 0.59 0.64)
			(layers "F.Cu" "F.Mask" "F.Paste")
			(roundrect_rratio 0.25)
			(net 4 "+12V")
			(pintype "passive")
		)
		(pad "2" smd roundrect
			(at 0.48 0 90)
			(size 0.59 0.64)
			(layers "F.Cu" "F.Mask" "F.Paste")
			(roundrect_rratio 0.25)
			(net 53 "Net-(L3-Pad2)")
			(pintype "passive")
		)
	)
	(footprint "antmicro-footprints:R_0402_1005Metric"
		(layer "F.Cu")
		(at 184.079 50.7008 -90)
		(descr "Resistor SMD 0402")
		(tags "resistor SMD 0402")
		(property "Reference" "R39"
			(at -1.016 0.763 90)
			(layer "F.SilkS")
			(effects
				(font
					(size 0.7 0.7)
					(thickness 0.15)
				)
				(justify right bottom)
			)
		)
		(property "Value" "R_10k_0402"
			(at -1.011843 1.772047 90)
			(layer "F.Fab")
			(effects
				(font
					(size 0.7 0.7)
					(thickness 0.15)
				)
				(justify right bottom)
			)
		)
		(property "Datasheet" "https://www.bourns.com/docs/product-datasheets/cr.pdf"
			(at 0 0 270)
			(layer "F.Fab")
			(hide yes)
			(effects
				(font
					(size 1.27 1.27)
					(thickness 0.15)
				)
			)
		)
		(property "Description" "SMD Chip Resistor, 10 kohm, ± 1%, 62.5 mW, 0402 [1005 Metric], Thick Film, General Purpose"
			(at 0 0 270)
			(layer "F.Fab")
			(hide yes)
			(effects
				(font
					(size 1.27 1.27)
					(thickness 0.15)
				)
			)
		)
		(property "Author" "Antmicro"
			(at 133.3782 234.7798 0)
			(layer "F.Fab")
			(hide yes)
			(effects
				(font
					(size 1 1)
					(thickness 0.15)
				)
			)
		)
		(property "License" "Apache-2.0"
			(at 133.3782 234.7798 0)
			(layer "F.Fab")
			(hide yes)
			(effects
				(font
					(size 1 1)
					(thickness 0.15)
				)
			)
		)
		(property "MPN" "CR0402-FX-1002GLF"
			(at 133.3782 234.7798 0)
			(layer "F.Fab")
			(hide yes)
			(effects
				(font
					(size 1 1)
					(thickness 0.15)
				)
			)
		)
		(property "Manufacturer" "Bourns"
			(at 133.3782 234.7798 0)
			(layer "F.Fab")
			(hide yes)
			(effects
				(font
					(size 1 1)
					(thickness 0.15)
				)
			)
		)
		(property "Tolerance" "1%"
			(at 133.3782 234.7798 0)
			(layer "F.Fab")
			(hide yes)
			(effects
				(font
					(size 1 1)
					(thickness 0.15)
				)
			)
		)
		(property "Val" "10k"
			(at 133.3782 234.7798 0)
			(layer "F.Fab")
			(hide yes)
			(effects
				(font
					(size 1 1)
					(thickness 0.15)
				)
			)
		)
		(sheetname "/Power/")
		(sheetfile "power.kicad_sch")
		(attr smd)
		(fp_rect
			(start -0.925 -0.47)
			(end 0.925 0.47)
			(stroke
				(width 0.05)
				(type default)
			)
			(fill no)
			(layer "F.CrtYd")
		)
		(fp_rect
			(start -0.5 -0.25)
			(end 0.5 0.25)
			(stroke
				(width 0.15)
				(type solid)
			)
			(fill no)
			(layer "F.Fab")
		)
		(pad "1" smd roundrect
			(at -0.48 0 270)
			(size 0.59 0.64)
			(layers "F.Cu" "F.Mask" "F.Paste")
			(roundrect_rratio 0.25)
			(net 72 "/Power/FFC_5V_FLG")
			(pintype "passive")
		)
		(pad "2" smd roundrect
			(at 0.48 0 270)
			(size 0.59 0.64)
			(layers "F.Cu" "F.Mask" "F.Paste")
			(roundrect_rratio 0.25)
			(net 3 "+1V8")
			(pintype "passive")
		)
	)
	(footprint "antmicro-footprints:C_0402_1005Metric"
		(layer "F.Cu")
		(at 141.351 75.057 135)
		(descr "Capacitor SMD 0402")
		(tags "capacitor SMD 0402")
		(property "Reference" "C33"
			(at 6.272037 -0.486489 315)
			(unlocked yes)
			(layer "F.SilkS")
			(effects
				(font
					(size 0.7 0.7)
					(thickness 0.15)
				)
				(justify left bottom)
			)
		)
		(property "Value" "C_100n_0402"
			(at -1.022927 2.155213 135)
			(layer "F.Fab")
			(effects
				(font
					(size 0.7 0.7)
					(thickness 0.15)
				)
				(justify left bottom)
			)
		)
		(property "Datasheet" "https://www.murata.com/products/productdetail?partno=GRM155R61H104KE14%23"
			(at 0 0 135)
			(layer "F.Fab")
			(hide yes)
			(effects
				(font
					(size 1.27 1.27)
					(thickness 0.15)
				)
			)
		)
		(property "Description" "SMD Multilayer Ceramic Capacitor, 0.1 µF, 50 V, 0402 [1005 Metric], ± 10%, X5R, GRM Series"
			(at 0 0 135)
			(layer "F.Fab")
			(hide yes)
			(effects
				(font
					(size 1.27 1.27)
					(thickness 0.15)
				)
			)
		)
		(property "Author" "Antmicro"
			(at 294.374564 28.180063 0)
			(layer "F.Fab")
			(hide yes)
			(effects
				(font
					(size 1 1)
					(thickness 0.15)
				)
			)
		)
		(property "Dielectric" "X5R"
			(at 294.374564 28.180063 0)
			(layer "F.Fab")
			(hide yes)
			(effects
				(font
					(size 1 1)
					(thickness 0.15)
				)
			)
		)
		(property "License" "Apache-2.0"
			(at 294.374564 28.180063 0)
			(layer "F.Fab")
			(hide yes)
			(effects
				(font
					(size 1 1)
					(thickness 0.15)
				)
			)
		)
		(property "MPN" "GRM155R61H104KE14D"
			(at 294.374564 28.180063 0)
			(layer "F.Fab")
			(hide yes)
			(effects
				(font
					(size 1 1)
					(thickness 0.15)
				)
			)
		)
		(property "Manufacturer" "Murata"
			(at 294.374564 28.180063 0)
			(layer "F.Fab")
			(hide yes)
			(effects
				(font
					(size 1 1)
					(thickness 0.15)
				)
			)
		)
		(property "Val" "100n"
			(at 294.374564 28.180063 0)
			(layer "F.Fab")
			(hide yes)
			(effects
				(font
					(size 1 1)
					(thickness 0.15)
				)
			)
		)
		(property "Voltage" "50V"
			(at 294.374564 28.180063 0)
			(layer "F.Fab")
			(hide yes)
			(effects
				(font
					(size 1 1)
					(thickness 0.15)
				)
			)
		)
		(sheetname "/Deserializer/")
		(sheetfile "deserializer.kicad_sch")
		(attr smd)
		(fp_poly
			(pts
				(xy -0.925 -0.47) (xy 0.925 -0.47) (xy 0.925 0.47) (xy -0.925 0.47)
			)
			(stroke
				(width 0.05)
				(type default)
			)
			(fill no)
			(layer "F.CrtYd")
		)
		(fp_line
			(start 0.504 -0.25)
			(end 0.504 0.248)
			(stroke
				(width 0.15)
				(type solid)
			)
			(layer "F.Fab")
		)
		(fp_line
			(start 0.504 0.248)
			(end -0.494 0.248)
			(stroke
				(width 0.15)
				(type solid)
			)
			(layer "F.Fab")
		)
		(fp_line
			(start -0.494 -0.25)
			(end 0.504 -0.25)
			(stroke
				(width 0.15)
				(type solid)
			)
			(layer "F.Fab")
		)
		(fp_line
			(start -0.494 0.248)
			(end -0.494 -0.25)
			(stroke
				(width 0.15)
				(type solid)
			)
			(layer "F.Fab")
		)
		(pad "1" smd roundrect
			(at -0.48 0 135)
			(size 0.59 0.64)
			(layers "F.Cu" "F.Mask" "F.Paste")
			(roundrect_rratio 0.25)
			(net 20 "/Deserializer/SIOB_N")
			(pintype "passive")
		)
		(pad "2" smd roundrect
			(at 0.48 0 135)
			(size 0.59 0.64)
			(layers "F.Cu" "F.Mask" "F.Paste")
			(roundrect_rratio 0.25)
			(net 21 "Net-(C33-Pad2)")
			(pintype "passive")
		)
	)
	(footprint "antmicro-footprints:C_0402_1005Metric"
		(layer "F.Cu")
		(at 144.653 71.628 -90)
		(descr "Capacitor SMD 0402")
		(tags "capacitor SMD 0402")
		(property "Reference" "C57"
			(at -3.0226 -0.3302 90)
			(layer "F.SilkS")
			(effects
				(font
					(size 0.7 0.7)
					(thickness 0.15)
				)
				(justify right bottom)
			)
		)
		(property "Value" "C_33p_0402"
			(at -1.022927 2.155213 90)
			(layer "F.Fab")
			(effects
				(font
					(size 0.7 0.7)
					(thickness 0.15)
				)
				(justify right bottom)
			)
		)
		(property "Datasheet" "https://spicat.kyocera-avx.com/product/mlcc/chartview/04025A330FAT2A/"
			(at 0 0 270)
			(layer "F.Fab")
			(hide yes)
			(effects
				(font
					(size 1.27 1.27)
					(thickness 0.15)
				)
			)
		)
		(property "Description" "SMD Multilayer Ceramic Capacitor, 33 pF, 50 V, 0402 [1005 Metric], ± 5%, C0G / NP0, MC"
			(at 0 0 270)
			(layer "F.Fab")
			(hide yes)
			(effects
				(font
					(size 1.27 1.27)
					(thickness 0.15)
				)
			)
		)
		(property "Author" "Antmicro"
			(at 73.025 216.281 0)
			(layer "F.Fab")
			(hide yes)
			(effects
				(font
					(size 1 1)
					(thickness 0.15)
				)
			)
		)
		(property "Dielectric" ""
			(at 73.025 216.281 0)
			(layer "F.Fab")
			(hide yes)
			(effects
				(font
					(size 1 1)
					(thickness 0.15)
				)
			)
		)
		(property "License" "Apache-2.0"
			(at 73.025 216.281 0)
			(layer "F.Fab")
			(hide yes)
			(effects
				(font
					(size 1 1)
					(thickness 0.15)
				)
			)
		)
		(property "MPN" "04025A330FAT2A"
			(at 73.025 216.281 0)
			(layer "F.Fab")
			(hide yes)
			(effects
				(font
					(size 1 1)
					(thickness 0.15)
				)
			)
		)
		(property "Manufacturer" "KYOCERA AVX"
			(at 73.025 216.281 0)
			(layer "F.Fab")
			(hide yes)
			(effects
				(font
					(size 1 1)
					(thickness 0.15)
				)
			)
		)
		(property "Val" "33p"
			(at 73.025 216.281 0)
			(layer "F.Fab")
			(hide yes)
			(effects
				(font
					(size 1 1)
					(thickness 0.15)
				)
			)
		)
		(property "Voltage" ""
			(at 73.025 216.281 0)
			(layer "F.Fab")
			(hide yes)
			(effects
				(font
					(size 1 1)
					(thickness 0.15)
				)
			)
		)
		(sheetname "/Deserializer/")
		(sheetfile "deserializer.kicad_sch")
		(attr smd)
		(fp_rect
			(start -0.925 -0.47)
			(end 0.925 0.47)
			(stroke
				(width 0.05)
				(type default)
			)
			(fill no)
			(layer "F.CrtYd")
		)
		(fp_line
			(start -0.494 0.248)
			(end -0.494 -0.25)
			(stroke
				(width 0.15)
				(type solid)
			)
			(layer "F.Fab")
		)
		(fp_line
			(start 0.504 0.248)
			(end -0.494 0.248)
			(stroke
				(width 0.15)
				(type solid)
			)
			(layer "F.Fab")
		)
		(fp_line
			(start -0.494 -0.25)
			(end 0.504 -0.25)
			(stroke
				(width 0.15)
				(type solid)
			)
			(layer "F.Fab")
		)
		(fp_line
			(start 0.504 -0.25)
			(end 0.504 0.248)
			(stroke
				(width 0.15)
				(type solid)
			)
			(layer "F.Fab")
		)
		(pad "1" smd roundrect
			(at -0.48 0 270)
			(size 0.59 0.64)
			(layers "F.Cu" "F.Mask" "F.Paste")
			(roundrect_rratio 0.25)
			(net 1 "GND")
			(pintype "passive")
		)
		(pad "2" smd roundrect
			(at 0.48 0 270)
			(size 0.59 0.64)
			(layers "F.Cu" "F.Mask" "F.Paste")
			(roundrect_rratio 0.25)
			(net 17 "/Deserializer/X2_R")
			(pintype "passive")
		)
	)
	(footprint "antmicro-footprints:SOD-523_NP"
		(layer "F.Cu")
		(at 179.705 64.516 -90)
		(property "Reference" "D8"
			(at 8.636 -0.381 90)
			(layer "F.SilkS")
			(effects
				(font
					(size 0.7 0.7)
					(thickness 0.15)
				)
				(justify right bottom)
			)
		)
		(property "Value" "ESD5B5_0ST1G"
			(at 0 1.499 90)
			(layer "F.Fab")
			(effects
				(font
					(size 0.7 0.7)
					(thickness 0.15)
				)
				(justify right bottom)
			)
		)
		(property "Datasheet" "https://www.onsemi.com/pdf/datasheet/esd5b5.0st1-d.pdf"
			(at 0 0 270)
			(layer "F.Fab")
			(hide yes)
			(effects
				(font
					(size 1.27 1.27)
					(thickness 0.15)
				)
			)
		)
		(property "Description" "Bidirectional TVS, 30 kV,  SOD-523, 5 V, 32 pF"
			(at 0 0 270)
			(layer "F.Fab")
			(hide yes)
			(effects
				(font
					(size 1.27 1.27)
					(thickness 0.15)
				)
			)
		)
		(property "Author" "Antmicro"
			(at 115.189 244.221 0)
			(layer "F.Fab")
			(hide yes)
			(effects
				(font
					(size 1 1)
					(thickness 0.15)
				)
			)
		)
		(property "License" "Apache-2.0"
			(at 115.189 244.221 0)
			(layer "F.Fab")
			(hide yes)
			(effects
				(font
					(size 1 1)
					(thickness 0.15)
				)
			)
		)
		(property "MPN" "ESD5B5.0ST1G"
			(at 115.189 244.221 0)
			(layer "F.Fab")
			(hide yes)
			(effects
				(font
					(size 1 1)
					(thickness 0.15)
				)
			)
		)
		(property "Manufacturer" "ON Semiconductor"
			(at 115.189 244.221 0)
			(layer "F.Fab")
			(hide yes)
			(effects
				(font
					(size 1 1)
					(thickness 0.15)
				)
			)
		)
		(sheetname "/Connectors/")
		(sheetfile "connectors.kicad_sch")
		(attr smd)
		(fp_rect
			(start -1 -0.6)
			(end 1 0.6)
			(stroke
				(width 0.05)
				(type solid)
			)
			(fill no)
			(layer "F.CrtYd")
		)
		(fp_line
			(start -0.652 0.423)
			(end 0.65 0.423)
			(stroke
				(width 0.15)
				(type solid)
			)
			(layer "F.Fab")
		)
		(fp_line
			(start -0.652 0.423)
			(end -0.652 -0.425)
			(stroke
				(width 0.15)
				(type solid)
			)
			(layer "F.Fab")
		)
		(fp_line
			(start -0.652 -0.425)
			(end 0.65 -0.425)
			(stroke
				(width 0.15)
				(type solid)
			)
			(layer "F.Fab")
		)
		(fp_line
			(start 0.65 -0.425)
			(end 0.65 0.423)
			(stroke
				(width 0.15)
				(type solid)
			)
			(layer "F.Fab")
		)
		(pad "1" smd roundrect
			(at -0.701 0 270)
			(size 0.5 0.6)
			(layers "F.Cu" "F.Mask" "F.Paste")
			(roundrect_rratio 0.25)
			(net 1 "GND")
			(pinfunction "C")
			(pintype "passive")
		)
		(pad "2" smd roundrect
			(at 0.699 0 270)
			(size 0.5 0.6)
			(layers "F.Cu" "F.Mask" "F.Paste")
			(roundrect_rratio 0.25)
			(net 44 "/Connectors/SDA_CAM")
			(pinfunction "A")
			(pintype "passive")
		)
	)
	(footprint "antmicro-footprints:R_0402_1005Metric"
		(layer "F.Cu")
		(at 172.212 60.071 90)
		(descr "Resistor SMD 0402")
		(tags "resistor SMD 0402")
		(property "Reference" "R1"
			(at -0.813323 1.238 270)
			(layer "F.SilkS")
			(effects
				(font
					(size 0.7 0.7)
					(thickness 0.15)
				)
				(justify left bottom)
			)
		)
		(property "Value" "R_10k_0402"
			(at -1.011843 1.772047 90)
			(layer "F.Fab")
			(effects
				(font
					(size 0.7 0.7)
					(thickness 0.15)
				)
				(justify left bottom)
			)
		)
		(property "Datasheet" "https://www.bourns.com/docs/product-datasheets/cr.pdf"
			(at 0 0 90)
			(layer "F.Fab")
			(hide yes)
			(effects
				(font
					(size 1.27 1.27)
					(thickness 0.15)
				)
			)
		)
		(property "Description" "SMD Chip Resistor, 10 kohm, ± 1%, 62.5 mW, 0402 [1005 Metric], Thick Film, General Purpose"
			(at 0 0 90)
			(layer "F.Fab")
			(hide yes)
			(effects
				(font
					(size 1.27 1.27)
					(thickness 0.15)
				)
			)
		)
		(property "Author" "Antmicro"
			(at 232.283 -112.141 0)
			(layer "F.Fab")
			(hide yes)
			(effects
				(font
					(size 1 1)
					(thickness 0.15)
				)
			)
		)
		(property "License" "Apache-2.0"
			(at 232.283 -112.141 0)
			(layer "F.Fab")
			(hide yes)
			(effects
				(font
					(size 1 1)
					(thickness 0.15)
				)
			)
		)
		(property "MPN" "CR0402-FX-1002GLF"
			(at 232.283 -112.141 0)
			(layer "F.Fab")
			(hide yes)
			(effects
				(font
					(size 1 1)
					(thickness 0.15)
				)
			)
		)
		(property "Manufacturer" "Bourns"
			(at 232.283 -112.141 0)
			(layer "F.Fab")
			(hide yes)
			(effects
				(font
					(size 1 1)
					(thickness 0.15)
				)
			)
		)
		(property "Tolerance" "1%"
			(at 232.283 -112.141 0)
			(layer "F.Fab")
			(hide yes)
			(effects
				(font
					(size 1 1)
					(thickness 0.15)
				)
			)
		)
		(property "Val" "10k"
			(at 232.283 -112.141 0)
			(layer "F.Fab")
			(hide yes)
			(effects
				(font
					(size 1 1)
					(thickness 0.15)
				)
			)
		)
		(sheetname "/Connectors/")
		(sheetfile "connectors.kicad_sch")
		(attr smd)
		(fp_rect
			(start -0.925 -0.47)
			(end 0.925 0.47)
			(stroke
				(width 0.05)
				(type default)
			)
			(fill no)
			(layer "F.CrtYd")
		)
		(fp_rect
			(start -0.5 -0.25)
			(end 0.5 0.25)
			(stroke
				(width 0.15)
				(type solid)
			)
			(fill no)
			(layer "F.Fab")
		)
		(pad "1" smd roundrect
			(at -0.48 0 90)
			(size 0.59 0.64)
			(layers "F.Cu" "F.Mask" "F.Paste")
			(roundrect_rratio 0.25)
			(net 1 "GND")
			(pintype "passive")
		)
		(pad "2" smd roundrect
			(at 0.48 0 90)
			(size 0.59 0.64)
			(layers "F.Cu" "F.Mask" "F.Paste")
			(roundrect_rratio 0.25)
			(net 129 "Net-(U1-~{OE})")
			(pintype "passive")
		)
	)
	(footprint "antmicro-footprints:SOT-23-3"
		(layer "F.Cu")
		(at 179.324 52.832 -90)
		(property "Reference" "Q1"
			(at -1.016 -2.54 90)
			(layer "F.SilkS")
			(effects
				(font
					(size 0.7 0.7)
					(thickness 0.15)
				)
				(justify right bottom)
			)
		)
		(property "Value" "BSS138AKA"
			(at -1.9 2.7 90)
			(layer "F.Fab")
			(effects
				(font
					(size 0.7 0.7)
					(thickness 0.15)
				)
				(justify right bottom)
			)
		)
		(property "Datasheet" "https://www.onsemi.com/pub/Collateral/BSS138-D.PDF"
			(at 0 0 270)
			(layer "F.Fab")
			(hide yes)
			(effects
				(font
					(size 1.27 1.27)
					(thickness 0.15)
				)
			)
		)
		(property "Description" "Power MOSFET, N Channel, 50 V, 220 mA, 6.0 ohm, SOT-23, Surface Mount"
			(at 0 0 270)
			(layer "F.Fab")
			(hide yes)
			(effects
				(font
					(size 1.27 1.27)
					(thickness 0.15)
				)
			)
		)
		(property "Author" "Antmicro"
			(at 126.492 232.156 0)
			(layer "F.Fab")
			(hide yes)
			(effects
				(font
					(size 1 1)
					(thickness 0.15)
				)
			)
		)
		(property "License" "Apache-2.0"
			(at 126.492 232.156 0)
			(layer "F.Fab")
			(hide yes)
			(effects
				(font
					(size 1 1)
					(thickness 0.15)
				)
			)
		)
		(property "MPN" "BSS138AKA"
			(at 126.492 232.156 0)
			(layer "F.Fab")
			(hide yes)
			(effects
				(font
					(size 1 1)
					(thickness 0.15)
				)
			)
		)
		(property "Manufacturer" "ON Semiconductor"
			(at 126.492 232.156 0)
			(layer "F.Fab")
			(hide yes)
			(effects
				(font
					(size 1 1)
					(thickness 0.15)
				)
			)
		)
		(sheetname "/Power/")
		(sheetfile "power.kicad_sch")
		(attr smd)
		(fp_line
			(start -0.7 1.5)
			(end -0.7 1.35)
			(stroke
				(width 0.15)
				(type solid)
			)
			(layer "F.SilkS")
		)
		(fp_line
			(start 0.7 1.5)
			(end -0.7 1.5)
			(stroke
				(width 0.15)
				(type solid)
			)
			(layer "F.SilkS")
		)
		(fp_line
			(start 0.7 0.4)
			(end 0.7 1.5)
			(stroke
				(width 0.15)
				(type solid)
			)
			(layer "F.SilkS")
		)
		(fp_line
			(start 0.7 -0.4)
			(end 0.7 -1.5)
			(stroke
				(width 0.15)
				(type solid)
			)
			(layer "F.SilkS")
		)
		(fp_line
			(start -1.45 -1.35)
			(end -0.85 -1.35)
			(stroke
				(width 0.15)
				(type solid)
			)
			(layer "F.SilkS")
		)
		(fp_line
			(start -0.85 -1.35)
			(end -0.7 -1.5)
			(stroke
				(width 0.15)
				(type solid)
			)
			(layer "F.SilkS")
		)
		(fp_line
			(start 0.7 -1.5)
			(end -0.7 -1.5)
			(stroke
				(width 0.15)
				(type solid)
			)
			(layer "F.SilkS")
		)
		(fp_line
			(start -0.85 1.65)
			(end -0.85 1.4)
			(stroke
				(width 0.05)
				(type solid)
			)
			(layer "F.CrtYd")
		)
		(fp_line
			(start 0.85 1.65)
			(end -0.85 1.65)
			(stroke
				(width 0.05)
				(type solid)
			)
			(layer "F.CrtYd")
		)
		(fp_line
			(start -1.75 1.4)
			(end -1.75 0.5)
			(stroke
				(width 0.05)
				(type solid)
			)
			(layer "F.CrtYd")
		)
		(fp_line
			(start -0.85 1.4)
			(end -1.75 1.4)
			(stroke
				(width 0.05)
				(type solid)
			)
			(layer "F.CrtYd")
		)
		(fp_line
			(start -1.75 0.5)
			(end -0.85 0.5)
			(stroke
				(width 0.05)
				(type solid)
			)
			(layer "F.CrtYd")
		)
		(fp_line
			(start -0.85 0.5)
			(end -0.85 -0.5)
			(stroke
				(width 0.05)
				(type solid)
			)
			(layer "F.CrtYd")
		)
		(fp_line
			(start 0.85 0.45)
			(end 0.85 1.65)
			(stroke
				(width 0.05)
				(type solid)
			)
			(layer "F.CrtYd")
		)
		(fp_line
			(start 1.75 0.45)
			(end 0.85 0.45)
			(stroke
				(width 0.05)
				(type solid)
			)
			(layer "F.CrtYd")
		)
		(fp_line
			(start 0.825 -0.45)
			(end 1.75 -0.45)
			(stroke
				(width 0.05)
				(type solid)
			)
			(layer "F.CrtYd")
		)
		(fp_line
			(start 1.75 -0.45)
			(end 1.75 0.45)
			(stroke
				(width 0.05)
				(type solid)
			)
			(layer "F.CrtYd")
		)
		(fp_line
			(start -1.75 -0.5)
			(end -1.75 -1.4)
			(stroke
				(width 0.05)
				(type solid)
			)
			(layer "F.CrtYd")
		)
		(fp_line
			(start -0.85 -0.5)
			(end -1.75 -0.5)
			(stroke
				(width 0.05)
				(type solid)
			)
			(layer "F.CrtYd")
		)
		(fp_line
			(start -0.9 -1.4)
			(end -1.75 -1.4)
			(stroke
				(width 0.05)
				(type solid)
			)
			(layer "F.CrtYd")
		)
		(fp_line
			(start -0.9 -1.6)
			(end -0.9 -1.4)
			(stroke
				(width 0.05)
				(type solid)
			)
			(layer "F.CrtYd")
		)
		(fp_line
			(start -0.9 -1.6)
			(end 0.825 -1.6)
			(stroke
				(width 0.05)
				(type solid)
			)
			(layer "F.CrtYd")
		)
		(fp_line
			(start 0.825 -1.6)
			(end 0.825 -0.45)
			(stroke
				(width 0.05)
				(type solid)
			)
			(layer "F.CrtYd")
		)
		(fp_line
			(start -0.712 1.519)
			(end 0.688 1.519)
			(stroke
				(width 0.15)
				(type solid)
			)
			(layer "F.Fab")
		)
		(fp_line
			(start 0.688 1.519)
			(end 0.688 -1.52)
			(stroke
				(width 0.15)
				(type solid)
			)
			(layer "F.Fab")
		)
		(fp_line
			(start -0.712 -1.325)
			(end -0.712 1.523)
			(stroke
				(width 0.15)
				(type solid)
			)
			(layer "F.Fab")
		)
		(fp_line
			(start -0.437 -1.526)
			(end -0.712 -1.325)
			(stroke
				(width 0.15)
				(type solid)
			)
			(layer "F.Fab")
		)
		(fp_line
			(start -0.437 -1.526)
			(end 0.688 -1.526)
			(stroke
				(width 0.15)
				(type solid)
			)
			(layer "F.Fab")
		)
		(pad "1" smd roundrect
			(at -1.1 -0.951 270)
			(size 1 0.6)
			(layers "F.Cu" "F.Mask" "F.Paste")
			(roundrect_rratio 0.15)
			(net 126 "Net-(Q1-G)")
			(pinfunction "G")
			(pintype "input")
		)
		(pad "2" smd roundrect
			(at -1.1 0.949 270)
			(size 1 0.6)
			(layers "F.Cu" "F.Mask" "F.Paste")
			(roundrect_rratio 0.15)
			(net 1 "GND")
			(pinfunction "S")
			(pintype "passive")
		)
		(pad "3" smd roundrect
			(at 1.1 -0.0005 270)
			(size 1 0.6)
			(layers "F.Cu" "F.Mask" "F.Paste")
			(roundrect_rratio 0.15)
			(net 63 "/Power/FFC_5V_EN")
			(pinfunction "D")
			(pintype "passive")
		)
	)
	(footprint "antmicro-footprints:R_0402_1005Metric"
		(layer "F.Cu")
		(at 177.8 58.674 180)
		(descr "Resistor SMD 0402")
		(tags "resistor SMD 0402")
		(property "Reference" "R23"
			(at 0.718006 -0.408082 0)
			(layer "F.SilkS")
			(effects
				(font
					(size 0.7 0.7)
					(thickness 0.15)
				)
				(justify right bottom)
			)
		)
		(property "Value" "R_1M_0402"
			(at -1.011843 1.772047 0)
			(layer "F.Fab")
			(effects
				(font
					(size 0.7 0.7)
					(thickness 0.15)
				)
				(justify right bottom)
			)
		)
		(property "Datasheet" "https://www.bourns.com/docs/product-datasheets/cr.pdf"
			(at 0 0 180)
			(layer "F.Fab")
			(hide yes)
			(effects
				(font
					(size 1.27 1.27)
					(thickness 0.15)
				)
			)
		)
		(property "Description" "SMD Chip Resistor, 1 Mohm, ± 1%, 62.5 mW, 0402 [1005 Metric], Thick Film, General Purpose"
			(at 0 0 180)
			(layer "F.Fab")
			(hide yes)
			(effects
				(font
					(size 1.27 1.27)
					(thickness 0.15)
				)
			)
		)
		(property "Author" "Antmicro"
			(at 355.6 117.348 0)
			(layer "F.Fab")
			(hide yes)
			(effects
				(font
					(size 1 1)
					(thickness 0.15)
				)
			)
		)
		(property "License" "Apache-2.0"
			(at 355.6 117.348 0)
			(layer "F.Fab")
			(hide yes)
			(effects
				(font
					(size 1 1)
					(thickness 0.15)
				)
			)
		)
		(property "MPN" "CR0402-FX-1004GLF"
			(at 355.6 117.348 0)
			(layer "F.Fab")
			(hide yes)
			(effects
				(font
					(size 1 1)
					(thickness 0.15)
				)
			)
		)
		(property "Manufacturer" "Bourns"
			(at 355.6 117.348 0)
			(layer "F.Fab")
			(hide yes)
			(effects
				(font
					(size 1 1)
					(thickness 0.15)
				)
			)
		)
		(property "Tolerance" "1%"
			(at 355.6 117.348 0)
			(layer "F.Fab")
			(hide yes)
			(effects
				(font
					(size 1 1)
					(thickness 0.15)
				)
			)
		)
		(property "Val" "1M"
			(at 355.6 117.348 0)
			(layer "F.Fab")
			(hide yes)
			(effects
				(font
					(size 1 1)
					(thickness 0.15)
				)
			)
		)
		(sheetname "/Power/")
		(sheetfile "power.kicad_sch")
		(attr smd)
		(fp_rect
			(start -0.925 -0.47)
			(end 0.925 0.47)
			(stroke
				(width 0.05)
				(type default)
			)
			(fill no)
			(layer "F.CrtYd")
		)
		(fp_rect
			(start -0.5 -0.25)
			(end 0.5 0.25)
			(stroke
				(width 0.15)
				(type solid)
			)
			(fill no)
			(layer "F.Fab")
		)
		(pad "1" smd roundrect
			(at -0.48 0 180)
			(size 0.59 0.64)
			(layers "F.Cu" "F.Mask" "F.Paste")
			(roundrect_rratio 0.25)
			(net 1 "GND")
			(pintype "passive")
		)
		(pad "2" smd roundrect
			(at 0.48 0 180)
			(size 0.59 0.64)
			(layers "F.Cu" "F.Mask" "F.Paste")
			(roundrect_rratio 0.25)
			(net 127 "Net-(Q2-G)")
			(pintype "passive")
		)
	)
	(footprint "antmicro-footprints:TP_SMD_0.75mm"
		(layer "F.Cu")
		(at 147.828 97.89)
		(property "Reference" "TP12"
			(at 0 -0.6 0)
			(layer "F.SilkS")
			(hide yes)
			(effects
				(font
					(size 0.7 0.7)
					(thickness 0.15)
				)
				(justify left bottom)
			)
		)
		(property "Value" "TP_0.75mm_SMD"
			(at 0 1.2 0)
			(layer "F.Fab")
			(effects
				(font
					(size 0.7 0.7)
					(thickness 0.15)
				)
				(justify left bottom)
			)
		)
		(property "Description" "SMT test point"
			(at 0 0 0)
			(layer "F.Fab")
			(hide yes)
			(effects
				(font
					(size 1.27 1.27)
					(thickness 0.15)
				)
			)
		)
		(property "Author" "Antmicro"
			(at 0 0 0)
			(layer "F.Fab")
			(hide yes)
			(effects
				(font
					(size 1 1)
					(thickness 0.15)
				)
			)
		)
		(property "License" "Apache-2.0"
			(at 0 0 0)
			(layer "F.Fab")
			(hide yes)
			(effects
				(font
					(size 1 1)
					(thickness 0.15)
				)
			)
		)
		(property "MPN" ""
			(at 0 0 0)
			(layer "F.Fab")
			(hide yes)
			(effects
				(font
					(size 1 1)
					(thickness 0.15)
				)
			)
		)
		(property "Manufacturer" ""
			(at 0 0 0)
			(layer "F.Fab")
			(hide yes)
			(effects
				(font
					(size 1 1)
					(thickness 0.15)
				)
			)
		)
		(sheetname "/Power/")
		(sheetfile "power.kicad_sch")
		(fp_circle
			(center 0 0)
			(end 0.475 0)
			(stroke
				(width 0.05)
				(type default)
			)
			(fill no)
			(layer "F.CrtYd")
		)
		(pad "1" smd circle
			(at 0 0)
			(size 0.75 0.75)
			(layers "F.Cu" "F.Mask")
			(net 123 "/Power/OUT_12V")
			(pinfunction "1")
			(pintype "passive")
		)
	)
	(footprint "antmicro-footprints:L_Coilcraft-PFL1609"
		(layer "F.Cu")
		(at 160.528 53.594)
		(property "Reference" "L12"
			(at -3.162703 0.381344 0)
			(layer "F.SilkS")
			(effects
				(font
					(size 0.7 0.7)
					(thickness 0.15)
				)
				(justify left bottom)
			)
		)
		(property "Value" "L_470n_1A_Coilcraft-PFL1609"
			(at 0 2 0)
			(layer "F.Fab")
			(effects
				(font
					(size 0.7 0.7)
					(thickness 0.15)
				)
				(justify left bottom)
			)
		)
		(property "Datasheet" "https://www.coilcraft.com/getmedia/2f4cd442-d64d-4413-a518-12fcfd03318d/pfl1609.pdf"
			(at 0 0 0)
			(layer "F.Fab")
			(hide yes)
			(effects
				(font
					(size 1.27 1.27)
					(thickness 0.15)
				)
			)
		)
		(property "Description" "Power Inductor (SMT), 6.8 µH, 9.2 A, Shielded, 12.8 A, XAL7070"
			(at 0 0 0)
			(layer "F.Fab")
			(hide yes)
			(effects
				(font
					(size 1.27 1.27)
					(thickness 0.15)
				)
			)
		)
		(property "Author" "Antmicro"
			(at 0 0 0)
			(layer "F.Fab")
			(hide yes)
			(effects
				(font
					(size 1 1)
					(thickness 0.15)
				)
			)
		)
		(property "IMax" "1 A"
			(at 0 0 0)
			(layer "F.Fab")
			(hide yes)
			(effects
				(font
					(size 1 1)
					(thickness 0.15)
				)
			)
		)
		(property "ISat" "0.99 A"
			(at 0 0 0)
			(layer "F.Fab")
			(hide yes)
			(effects
				(font
					(size 1 1)
					(thickness 0.15)
				)
			)
		)
		(property "License" "Apache-2.0"
			(at 0 0 0)
			(layer "F.Fab")
			(hide yes)
			(effects
				(font
					(size 1 1)
					(thickness 0.15)
				)
			)
		)
		(property "MPN" "PFL1609-471"
			(at 0 0 0)
			(layer "F.Fab")
			(hide yes)
			(effects
				(font
					(size 1 1)
					(thickness 0.15)
				)
			)
		)
		(property "Manufacturer" "Coilcraft"
			(at 0 0 0)
			(layer "F.Fab")
			(hide yes)
			(effects
				(font
					(size 1 1)
					(thickness 0.15)
				)
			)
		)
		(property "Size" "1.07x1.8"
			(at 0 0 0)
			(layer "F.Fab")
			(hide yes)
			(effects
				(font
					(size 1 1)
					(thickness 0.15)
				)
			)
		)
		(property "Val" "470n/0.99A"
			(at 0 0 0)
			(layer "F.Fab")
			(hide yes)
			(effects
				(font
					(size 1 1)
					(thickness 0.15)
				)
			)
		)
		(sheetname "/Power/")
		(sheetfile "power.kicad_sch")
		(attr smd)
		(fp_line
			(start -0.23 -0.45)
			(end 0.23 -0.45)
			(stroke
				(width 0.15)
				(type solid)
			)
			(layer "F.SilkS")
		)
		(fp_line
			(start -0.23 0.45)
			(end 0.23 0.45)
			(stroke
				(width 0.15)
				(type solid)
			)
			(layer "F.SilkS")
		)
		(fp_rect
			(start -1.2 -0.84)
			(end 1.2 0.84)
			(stroke
				(width 0.05)
				(type solid)
			)
			(fill no)
			(layer "F.CrtYd")
		)
		(fp_rect
			(start -0.9 -0.535)
			(end 0.9 0.535)
			(stroke
				(width 0.15)
				(type solid)
			)
			(fill no)
			(layer "F.Fab")
		)
		(pad "1" smd roundrect
			(at -0.635 0)
			(size 0.64 1.02)
			(layers "F.Cu" "F.Mask" "F.Paste")
			(roundrect_rratio 0.15)
			(net 58 "Net-(L12-Pad1)")
			(pintype "passive")
		)
		(pad "2" smd roundrect
			(at 0.635 0)
			(size 0.64 1.02)
			(layers "F.Cu" "F.Mask" "F.Paste")
			(roundrect_rratio 0.15)
			(net 62 "Net-(L12-Pad2)")
			(pintype "passive")
		)
	)
	(footprint "antmicro-footprints:TSOT23-6"
		(layer "F.Cu")
		(at 186.364 52.324 -90)
		(property "Reference" "U6"
			(at -2.921 -1.342 180)
			(layer "F.SilkS")
			(effects
				(font
					(size 0.7 0.7)
					(thickness 0.15)
				)
				(justify right bottom)
			)
		)
		(property "Value" "AP22615A_TSOT26"
			(at 0 2.6 90)
			(layer "F.Fab")
			(effects
				(font
					(size 0.7 0.7)
					(thickness 0.15)
				)
				(justify right bottom)
			)
		)
		(property "Datasheet" "https://www.mouser.com/datasheet/2/115/DIOD_S_A0008958405_1-2543193.pdf"
			(at 0 0 270)
			(layer "F.Fab")
			(hide yes)
			(effects
				(font
					(size 1.27 1.27)
					(thickness 0.15)
				)
			)
		)
		(property "Description" "Power Load Distribution Switch, High Side, Active High, 1 Output, 5.5 V, 3.6 A, 0.04 ohm, TSOT-26-6"
			(at 0 0 270)
			(layer "F.Fab")
			(hide yes)
			(effects
				(font
					(size 1.27 1.27)
					(thickness 0.15)
				)
			)
		)
		(property "Author" "Antmicro"
			(at 134.04 238.688 0)
			(layer "F.Fab")
			(hide yes)
			(effects
				(font
					(size 1 1)
					(thickness 0.15)
				)
			)
		)
		(property "License" "Apache-2.0"
			(at 134.04 238.688 0)
			(layer "F.Fab")
			(hide yes)
			(effects
				(font
					(size 1 1)
					(thickness 0.15)
				)
			)
		)
		(property "MPN" "AP22615AWU-7"
			(at 134.04 238.688 0)
			(layer "F.Fab")
			(hide yes)
			(effects
				(font
					(size 1 1)
					(thickness 0.15)
				)
			)
		)
		(property "Manufacturer" "Diodes Incorporated"
			(at 134.04 238.688 0)
			(layer "F.Fab")
			(hide yes)
			(effects
				(font
					(size 1 1)
					(thickness 0.15)
				)
			)
		)
		(sheetname "/Power/")
		(sheetfile "power.kicad_sch")
		(attr smd)
		(fp_line
			(start -1 1.55)
			(end -1 1.4)
			(stroke
				(width 0.15)
				(type solid)
			)
			(layer "F.SilkS")
		)
		(fp_line
			(start 1 1.55)
			(end -1 1.55)
			(stroke
				(width 0.15)
				(type solid)
			)
			(layer "F.SilkS")
		)
		(fp_line
			(start 1 1.55)
			(end 1 1.4)
			(stroke
				(width 0.15)
				(type solid)
			)
			(layer "F.SilkS")
		)
		(fp_line
			(start 1 -1.497)
			(end 1 -1.375)
			(stroke
				(width 0.15)
				(type solid)
			)
			(layer "F.SilkS")
		)
		(fp_line
			(start 1 -1.497)
			(end -1 -1.5)
			(stroke
				(width 0.15)
				(type solid)
			)
			(layer "F.SilkS")
		)
		(fp_line
			(start -1 -1.5)
			(end -1 -1.375)
			(stroke
				(width 0.15)
				(type solid)
			)
			(layer "F.SilkS")
		)
		(fp_circle
			(center -1.44 -1.5)
			(end -1.39 -1.5)
			(stroke
				(width 0.15)
				(type solid)
			)
			(fill yes)
			(layer "F.SilkS")
		)
		(fp_rect
			(start 1.93 -1.7)
			(end -1.93 1.7)
			(stroke
				(width 0.05)
				(type solid)
			)
			(fill no)
			(layer "F.CrtYd")
		)
		(fp_line
			(start -0.45 -1.521)
			(end -0.876 -1.096)
			(stroke
				(width 0.15)
				(type solid)
			)
			(layer "F.Fab")
		)
		(fp_rect
			(start 0.875 1.528)
			(end -0.875 -1.525)
			(stroke
				(width 0.15)
				(type solid)
			)
			(fill no)
			(layer "F.Fab")
		)
		(pad "1" smd rect
			(at -1.301 -0.947 180)
			(size 0.7 1.2)
			(layers "F.Cu" "F.Mask" "F.Paste")
			(net 5 "+5V")
			(pinfunction "OUT")
			(pintype "power_out")
		)
		(pad "2" smd rect
			(at -1.301 0.004 180)
			(size 0.7 1.2)
			(layers "F.Cu" "F.Mask" "F.Paste")
			(net 1 "GND")
			(pinfunction "GND")
			(pintype "power_in")
		)
		(pad "3" smd rect
			(at -1.301 0.954 180)
			(size 0.7 1.2)
			(layers "F.Cu" "F.Mask" "F.Paste")
			(net 72 "/Power/FFC_5V_FLG")
			(pinfunction "FLG")
			(pintype "output")
		)
		(pad "4" smd rect
			(at 1.299 0.954 180)
			(size 0.7 1.2)
			(layers "F.Cu" "F.Mask" "F.Paste")
			(net 63 "/Power/FFC_5V_EN")
			(pinfunction "EN")
			(pintype "input")
		)
		(pad "5" smd rect
			(at 1.299 0.004 180)
			(size 0.7 1.2)
			(layers "F.Cu" "F.Mask" "F.Paste")
			(net 74 "/Power/FFC_5V_ISET")
			(pinfunction "ISET")
			(pintype "passive")
		)
		(pad "6" smd rect
			(at 1.299 -0.947 180)
			(size 0.7 1.2)
			(layers "F.Cu" "F.Mask" "F.Paste")
			(net 113 "/Connectors/FFC_5V")
			(pinfunction "IN")
			(pintype "power_in")
		)
	)
	(footprint "antmicro-footprints:R_0402_1005Metric"
		(layer "F.Cu")
		(at 179.301 50.542)
		(descr "Resistor SMD 0402")
		(tags "resistor SMD 0402")
		(property "Reference" "R16"
			(at 0.775356 0.30709 0)
			(layer "F.SilkS")
			(effects
				(font
					(size 0.7 0.7)
					(thickness 0.15)
				)
				(justify left bottom)
			)
		)
		(property "Value" "R_10k_0402"
			(at -1.011843 1.772047 0)
			(layer "F.Fab")
			(effects
				(font
					(size 0.7 0.7)
					(thickness 0.15)
				)
				(justify left bottom)
			)
		)
		(property "Datasheet" "https://www.bourns.com/docs/product-datasheets/cr.pdf"
			(at 0 0 0)
			(layer "F.Fab")
			(hide yes)
			(effects
				(font
					(size 1.27 1.27)
					(thickness 0.15)
				)
			)
		)
		(property "Description" "SMD Chip Resistor, 10 kohm, ± 1%, 62.5 mW, 0402 [1005 Metric], Thick Film, General Purpose"
			(at 0 0 0)
			(layer "F.Fab")
			(hide yes)
			(effects
				(font
					(size 1.27 1.27)
					(thickness 0.15)
				)
			)
		)
		(property "Author" "Antmicro"
			(at 0 0 0)
			(layer "F.Fab")
			(hide yes)
			(effects
				(font
					(size 1 1)
					(thickness 0.15)
				)
			)
		)
		(property "License" "Apache-2.0"
			(at 0 0 0)
			(layer "F.Fab")
			(hide yes)
			(effects
				(font
					(size 1 1)
					(thickness 0.15)
				)
			)
		)
		(property "MPN" "CR0402-FX-1002GLF"
			(at 0 0 0)
			(layer "F.Fab")
			(hide yes)
			(effects
				(font
					(size 1 1)
					(thickness 0.15)
				)
			)
		)
		(property "Manufacturer" "Bourns"
			(at 0 0 0)
			(layer "F.Fab")
			(hide yes)
			(effects
				(font
					(size 1 1)
					(thickness 0.15)
				)
			)
		)
		(property "Tolerance" "1%"
			(at 0 0 0)
			(layer "F.Fab")
			(hide yes)
			(effects
				(font
					(size 1 1)
					(thickness 0.15)
				)
			)
		)
		(property "Val" "10k"
			(at 0 0 0)
			(layer "F.Fab")
			(hide yes)
			(effects
				(font
					(size 1 1)
					(thickness 0.15)
				)
			)
		)
		(sheetname "/Power/")
		(sheetfile "power.kicad_sch")
		(attr smd)
		(fp_rect
			(start -0.925 -0.47)
			(end 0.925 0.47)
			(stroke
				(width 0.05)
				(type default)
			)
			(fill no)
			(layer "F.CrtYd")
		)
		(fp_rect
			(start -0.5 -0.25)
			(end 0.5 0.25)
			(stroke
				(width 0.15)
				(type solid)
			)
			(fill no)
			(layer "F.Fab")
		)
		(pad "1" smd roundrect
			(at -0.48 0)
			(size 0.59 0.64)
			(layers "F.Cu" "F.Mask" "F.Paste")
			(roundrect_rratio 0.25)
			(net 1 "GND")
			(pintype "passive")
		)
		(pad "2" smd roundrect
			(at 0.48 0)
			(size 0.59 0.64)
			(layers "F.Cu" "F.Mask" "F.Paste")
			(roundrect_rratio 0.25)
			(net 126 "Net-(Q1-G)")
			(pintype "passive")
		)
	)
	(footprint "antmicro-footprints:Conn_FAKRA_7-2287906-0"
		(layer "F.Cu")
		(at 140.784666 38.348)
		(descr "Connector FAKRA, 5 pins")
		(property "Reference" "J3"
			(at 5.054 5.3 0)
			(layer "F.SilkS")
			(effects
				(font
					(size 0.7 0.7)
					(thickness 0.15)
				)
				(justify left bottom)
			)
		)
		(property "Value" "Conn_FAKRA_59S2AQ-40MT5-Z_1"
			(at -6.55 15.019 0)
			(layer "F.Fab")
			(effects
				(font
					(size 0.7 0.7)
					(thickness 0.15)
				)
				(justify left bottom)
			)
		)
		(property ki_fp_filters "*BNC* *SMA* *SMB* *SMC* *Cinch*")
		(sheetname "/Connectors/")
		(sheetfile "connectors.kicad_sch")
		(attr through_hole)
		(fp_line
			(start -4.572 0.94)
			(end -4.572 13.919)
			(stroke
				(width 0.15)
				(type solid)
			)
			(layer "F.SilkS")
		)
		(fp_line
			(start -4.572 13.919)
			(end 4.572 13.919)
			(stroke
				(width 0.15)
				(type solid)
			)
			(layer "F.SilkS")
		)
		(fp_line
			(start 4.572 0.94)
			(end -4.572 0.94)
			(stroke
				(width 0.15)
				(type solid)
			)
			(layer "F.SilkS")
		)
		(fp_line
			(start 4.572 13.919)
			(end 4.572 0.94)
			(stroke
				(width 0.15)
				(type solid)
			)
			(layer "F.SilkS")
		)
		(fp_rect
			(start -5.14 -12.64)
			(end 5.131 14.164)
			(stroke
				(width 0.05)
				(type solid)
			)
			(fill no)
			(layer "F.CrtYd")
		)
		(fp_text user "${REFERENCE}"
			(at -6.55 18.619 0)
			(layer "F.Fab")
			(effects
				(font
					(size 0.7 0.7)
					(thickness 0.15)
				)
				(justify left bottom)
			)
		)
		(fp_text user "Author: Antmicro"
			(at -6.55 17.419 0)
			(layer "F.Fab")
			(effects
				(font
					(size 0.7 0.7)
					(thickness 0.15)
				)
				(justify left bottom)
			)
		)
		(fp_text user "License: Apache-2.0"
			(at -6.55 16.219 0)
			(layer "F.Fab")
			(effects
				(font
					(size 0.7 0.7)
					(thickness 0.15)
				)
				(justify left bottom)
			)
		)
		(pad "1" smd roundrect
			(at 0 3.62 270)
			(size 4.79 1.9)
			(layers "F.Cu" "F.Mask" "F.Paste")
			(roundrect_rratio 0.25)
			(net 115 "/Connectors/PoCB")
			(pinfunction "1")
			(pintype "passive")
		)
		(pad "2" thru_hole circle
			(at -3 3.315 270)
			(size 1.8 1.8)
			(drill 1.45)
			(layers "*.Cu" "*.Mask")
			(remove_unused_layers no)
			(net 1 "GND")
			(pinfunction "2")
			(pintype "passive")
		)
		(pad "2" smd roundrect
			(at -2.9975 3.7175 270)
			(size 4.985 1.8)
			(layers "F.Cu" "F.Mask" "F.Paste")
			(roundrect_rratio 0.25)
			(net 1 "GND")
			(pinfunction "2")
			(pintype "passive")
		)
		(pad "3" thru_hole circle
			(at -3 10.315 270)
			(size 1.8 1.8)
			(drill 1.45)
			(layers "*.Cu" "*.Mask")
			(remove_unused_layers no)
			(net 1 "GND")
			(pinfunction "3")
			(pintype "passive")
		)
		(pad "3" smd roundrect
			(at -3 10.815 270)
			(size 5.6 1.8)
			(layers "F.Cu" "F.Mask" "F.Paste")
			(roundrect_rratio 0.25)
			(net 1 "GND")
			(pinfunction "3")
			(pintype "passive")
		)
		(pad "4" thru_hole circle
			(at 3 10.315 270)
			(size 1.8 1.8)
			(drill 1.45)
			(layers "*.Cu" "*.Mask")
			(remove_unused_layers no)
			(net 1 "GND")
			(pinfunction "4")
			(pintype "passive")
		)
		(pad "4" smd roundrect
			(at 3 10.815 270)
			(size 5.6 1.8)
			(layers "F.Cu" "F.Mask" "F.Paste")
			(roundrect_rratio 0.25)
			(net 1 "GND")
			(pinfunction "4")
			(pintype "passive")
		)
		(pad "5" thru_hole circle
			(at 3 3.315 270)
			(size 1.8 1.8)
			(drill 1.45)
			(layers "*.Cu" "*.Mask")
			(remove_unused_layers no)
			(net 1 "GND")
			(pinfunction "5")
			(pintype "passive")
		)
		(pad "5" smd roundrect
			(at 3 3.72 270)
			(size 4.99 1.8)
			(layers "F.Cu" "F.Mask" "F.Paste")
			(roundrect_rratio 0.25)
			(net 1 "GND")
			(pinfunction "5")
			(pintype "passive")
		)
	)
	(footprint "antmicro-footprints:R_0402_1005Metric"
		(layer "F.Cu")
		(at 120.324 83.162 180)
		(descr "Resistor SMD 0402")
		(tags "resistor SMD 0402")
		(property "Reference" "R37"
			(at 1.016 0.358 0)
			(layer "F.SilkS")
			(effects
				(font
					(size 0.7 0.7)
					(thickness 0.15)
				)
				(justify right bottom)
			)
		)
		(property "Value" "R_4k99_0402"
			(at -1.011843 1.772047 0)
			(layer "F.Fab")
			(effects
				(font
					(size 0.7 0.7)
					(thickness 0.15)
				)
				(justify right bottom)
			)
		)
		(property "Datasheet" "https://www.bourns.com/docs/product-datasheets/cr.pdf"
			(at 0 0 180)
			(layer "F.Fab")
			(hide yes)
			(effects
				(font
					(size 1.27 1.27)
					(thickness 0.15)
				)
			)
		)
		(property "Description" "SMD Chip Resistor, 4.99 kohm, ± 1%, 62.5 mW, 0402 [1005 Metric], Thick Film, General Purpose"
			(at 0 0 180)
			(layer "F.Fab")
			(hide yes)
			(effects
				(font
					(size 1.27 1.27)
					(thickness 0.15)
				)
			)
		)
		(property "Author" "Antmicro"
			(at 240.648 166.324 0)
			(layer "F.Fab")
			(hide yes)
			(effects
				(font
					(size 1 1)
					(thickness 0.15)
				)
			)
		)
		(property "License" "Apache-2.0"
			(at 240.648 166.324 0)
			(layer "F.Fab")
			(hide yes)
			(effects
				(font
					(size 1 1)
					(thickness 0.15)
				)
			)
		)
		(property "MPN" "CR0402-FX-4991GLF"
			(at 240.648 166.324 0)
			(layer "F.Fab")
			(hide yes)
			(effects
				(font
					(size 1 1)
					(thickness 0.15)
				)
			)
		)
		(property "Manufacturer" "Bourns"
			(at 240.648 166.324 0)
			(layer "F.Fab")
			(hide yes)
			(effects
				(font
					(size 1 1)
					(thickness 0.15)
				)
			)
		)
		(property "Tolerance" "1%"
			(at 240.648 166.324 0)
			(layer "F.Fab")
			(hide yes)
			(effects
				(font
					(size 1 1)
					(thickness 0.15)
				)
			)
		)
		(property "Val" "4k99"
			(at 240.648 166.324 0)
			(layer "F.Fab")
			(hide yes)
			(effects
				(font
					(size 1 1)
					(thickness 0.15)
				)
			)
		)
		(sheetname "/Power/")
		(sheetfile "power.kicad_sch")
		(attr smd)
		(fp_rect
			(start -0.925 -0.47)
			(end 0.925 0.47)
			(stroke
				(width 0.05)
				(type default)
			)
			(fill no)
			(layer "F.CrtYd")
		)
		(fp_rect
			(start -0.5 -0.25)
			(end 0.5 0.25)
			(stroke
				(width 0.15)
				(type solid)
			)
			(fill no)
			(layer "F.Fab")
		)
		(pad "1" smd roundrect
			(at -0.48 0 180)
			(size 0.59 0.64)
			(layers "F.Cu" "F.Mask" "F.Paste")
			(roundrect_rratio 0.25)
			(net 71 "/Power/FB_1V2")
			(pintype "passive")
		)
		(pad "2" smd roundrect
			(at 0.48 0 180)
			(size 0.59 0.64)
			(layers "F.Cu" "F.Mask" "F.Paste")
			(roundrect_rratio 0.25)
			(net 11 "/Power/OUT_1V2")
			(pintype "passive")
		)
	)
	(footprint "antmicro-footprints:C_0402_1005Metric"
		(layer "F.Cu")
		(at 171.45 50.5)
		(descr "Capacitor SMD 0402")
		(tags "capacitor SMD 0402")
		(property "Reference" "C2"
			(at 0.381547 -0.600406 0)
			(layer "F.SilkS")
			(effects
				(font
					(size 0.7 0.7)
					(thickness 0.15)
				)
				(justify right bottom)
			)
		)
		(property "Value" "C_100n_0402"
			(at -1.022927 2.155213 0)
			(layer "F.Fab")
			(effects
				(font
					(size 0.7 0.7)
					(thickness 0.15)
				)
				(justify left bottom)
			)
		)
		(property "Datasheet" "https://www.murata.com/products/productdetail?partno=GRM155R61H104KE14%23"
			(at 0 0 0)
			(layer "F.Fab")
			(hide yes)
			(effects
				(font
					(size 1.27 1.27)
					(thickness 0.15)
				)
			)
		)
		(property "Description" "SMD Multilayer Ceramic Capacitor, 0.1 µF, 50 V, 0402 [1005 Metric], ± 10%, X5R, GRM Series"
			(at 0 0 0)
			(layer "F.Fab")
			(hide yes)
			(effects
				(font
					(size 1.27 1.27)
					(thickness 0.15)
				)
			)
		)
		(property "Author" "Antmicro"
			(at 0 0 0)
			(layer "F.Fab")
			(hide yes)
			(effects
				(font
					(size 1 1)
					(thickness 0.15)
				)
			)
		)
		(property "Dielectric" "X5R"
			(at 0 0 0)
			(layer "F.Fab")
			(hide yes)
			(effects
				(font
					(size 1 1)
					(thickness 0.15)
				)
			)
		)
		(property "License" "Apache-2.0"
			(at 0 0 0)
			(layer "F.Fab")
			(hide yes)
			(effects
				(font
					(size 1 1)
					(thickness 0.15)
				)
			)
		)
		(property "MPN" "GRM155R61H104KE14D"
			(at 0 0 0)
			(layer "F.Fab")
			(hide yes)
			(effects
				(font
					(size 1 1)
					(thickness 0.15)
				)
			)
		)
		(property "Manufacturer" "Murata"
			(at 0 0 0)
			(layer "F.Fab")
			(hide yes)
			(effects
				(font
					(size 1 1)
					(thickness 0.15)
				)
			)
		)
		(property "Val" "100n"
			(at 0 0 0)
			(layer "F.Fab")
			(hide yes)
			(effects
				(font
					(size 1 1)
					(thickness 0.15)
				)
			)
		)
		(property "Voltage" "50V"
			(at 0 0 0)
			(layer "F.Fab")
			(hide yes)
			(effects
				(font
					(size 1 1)
					(thickness 0.15)
				)
			)
		)
		(sheetname "/Connectors/")
		(sheetfile "connectors.kicad_sch")
		(attr smd)
		(fp_rect
			(start -0.925 -0.47)
			(end 0.925 0.47)
			(stroke
				(width 0.05)
				(type default)
			)
			(fill no)
			(layer "F.CrtYd")
		)
		(fp_line
			(start -0.494 -0.25)
			(end 0.504 -0.25)
			(stroke
				(width 0.15)
				(type solid)
			)
			(layer "F.Fab")
		)
		(fp_line
			(start -0.494 0.248)
			(end -0.494 -0.25)
			(stroke
				(width 0.15)
				(type solid)
			)
			(layer "F.Fab")
		)
		(fp_line
			(start 0.504 -0.25)
			(end 0.504 0.248)
			(stroke
				(width 0.15)
				(type solid)
			)
			(layer "F.Fab")
		)
		(fp_line
			(start 0.504 0.248)
			(end -0.494 0.248)
			(stroke
				(width 0.15)
				(type solid)
			)
			(layer "F.Fab")
		)
		(pad "1" smd roundrect
			(at -0.48 0)
			(size 0.59 0.64)
			(layers "F.Cu" "F.Mask" "F.Paste")
			(roundrect_rratio 0.25)
			(net 1 "GND")
			(pintype "passive")
		)
		(pad "2" smd roundrect
			(at 0.48 0)
			(size 0.59 0.64)
			(layers "F.Cu" "F.Mask" "F.Paste")
			(roundrect_rratio 0.25)
			(net 2 "/Connectors/DC_UNFUSED")
			(pintype "passive")
		)
	)
	(footprint "antmicro-footprints:R_0402_1005Metric"
		(layer "F.Cu")
		(at 181.356 64.008)
		(descr "Resistor SMD 0402")
		(tags "resistor SMD 0402")
		(property "Reference" "R14"
			(at -1.27 9.2202 0)
			(layer "F.SilkS")
			(effects
				(font
					(size 0.7 0.7)
					(thickness 0.15)
				)
				(justify left bottom)
			)
		)
		(property "Value" "R_100R_0402"
			(at -1.011843 1.772047 0)
			(layer "F.Fab")
			(effects
				(font
					(size 0.7 0.7)
					(thickness 0.15)
				)
				(justify left bottom)
			)
		)
		(property "Datasheet" "https://www.bourns.com/docs/product-datasheets/cr.pdf"
			(at 0 0 0)
			(layer "F.Fab")
			(hide yes)
			(effects
				(font
					(size 1.27 1.27)
					(thickness 0.15)
				)
			)
		)
		(property "Description" "SMD Chip Resistor, 100 ohm, ± 1%, 62.5 mW, 0402 [1005 Metric], Thick Film, General Purpose"
			(at 0 0 0)
			(layer "F.Fab")
			(hide yes)
			(effects
				(font
					(size 1.27 1.27)
					(thickness 0.15)
				)
			)
		)
		(property "Author" "Antmicro"
			(at 0 0 0)
			(layer "F.Fab")
			(hide yes)
			(effects
				(font
					(size 1 1)
					(thickness 0.15)
				)
			)
		)
		(property "License" "Apache-2.0"
			(at 0 0 0)
			(layer "F.Fab")
			(hide yes)
			(effects
				(font
					(size 1 1)
					(thickness 0.15)
				)
			)
		)
		(property "MPN" "CR0402-FX-1000GLF"
			(at 0 0 0)
			(layer "F.Fab")
			(hide yes)
			(effects
				(font
					(size 1 1)
					(thickness 0.15)
				)
			)
		)
		(property "Manufacturer" "Bourns"
			(at 0 0 0)
			(layer "F.Fab")
			(hide yes)
			(effects
				(font
					(size 1 1)
					(thickness 0.15)
				)
			)
		)
		(property "Tolerance" "1%"
			(at 0 0 0)
			(layer "F.Fab")
			(hide yes)
			(effects
				(font
					(size 1 1)
					(thickness 0.15)
				)
			)
		)
		(property "Val" "100R"
			(at 0 0 0)
			(layer "F.Fab")
			(hide yes)
			(effects
				(font
					(size 1 1)
					(thickness 0.15)
				)
			)
		)
		(sheetname "/Connectors/")
		(sheetfile "connectors.kicad_sch")
		(attr smd)
		(fp_rect
			(start -0.925 -0.47)
			(end 0.925 0.47)
			(stroke
				(width 0.05)
				(type default)
			)
			(fill no)
			(layer "F.CrtYd")
		)
		(fp_rect
			(start -0.5 -0.25)
			(end 0.5 0.25)
			(stroke
				(width 0.15)
				(type solid)
			)
			(fill no)
			(layer "F.Fab")
		)
		(pad "1" smd roundrect
			(at -0.48 0)
			(size 0.59 0.64)
			(layers "F.Cu" "F.Mask" "F.Paste")
			(roundrect_rratio 0.25)
			(net 45 "/Connectors/SCL_CAM")
			(pintype "passive")
		)
		(pad "2" smd roundrect
			(at 0.48 0)
			(size 0.59 0.64)
			(layers "F.Cu" "F.Mask" "F.Paste")
			(roundrect_rratio 0.25)
			(net 43 "/Connectors/SCL_CAM1")
			(pintype "passive")
		)
	)
	(footprint "antmicro-footprints:L_Bourns-SRN8040"
		(layer "F.Cu")
		(at 120.578 73.764 -90)
		(property "Reference" "L17"
			(at -4.4728 4.3476 0)
			(layer "F.SilkS")
			(effects
				(font
					(size 0.7 0.7)
					(thickness 0.15)
				)
				(justify left bottom)
			)
		)
		(property "Value" "L_10u_3.1A_Bourns-SRN8040"
			(at 0 -5.461 90)
			(layer "F.Fab")
			(effects
				(font
					(size 0.7 0.7)
					(thickness 0.15)
				)
				(justify right bottom)
			)
		)
		(property "Datasheet" "https://www.bourns.com/pdfs/SRN8040.pdf"
			(at 0 0 270)
			(layer "F.Fab")
			(hide yes)
			(effects
				(font
					(size 1.27 1.27)
					(thickness 0.15)
				)
			)
		)
		(property "Description" "Power Inductor (SMD), 10 µH, 3.1 A, Shielded, 3.4 A, SRN8040"
			(at 0 0 270)
			(layer "F.Fab")
			(hide yes)
			(effects
				(font
					(size 1.27 1.27)
					(thickness 0.15)
				)
			)
		)
		(property "Author" "Antmicro"
			(at 46.814 194.342 0)
			(layer "F.Fab")
			(hide yes)
			(effects
				(font
					(size 1 1)
					(thickness 0.15)
				)
			)
		)
		(property "IMax" "3.1 A"
			(at 46.814 194.342 0)
			(layer "F.Fab")
			(hide yes)
			(effects
				(font
					(size 1 1)
					(thickness 0.15)
				)
			)
		)
		(property "ISat" "3.4 A"
			(at 46.814 194.342 0)
			(layer "F.Fab")
			(hide yes)
			(effects
				(font
					(size 1 1)
					(thickness 0.15)
				)
			)
		)
		(property "License" "Apache-2.0"
			(at 46.814 194.342 0)
			(layer "F.Fab")
			(hide yes)
			(effects
				(font
					(size 1 1)
					(thickness 0.15)
				)
			)
		)
		(property "MPN" "SRN8040-100M"
			(at 46.814 194.342 0)
			(layer "F.Fab")
			(hide yes)
			(effects
				(font
					(size 1 1)
					(thickness 0.15)
				)
			)
		)
		(property "Manufacturer" "Bourns"
			(at 46.814 194.342 0)
			(layer "F.Fab")
			(hide yes)
			(effects
				(font
					(size 1 1)
					(thickness 0.15)
				)
			)
		)
		(property "Size" "8.0x8.0"
			(at 46.814 194.342 0)
			(layer "F.Fab")
			(hide yes)
			(effects
				(font
					(size 1 1)
					(thickness 0.15)
				)
			)
		)
		(property "Val" "10u/3.1A"
			(at 46.814 194.342 0)
			(layer "F.Fab")
			(hide yes)
			(effects
				(font
					(size 1 1)
					(thickness 0.15)
				)
			)
		)
		(sheetname "/Power/")
		(sheetfile "power.kicad_sch")
		(attr smd)
		(fp_line
			(start -1.3 4.1)
			(end 1.3 4.1)
			(stroke
				(width 0.12)
				(type solid)
			)
			(layer "F.SilkS")
		)
		(fp_line
			(start -1.3 -4.1)
			(end 1.3 -4.1)
			(stroke
				(width 0.12)
				(type solid)
			)
			(layer "F.SilkS")
		)
		(fp_rect
			(start -4.325 -4.35)
			(end 4.325 4.35)
			(stroke
				(width 0.05)
				(type solid)
			)
			(fill no)
			(layer "F.CrtYd")
		)
		(fp_line
			(start -4.099 4.1)
			(end -4.099 -4.1)
			(stroke
				(width 0.15)
				(type solid)
			)
			(layer "F.Fab")
		)
		(fp_line
			(start 4.1 4.1)
			(end -4.099 4.1)
			(stroke
				(width 0.15)
				(type solid)
			)
			(layer "F.Fab")
		)
		(fp_line
			(start -4.099 -4.1)
			(end 4.1 -4.1)
			(stroke
				(width 0.15)
				(type solid)
			)
			(layer "F.Fab")
		)
		(fp_line
			(start 4.1 -4.1)
			(end 4.1 4.1)
			(stroke
				(width 0.15)
				(type solid)
			)
			(layer "F.Fab")
		)
		(pad "1" smd rect
			(at -2.8 0 270)
			(size 2.6 8.2)
			(layers "F.Cu" "F.Mask" "F.Paste")
			(net 5 "+5V")
			(pintype "passive")
		)
		(pad "2" smd rect
			(at 2.8 0 270)
			(size 2.6 8.2)
			(layers "F.Cu" "F.Mask" "F.Paste")
			(net 124 "/Power/SW_12V")
			(pintype "passive")
		)
	)
	(footprint "antmicro-footprints:R_0402_1005Metric"
		(layer "F.Cu")
		(at 139.192 93.472)
		(descr "Resistor SMD 0402")
		(tags "resistor SMD 0402")
		(property "Reference" "R32"
			(at 0.99 -0.508 0)
			(layer "F.SilkS")
			(effects
				(font
					(size 0.7 0.7)
					(thickness 0.15)
				)
				(justify left bottom)
			)
		)
		(property "Value" "R_10k_0402"
			(at -1.011843 1.772047 0)
			(layer "F.Fab")
			(effects
				(font
					(size 0.7 0.7)
					(thickness 0.15)
				)
				(justify left bottom)
			)
		)
		(property "Datasheet" "https://www.bourns.com/docs/product-datasheets/cr.pdf"
			(at 0 0 0)
			(layer "F.Fab")
			(hide yes)
			(effects
				(font
					(size 1.27 1.27)
					(thickness 0.15)
				)
			)
		)
		(property "Description" "SMD Chip Resistor, 10 kohm, ± 1%, 62.5 mW, 0402 [1005 Metric], Thick Film, General Purpose"
			(at 0 0 0)
			(layer "F.Fab")
			(hide yes)
			(effects
				(font
					(size 1.27 1.27)
					(thickness 0.15)
				)
			)
		)
		(property "Author" "Antmicro"
			(at 0 0 0)
			(layer "F.Fab")
			(hide yes)
			(effects
				(font
					(size 1 1)
					(thickness 0.15)
				)
			)
		)
		(property "License" "Apache-2.0"
			(at 0 0 0)
			(layer "F.Fab")
			(hide yes)
			(effects
				(font
					(size 1 1)
					(thickness 0.15)
				)
			)
		)
		(property "MPN" "CR0402-FX-1002GLF"
			(at 0 0 0)
			(layer "F.Fab")
			(hide yes)
			(effects
				(font
					(size 1 1)
					(thickness 0.15)
				)
			)
		)
		(property "Manufacturer" "Bourns"
			(at 0 0 0)
			(layer "F.Fab")
			(hide yes)
			(effects
				(font
					(size 1 1)
					(thickness 0.15)
				)
			)
		)
		(property "Tolerance" "1%"
			(at 0 0 0)
			(layer "F.Fab")
			(hide yes)
			(effects
				(font
					(size 1 1)
					(thickness 0.15)
				)
			)
		)
		(property "Val" "10k"
			(at 0 0 0)
			(layer "F.Fab")
			(hide yes)
			(effects
				(font
					(size 1 1)
					(thickness 0.15)
				)
			)
		)
		(sheetname "/Power/")
		(sheetfile "power.kicad_sch")
		(attr smd)
		(fp_rect
			(start -0.925 -0.47)
			(end 0.925 0.47)
			(stroke
				(width 0.05)
				(type default)
			)
			(fill no)
			(layer "F.CrtYd")
		)
		(fp_rect
			(start -0.5 -0.25)
			(end 0.5 0.25)
			(stroke
				(width 0.15)
				(type solid)
			)
			(fill no)
			(layer "F.Fab")
		)
		(pad "1" smd roundrect
			(at -0.48 0)
			(size 0.59 0.64)
			(layers "F.Cu" "F.Mask" "F.Paste")
			(roundrect_rratio 0.25)
			(net 69 "/Power/EN_1V8")
			(pintype "passive")
		)
		(pad "2" smd roundrect
			(at 0.48 0)
			(size 0.59 0.64)
			(layers "F.Cu" "F.Mask" "F.Paste")
			(roundrect_rratio 0.25)
			(net 4 "+12V")
			(pintype "passive")
		)
	)
	(footprint "antmicro-footprints:R_0402_1005Metric"
		(layer "F.Cu")
		(at 167.386 59.817 90)
		(descr "Resistor SMD 0402")
		(tags "resistor SMD 0402")
		(property "Reference" "R5"
			(at -2.286 0.381 90)
			(layer "F.SilkS")
			(effects
				(font
					(size 0.7 0.7)
					(thickness 0.15)
				)
				(justify left bottom)
			)
		)
		(property "Value" "R_0R_0402"
			(at -1.011843 1.772047 90)
			(layer "F.Fab")
			(effects
				(font
					(size 0.7 0.7)
					(thickness 0.15)
				)
				(justify left bottom)
			)
		)
		(property "Datasheet" "https://industrial.panasonic.com/cdbs/www-data/pdf/RDA0000/AOA0000C301.pdf"
			(at 0 0 90)
			(layer "F.Fab")
			(hide yes)
			(effects
				(font
					(size 1.27 1.27)
					(thickness 0.15)
				)
			)
		)
		(property "Description" "SMD Chip Resistor, Jumper, 0 ohm, 100 mW, 0402 [1005 Metric], Thick Film, General Purpose"
			(at 0 0 90)
			(layer "F.Fab")
			(hide yes)
			(effects
				(font
					(size 1.27 1.27)
					(thickness 0.15)
				)
			)
		)
		(property "Author" "Antmicro"
			(at 227.203 -107.569 0)
			(layer "F.Fab")
			(hide yes)
			(effects
				(font
					(size 1 1)
					(thickness 0.15)
				)
			)
		)
		(property "Current" "1A"
			(at 227.203 -107.569 0)
			(layer "F.Fab")
			(hide yes)
			(effects
				(font
					(size 1 1)
					(thickness 0.15)
				)
			)
		)
		(property "License" "Apache-2.0"
			(at 227.203 -107.569 0)
			(layer "F.Fab")
			(hide yes)
			(effects
				(font
					(size 1 1)
					(thickness 0.15)
				)
			)
		)
		(property "MPN" "ERJ2GE0R00X"
			(at 227.203 -107.569 0)
			(layer "F.Fab")
			(hide yes)
			(effects
				(font
					(size 1 1)
					(thickness 0.15)
				)
			)
		)
		(property "Manufacturer" "Panasonic"
			(at 227.203 -107.569 0)
			(layer "F.Fab")
			(hide yes)
			(effects
				(font
					(size 1 1)
					(thickness 0.15)
				)
			)
		)
		(property "Tolerance" ""
			(at 227.203 -107.569 0)
			(layer "F.Fab")
			(hide yes)
			(effects
				(font
					(size 1 1)
					(thickness 0.15)
				)
			)
		)
		(property "Val" "0R"
			(at 227.203 -107.569 0)
			(layer "F.Fab")
			(hide yes)
			(effects
				(font
					(size 1 1)
					(thickness 0.15)
				)
			)
		)
		(sheetname "/Connectors/")
		(sheetfile "connectors.kicad_sch")
		(attr smd)
		(fp_rect
			(start -0.925 -0.47)
			(end 0.925 0.47)
			(stroke
				(width 0.05)
				(type default)
			)
			(fill no)
			(layer "F.CrtYd")
		)
		(fp_rect
			(start -0.5 -0.25)
			(end 0.5 0.25)
			(stroke
				(width 0.15)
				(type solid)
			)
			(fill no)
			(layer "F.Fab")
		)
		(pad "1" smd roundrect
			(at -0.48 0 90)
			(size 0.59 0.64)
			(layers "F.Cu" "F.Mask" "F.Paste")
			(roundrect_rratio 0.25)
			(net 82 "/Connectors/MFP2")
			(pintype "passive")
		)
		(pad "2" smd roundrect
			(at 0.48 0 90)
			(size 0.59 0.64)
			(layers "F.Cu" "F.Mask" "F.Paste")
			(roundrect_rratio 0.25)
			(net 132 "Net-(U2-Y)")
			(pintype "passive")
		)
	)
	(footprint "antmicro-footprints:R_0402_1005Metric"
		(layer "F.Cu")
		(at 130.563 74.422 -90)
		(descr "Resistor SMD 0402")
		(tags "resistor SMD 0402")
		(property "Reference" "R29"
			(at -1.122484 -1.263 90)
			(layer "F.SilkS")
			(effects
				(font
					(size 0.7 0.7)
					(thickness 0.15)
				)
				(justify right bottom)
			)
		)
		(property "Value" "R_13k7_0402"
			(at -1.011843 1.772047 90)
			(layer "F.Fab")
			(effects
				(font
					(size 0.7 0.7)
					(thickness 0.15)
				)
				(justify right bottom)
			)
		)
		(property "Datasheet" "https://www.bourns.com/docs/product-datasheets/cr.pdf"
			(at 0 0 270)
			(layer "F.Fab")
			(hide yes)
			(effects
				(font
					(size 1.27 1.27)
					(thickness 0.15)
				)
			)
		)
		(property "Description" "SMD Chip Resistor, Ceramic, 13.7 kohm, ± 1%, 62.5 mW, 0402 [1005 Metric], Thick Film"
			(at 0 0 270)
			(layer "F.Fab")
			(hide yes)
			(effects
				(font
					(size 1.27 1.27)
					(thickness 0.15)
				)
			)
		)
		(property "Author" "Antmicro"
			(at 56.141 204.985 0)
			(layer "F.Fab")
			(hide yes)
			(effects
				(font
					(size 1 1)
					(thickness 0.15)
				)
			)
		)
		(property "License" "Apache-2.0"
			(at 56.141 204.985 0)
			(layer "F.Fab")
			(hide yes)
			(effects
				(font
					(size 1 1)
					(thickness 0.15)
				)
			)
		)
		(property "MPN" "CR0402-FX-1372GLF"
			(at 56.141 204.985 0)
			(layer "F.Fab")
			(hide yes)
			(effects
				(font
					(size 1 1)
					(thickness 0.15)
				)
			)
		)
		(property "Manufacturer" "Bourns"
			(at 56.141 204.985 0)
			(layer "F.Fab")
			(hide yes)
			(effects
				(font
					(size 1 1)
					(thickness 0.15)
				)
			)
		)
		(property "Tolerance" "1%"
			(at 56.141 204.985 0)
			(layer "F.Fab")
			(hide yes)
			(effects
				(font
					(size 1 1)
					(thickness 0.15)
				)
			)
		)
		(property "Val" "13k7"
			(at 56.141 204.985 0)
			(layer "F.Fab")
			(hide yes)
			(effects
				(font
					(size 1 1)
					(thickness 0.15)
				)
			)
		)
		(sheetname "/Power/")
		(sheetfile "power.kicad_sch")
		(attr smd)
		(fp_rect
			(start -0.925 -0.47)
			(end 0.925 0.47)
			(stroke
				(width 0.05)
				(type default)
			)
			(fill no)
			(layer "F.CrtYd")
		)
		(fp_rect
			(start -0.5 -0.25)
			(end 0.5 0.25)
			(stroke
				(width 0.15)
				(type solid)
			)
			(fill no)
			(layer "F.Fab")
		)
		(pad "1" smd roundrect
			(at -0.48 0 270)
			(size 0.59 0.64)
			(layers "F.Cu" "F.Mask" "F.Paste")
			(roundrect_rratio 0.25)
			(net 1 "GND")
			(pintype "passive")
		)
		(pad "2" smd roundrect
			(at 0.48 0 270)
			(size 0.59 0.64)
			(layers "F.Cu" "F.Mask" "F.Paste")
			(roundrect_rratio 0.25)
			(net 122 "/Power/FB_12V")
			(pintype "passive")
		)
	)
	(footprint "antmicro-footprints:R_0402_1005Metric"
		(layer "F.Cu")
		(at 138.075 95.618)
		(descr "Resistor SMD 0402")
		(tags "resistor SMD 0402")
		(property "Reference" "R35"
			(at 0.99 0.394 0)
			(layer "F.SilkS")
			(effects
				(font
					(size 0.7 0.7)
					(thickness 0.15)
				)
				(justify left bottom)
			)
		)
		(property "Value" "R_12k4_0402"
			(at -1.011843 1.772047 0)
			(layer "F.Fab")
			(effects
				(font
					(size 0.7 0.7)
					(thickness 0.15)
				)
				(justify left bottom)
			)
		)
		(property "Datasheet" "https://www.bourns.com/docs/product-datasheets/cr.pdf"
			(at 0 0 0)
			(layer "F.Fab")
			(hide yes)
			(effects
				(font
					(size 1.27 1.27)
					(thickness 0.15)
				)
			)
		)
		(property "Description" "SMD Chip Resistor, 12.4 kohm, ± 1%, 62.5 mW, 0402 [1005 Metric], Thick Film, General Purpose"
			(at 0 0 0)
			(layer "F.Fab")
			(hide yes)
			(effects
				(font
					(size 1.27 1.27)
					(thickness 0.15)
				)
			)
		)
		(property "Author" "Antmicro"
			(at 0 0 0)
			(layer "F.Fab")
			(hide yes)
			(effects
				(font
					(size 1 1)
					(thickness 0.15)
				)
			)
		)
		(property "License" "Apache-2.0"
			(at 0 0 0)
			(layer "F.Fab")
			(hide yes)
			(effects
				(font
					(size 1 1)
					(thickness 0.15)
				)
			)
		)
		(property "MPN" "CR0402-FX-1242GLF"
			(at 0 0 0)
			(layer "F.Fab")
			(hide yes)
			(effects
				(font
					(size 1 1)
					(thickness 0.15)
				)
			)
		)
		(property "Manufacturer" "Bourns"
			(at 0 0 0)
			(layer "F.Fab")
			(hide yes)
			(effects
				(font
					(size 1 1)
					(thickness 0.15)
				)
			)
		)
		(property "Tolerance" "1%"
			(at 0 0 0)
			(layer "F.Fab")
			(hide yes)
			(effects
				(font
					(size 1 1)
					(thickness 0.15)
				)
			)
		)
		(property "Val" "12k4"
			(at 0 0 0)
			(layer "F.Fab")
			(hide yes)
			(effects
				(font
					(size 1 1)
					(thickness 0.15)
				)
			)
		)
		(sheetname "/Power/")
		(sheetfile "power.kicad_sch")
		(attr smd)
		(fp_rect
			(start -0.925 -0.47)
			(end 0.925 0.47)
			(stroke
				(width 0.05)
				(type default)
			)
			(fill no)
			(layer "F.CrtYd")
		)
		(fp_rect
			(start -0.5 -0.25)
			(end 0.5 0.25)
			(stroke
				(width 0.15)
				(type solid)
			)
			(fill no)
			(layer "F.Fab")
		)
		(pad "1" smd roundrect
			(at -0.48 0)
			(size 0.59 0.64)
			(layers "F.Cu" "F.Mask" "F.Paste")
			(roundrect_rratio 0.25)
			(net 70 "/Power/FB_1V8")
			(pintype "passive")
		)
		(pad "2" smd roundrect
			(at 0.48 0)
			(size 0.59 0.64)
			(layers "F.Cu" "F.Mask" "F.Paste")
			(roundrect_rratio 0.25)
			(net 10 "/Power/OUT_1V8")
			(pintype "passive")
		)
	)
	(footprint "antmicro-footprints:R_0402_1005Metric"
		(layer "F.Cu")
		(at 170.682 68.833)
		(descr "Resistor SMD 0402")
		(tags "resistor SMD 0402")
		(property "Reference" "R66"
			(at 0.768 0.345135 0)
			(layer "F.SilkS")
			(effects
				(font
					(size 0.7 0.7)
					(thickness 0.15)
				)
				(justify left bottom)
			)
		)
		(property "Value" "R_100R_0402"
			(at -1.011843 1.772047 0)
			(layer "F.Fab")
			(effects
				(font
					(size 0.7 0.7)
					(thickness 0.15)
				)
				(justify left bottom)
			)
		)
		(property "Datasheet" "https://www.bourns.com/docs/product-datasheets/cr.pdf"
			(at 0 0 0)
			(layer "F.Fab")
			(hide yes)
			(effects
				(font
					(size 1.27 1.27)
					(thickness 0.15)
				)
			)
		)
		(property "Description" "SMD Chip Resistor, 100 ohm, ± 1%, 62.5 mW, 0402 [1005 Metric], Thick Film, General Purpose"
			(at 0 0 0)
			(layer "F.Fab")
			(hide yes)
			(effects
				(font
					(size 1.27 1.27)
					(thickness 0.15)
				)
			)
		)
		(property "Author" "Antmicro"
			(at 0 0 0)
			(layer "F.Fab")
			(hide yes)
			(effects
				(font
					(size 1 1)
					(thickness 0.15)
				)
			)
		)
		(property "License" "Apache-2.0"
			(at 0 0 0)
			(layer "F.Fab")
			(hide yes)
			(effects
				(font
					(size 1 1)
					(thickness 0.15)
				)
			)
		)
		(property "MPN" "CR0402-FX-1000GLF"
			(at 0 0 0)
			(layer "F.Fab")
			(hide yes)
			(effects
				(font
					(size 1 1)
					(thickness 0.15)
				)
			)
		)
		(property "Manufacturer" "Bourns"
			(at 0 0 0)
			(layer "F.Fab")
			(hide yes)
			(effects
				(font
					(size 1 1)
					(thickness 0.15)
				)
			)
		)
		(property "Tolerance" "1%"
			(at 0 0 0)
			(layer "F.Fab")
			(hide yes)
			(effects
				(font
					(size 1 1)
					(thickness 0.15)
				)
			)
		)
		(property "Val" "100R"
			(at 0 0 0)
			(layer "F.Fab")
			(hide yes)
			(effects
				(font
					(size 1 1)
					(thickness 0.15)
				)
			)
		)
		(sheetname "/Connectors/")
		(sheetfile "connectors.kicad_sch")
		(attr smd)
		(fp_rect
			(start -0.925 -0.47)
			(end 0.925 0.47)
			(stroke
				(width 0.05)
				(type default)
			)
			(fill no)
			(layer "F.CrtYd")
		)
		(fp_rect
			(start -0.5 -0.25)
			(end 0.5 0.25)
			(stroke
				(width 0.15)
				(type solid)
			)
			(fill no)
			(layer "F.Fab")
		)
		(pad "1" smd roundrect
			(at -0.48 0)
			(size 0.59 0.64)
			(layers "F.Cu" "F.Mask" "F.Paste")
			(roundrect_rratio 0.25)
			(net 88 "/Connectors/SDA")
			(pintype "passive")
		)
		(pad "2" smd roundrect
			(at 0.48 0)
			(size 0.59 0.64)
			(layers "F.Cu" "F.Mask" "F.Paste")
			(roundrect_rratio 0.25)
			(net 133 "Net-(U8-A_{1})")
			(pintype "passive")
		)
	)
	(footprint "antmicro-footprints:DFN-10_2.5x1mm"
		(layer "F.Cu")
		(at 150.55 77.555355 -135)
		(property "Reference" "D5"
			(at -0.791817 1.849046 315)
			(unlocked yes)
			(layer "F.SilkS")
			(effects
				(font
					(size 0.7 0.7)
					(thickness 0.15)
				)
				(justify left bottom)
			)
		)
		(property "Value" "PESD4USB5U-TTS"
			(at 2.032 1.524 45)
			(layer "F.Fab")
			(effects
				(font
					(size 0.7 0.7)
					(thickness 0.15)
				)
				(justify right bottom)
			)
		)
		(property "Datasheet" "https://assets.nexperia.com/documents/data-sheet/PESD4USB5U-TTS.pdf"
			(at 0 0 225)
			(layer "F.Fab")
			(hide yes)
			(effects
				(font
					(size 1.27 1.27)
					(thickness 0.15)
				)
			)
		)
		(property "Description" "TVS diode array, 15kV, DFN-10, 5 V, 0.5 pF"
			(at 0 0 225)
			(layer "F.Fab")
			(hide yes)
			(effects
				(font
					(size 1.27 1.27)
					(thickness 0.15)
				)
			)
		)
		(property "Author" "Antmicro"
			(at 202.165008 238.850198 0)
			(layer "F.Fab")
			(hide yes)
			(effects
				(font
					(size 1 1)
					(thickness 0.15)
				)
			)
		)
		(property "License" "Apache-2.0"
			(at 202.165008 238.850198 0)
			(layer "F.Fab")
			(hide yes)
			(effects
				(font
					(size 1 1)
					(thickness 0.15)
				)
			)
		)
		(property "MPN" "PESD4USB5U-TTS"
			(at 202.165008 238.850198 0)
			(layer "F.Fab")
			(hide yes)
			(effects
				(font
					(size 1 1)
					(thickness 0.15)
				)
			)
		)
		(property "Manufacturer" "Nexperia"
			(at 202.165008 238.850198 0)
			(layer "F.Fab")
			(hide yes)
			(effects
				(font
					(size 1 1)
					(thickness 0.15)
				)
			)
		)
		(sheetname "/Deserializer/")
		(sheetfile "deserializer.kicad_sch")
		(attr smd)
		(fp_line
			(start -0.4 1.4)
			(end 0.4 1.4)
			(stroke
				(width 0.15)
				(type solid)
			)
			(layer "F.SilkS")
		)
		(fp_line
			(start 0.4 -1.4)
			(end -0.4 -1.4)
			(stroke
				(width 0.15)
				(type solid)
			)
			(layer "F.SilkS")
		)
		(fp_circle
			(center -0.762 -1.27)
			(end -0.712 -1.270001)
			(stroke
				(width 0.15)
				(type solid)
			)
			(fill yes)
			(layer "F.SilkS")
		)
		(fp_poly
			(pts
				(xy -0.85 -1.6) (xy 0.85 -1.6) (xy 0.85 1.6) (xy -0.85 1.6)
			)
			(stroke
				(width 0.05)
				(type solid)
			)
			(fill no)
			(layer "F.CrtYd")
		)
		(fp_line
			(start 0.5 1.25)
			(end 0.5 -1.25)
			(stroke
				(width 0.15)
				(type solid)
			)
			(layer "F.Fab")
		)
		(fp_line
			(start -0.5 1.25)
			(end 0.5 1.25)
			(stroke
				(width 0.15)
				(type solid)
			)
			(layer "F.Fab")
		)
		(fp_line
			(start 0.5 -1.25)
			(end -0.15 -1.249999)
			(stroke
				(width 0.15)
				(type solid)
			)
			(layer "F.Fab")
		)
		(fp_line
			(start -0.499999 -0.9)
			(end -0.5 1.25)
			(stroke
				(width 0.15)
				(type solid)
			)
			(layer "F.Fab")
		)
		(fp_line
			(start -0.15 -1.249999)
			(end -0.499999 -0.9)
			(stroke
				(width 0.15)
				(type solid)
			)
			(layer "F.Fab")
		)
		(pad "1" smd roundrect
			(at -0.425 -1 135)
			(size 0.2 0.6)
			(layers "F.Cu" "F.Mask" "F.Paste")
			(roundrect_rratio 0.25)
			(net 16 "/Deserializer/SIOD_P")
			(pinfunction "1")
			(pintype "passive")
			(solder_mask_margin 0.05)
		)
		(pad "2" smd roundrect
			(at -0.425 -0.5 135)
			(size 0.2 0.6)
			(layers "F.Cu" "F.Mask" "F.Paste")
			(roundrect_rratio 0.25)
			(net 24 "/Deserializer/SIOD_N")
			(pinfunction "2")
			(pintype "passive")
			(solder_mask_margin 0.05)
		)
		(pad "3" smd roundrect
			(at -0.424999 0 135)
			(size 0.4 0.6)
			(layers "F.Cu" "F.Mask" "F.Paste")
			(roundrect_rratio 0.25)
			(net 1 "GND")
			(pinfunction "3")
			(pintype "passive")
			(solder_mask_margin 0.05)
		)
		(pad "4" smd roundrect
			(at -0.425 0.5 135)
			(size 0.2 0.6)
			(layers "F.Cu" "F.Mask" "F.Paste")
			(roundrect_rratio 0.25)
			(net 22 "/Deserializer/SIOC_N")
			(pinfunction "4")
			(pintype "passive")
			(solder_mask_margin 0.05)
		)
		(pad "5" smd roundrect
			(at -0.425 1 135)
			(size 0.2 0.6)
			(layers "F.Cu" "F.Mask" "F.Paste")
			(roundrect_rratio 0.25)
			(net 15 "/Deserializer/SIOC_P")
			(pinfunction "5")
			(pintype "passive")
			(solder_mask_margin 0.05)
		)
		(pad "6" smd roundrect
			(at 0.425 1 135)
			(size 0.2 0.6)
			(layers "F.Cu" "F.Mask" "F.Paste")
			(roundrect_rratio 0.25)
			(net 15 "/Deserializer/SIOC_P")
			(pinfunction "6")
			(pintype "passive")
			(solder_mask_margin 0.05)
		)
		(pad "7" smd roundrect
			(at 0.425 0.5 135)
			(size 0.2 0.6)
			(layers "F.Cu" "F.Mask" "F.Paste")
			(roundrect_rratio 0.25)
			(net 22 "/Deserializer/SIOC_N")
			(pinfunction "7")
			(pintype "passive")
			(solder_mask_margin 0.05)
		)
		(pad "8" smd roundrect
			(at 0.424999 0 135)
			(size 0.4 0.6)
			(layers "F.Cu" "F.Mask" "F.Paste")
			(roundrect_rratio 0.25)
			(net 1 "GND")
			(pinfunction "8")
			(pintype "passive")
			(solder_mask_margin 0.05)
		)
		(pad "9" smd roundrect
			(at 0.425 -0.5 135)
			(size 0.2 0.6)
			(layers "F.Cu" "F.Mask" "F.Paste")
			(roundrect_rratio 0.25)
			(net 24 "/Deserializer/SIOD_N")
			(pinfunction "9")
			(pintype "passive")
			(solder_mask_margin 0.05)
		)
		(pad "10" smd roundrect
			(at 0.425 -1 135)
			(size 0.2 0.6)
			(layers "F.Cu" "F.Mask" "F.Paste")
			(roundrect_rratio 0.25)
			(net 16 "/Deserializer/SIOD_P")
			(pinfunction "10")
			(pintype "passive")
			(solder_mask_margin 0.05)
		)
	)
	(footprint "antmicro-footprints:C_0402_1005Metric"
		(layer "F.Cu")
		(at 158.424 66.548 90)
		(descr "Capacitor SMD 0402")
		(tags "capacitor SMD 0402")
		(property "Reference" "C13"
			(at -1.905 1.215 90)
			(layer "F.SilkS")
			(effects
				(font
					(size 0.7 0.7)
					(thickness 0.15)
				)
				(justify left bottom)
			)
		)
		(property "Value" "C_10n_0402"
			(at -1.022927 2.155213 90)
			(layer "F.Fab")
			(effects
				(font
					(size 0.7 0.7)
					(thickness 0.15)
				)
				(justify left bottom)
			)
		)
		(property "Datasheet" "https://www.murata.com/products/productdetail?partno=GRM155R71H103KA88%23"
			(at 0 0 90)
			(layer "F.Fab")
			(hide yes)
			(effects
				(font
					(size 1.27 1.27)
					(thickness 0.15)
				)
			)
		)
		(property "Description" "SMD Multilayer Ceramic Capacitor, 10000 pF, 50 V, 0402 [1005 Metric], ± 10%, X7R, GRM Series"
			(at 0 0 90)
			(layer "F.Fab")
			(hide yes)
			(effects
				(font
					(size 1.27 1.27)
					(thickness 0.15)
				)
			)
		)
		(property "Author" "Antmicro"
			(at 224.972 -91.876 0)
			(layer "F.Fab")
			(hide yes)
			(effects
				(font
					(size 1 1)
					(thickness 0.15)
				)
			)
		)
		(property "Dielectric" "X7R"
			(at 224.972 -91.876 0)
			(layer "F.Fab")
			(hide yes)
			(effects
				(font
					(size 1 1)
					(thickness 0.15)
				)
			)
		)
		(property "License" "Apache-2.0"
			(at 224.972 -91.876 0)
			(layer "F.Fab")
			(hide yes)
			(effects
				(font
					(size 1 1)
					(thickness 0.15)
				)
			)
		)
		(property "MPN" "GRM155R71H103KA88D"
			(at 224.972 -91.876 0)
			(layer "F.Fab")
			(hide yes)
			(effects
				(font
					(size 1 1)
					(thickness 0.15)
				)
			)
		)
		(property "Manufacturer" "Murata"
			(at 224.972 -91.876 0)
			(layer "F.Fab")
			(hide yes)
			(effects
				(font
					(size 1 1)
					(thickness 0.15)
				)
			)
		)
		(property "Val" "10n"
			(at 224.972 -91.876 0)
			(layer "F.Fab")
			(hide yes)
			(effects
				(font
					(size 1 1)
					(thickness 0.15)
				)
			)
		)
		(property "Voltage" "50V"
			(at 224.972 -91.876 0)
			(layer "F.Fab")
			(hide yes)
			(effects
				(font
					(size 1 1)
					(thickness 0.15)
				)
			)
		)
		(sheetname "/Power/")
		(sheetfile "power.kicad_sch")
		(attr smd)
		(fp_rect
			(start -0.925 -0.47)
			(end 0.925 0.47)
			(stroke
				(width 0.05)
				(type default)
			)
			(fill no)
			(layer "F.CrtYd")
		)
		(fp_line
			(start 0.504 -0.25)
			(end 0.504 0.248)
			(stroke
				(width 0.15)
				(type solid)
			)
			(layer "F.Fab")
		)
		(fp_line
			(start -0.494 -0.25)
			(end 0.504 -0.25)
			(stroke
				(width 0.15)
				(type solid)
			)
			(layer "F.Fab")
		)
		(fp_line
			(start 0.504 0.248)
			(end -0.494 0.248)
			(stroke
				(width 0.15)
				(type solid)
			)
			(layer "F.Fab")
		)
		(fp_line
			(start -0.494 0.248)
			(end -0.494 -0.25)
			(stroke
				(width 0.15)
				(type solid)
			)
			(layer "F.Fab")
		)
		(pad "1" smd roundrect
			(at -0.48 0 90)
			(size 0.59 0.64)
			(layers "F.Cu" "F.Mask" "F.Paste")
			(roundrect_rratio 0.25)
			(net 1 "GND")
			(pintype "passive")
		)
		(pad "2" smd roundrect
			(at 0.48 0 90)
			(size 0.59 0.64)
			(layers "F.Cu" "F.Mask" "F.Paste")
			(roundrect_rratio 0.25)
			(net 4 "+12V")
			(pintype "passive")
		)
	)
	(footprint "antmicro-footprints:C_0402_1005Metric"
		(layer "F.Cu")
		(at 179.498 62.33 -90)
		(descr "Capacitor SMD 0402")
		(tags "capacitor SMD 0402")
		(property "Reference" "C31"
			(at 7.8422 -0.588 90)
			(layer "F.SilkS")
			(effects
				(font
					(size 0.7 0.7)
					(thickness 0.15)
				)
				(justify right bottom)
			)
		)
		(property "Value" "C_100n_0402"
			(at -1.022927 2.155213 90)
			(layer "F.Fab")
			(effects
				(font
					(size 0.7 0.7)
					(thickness 0.15)
				)
				(justify right bottom)
			)
		)
		(property "Datasheet" "https://www.murata.com/products/productdetail?partno=GRM155R61H104KE14%23"
			(at 0 0 270)
			(layer "F.Fab")
			(hide yes)
			(effects
				(font
					(size 1.27 1.27)
					(thickness 0.15)
				)
			)
		)
		(property "Description" "SMD Multilayer Ceramic Capacitor, 0.1 µF, 50 V, 0402 [1005 Metric], ± 10%, X5R, GRM Series"
			(at 0 0 270)
			(layer "F.Fab")
			(hide yes)
			(effects
				(font
					(size 1.27 1.27)
					(thickness 0.15)
				)
			)
		)
		(property "Author" "Antmicro"
			(at 117.168 241.828 0)
			(layer "F.Fab")
			(hide yes)
			(effects
				(font
					(size 1 1)
					(thickness 0.15)
				)
			)
		)
		(property "Dielectric" "X5R"
			(at 117.168 241.828 0)
			(layer "F.Fab")
			(hide yes)
			(effects
				(font
					(size 1 1)
					(thickness 0.15)
				)
			)
		)
		(property "License" "Apache-2.0"
			(at 117.168 241.828 0)
			(layer "F.Fab")
			(hide yes)
			(effects
				(font
					(size 1 1)
					(thickness 0.15)
				)
			)
		)
		(property "MPN" "GRM155R61H104KE14D"
			(at 117.168 241.828 0)
			(layer "F.Fab")
			(hide yes)
			(effects
				(font
					(size 1 1)
					(thickness 0.15)
				)
			)
		)
		(property "Manufacturer" "Murata"
			(at 117.168 241.828 0)
			(layer "F.Fab")
			(hide yes)
			(effects
				(font
					(size 1 1)
					(thickness 0.15)
				)
			)
		)
		(property "Val" "100n"
			(at 117.168 241.828 0)
			(layer "F.Fab")
			(hide yes)
			(effects
				(font
					(size 1 1)
					(thickness 0.15)
				)
			)
		)
		(property "Voltage" "50V"
			(at 117.168 241.828 0)
			(layer "F.Fab")
			(hide yes)
			(effects
				(font
					(size 1 1)
					(thickness 0.15)
				)
			)
		)
		(sheetname "/Connectors/")
		(sheetfile "connectors.kicad_sch")
		(attr smd)
		(fp_rect
			(start -0.925 -0.47)
			(end 0.925 0.47)
			(stroke
				(width 0.05)
				(type default)
			)
			(fill no)
			(layer "F.CrtYd")
		)
		(fp_line
			(start -0.494 0.248)
			(end -0.494 -0.25)
			(stroke
				(width 0.15)
				(type solid)
			)
			(layer "F.Fab")
		)
		(fp_line
			(start 0.504 0.248)
			(end -0.494 0.248)
			(stroke
				(width 0.15)
				(type solid)
			)
			(layer "F.Fab")
		)
		(fp_line
			(start -0.494 -0.25)
			(end 0.504 -0.25)
			(stroke
				(width 0.15)
				(type solid)
			)
			(layer "F.Fab")
		)
		(fp_line
			(start 0.504 -0.25)
			(end 0.504 0.248)
			(stroke
				(width 0.15)
				(type solid)
			)
			(layer "F.Fab")
		)
		(pad "1" smd roundrect
			(at -0.48 0 270)
			(size 0.59 0.64)
			(layers "F.Cu" "F.Mask" "F.Paste")
			(roundrect_rratio 0.25)
			(net 1 "GND")
			(pintype "passive")
		)
		(pad "2" smd roundrect
			(at 0.48 0 270)
			(size 0.59 0.64)
			(layers "F.Cu" "F.Mask" "F.Paste")
			(roundrect_rratio 0.25)
			(net 50 "/Connectors/FFC_3V3")
			(pintype "passive")
		)
	)
	(footprint "antmicro-footprints:C_0402_1005Metric"
		(layer "F.Cu")
		(at 180.514 62.354 -90)
		(descr "Capacitor SMD 0402")
		(tags "capacitor SMD 0402")
		(property "Reference" "C58"
			(at 7.9242 -0.592 90)
			(layer "F.SilkS")
			(effects
				(font
					(size 0.7 0.7)
					(thickness 0.15)
				)
				(justify right bottom)
			)
		)
		(property "Value" "C_1u_0402"
			(at -1.022927 2.155213 90)
			(layer "F.Fab")
			(effects
				(font
					(size 0.7 0.7)
					(thickness 0.15)
				)
				(justify right bottom)
			)
		)
		(property "Datasheet" "https://product.tdk.com/en/search/capacitor/ceramic/mlcc/info?part_no=C1005X6S1A105K050BC"
			(at 0 0 270)
			(layer "F.Fab")
			(hide yes)
			(effects
				(font
					(size 1.27 1.27)
					(thickness 0.15)
				)
			)
		)
		(property "Description" "SMD Multilayer Ceramic Capacitor, 1 µF, 10 V, 0402 [1005 Metric], ± 10%, X6S, C"
			(at 0 0 270)
			(layer "F.Fab")
			(hide yes)
			(effects
				(font
					(size 1.27 1.27)
					(thickness 0.15)
				)
			)
		)
		(property "Author" "Antmicro"
			(at 118.16 242.868 0)
			(layer "F.Fab")
			(hide yes)
			(effects
				(font
					(size 1 1)
					(thickness 0.15)
				)
			)
		)
		(property "Dielectric" ""
			(at 118.16 242.868 0)
			(layer "F.Fab")
			(hide yes)
			(effects
				(font
					(size 1 1)
					(thickness 0.15)
				)
			)
		)
		(property "License" "Apache-2.0"
			(at 118.16 242.868 0)
			(layer "F.Fab")
			(hide yes)
			(effects
				(font
					(size 1 1)
					(thickness 0.15)
				)
			)
		)
		(property "MPN" "C1005X6S1A105K050BC"
			(at 118.16 242.868 0)
			(layer "F.Fab")
			(hide yes)
			(effects
				(font
					(size 1 1)
					(thickness 0.15)
				)
			)
		)
		(property "Manufacturer" "TDK"
			(at 118.16 242.868 0)
			(layer "F.Fab")
			(hide yes)
			(effects
				(font
					(size 1 1)
					(thickness 0.15)
				)
			)
		)
		(property "Val" "1u"
			(at 118.16 242.868 0)
			(layer "F.Fab")
			(hide yes)
			(effects
				(font
					(size 1 1)
					(thickness 0.15)
				)
			)
		)
		(property "Voltage" ""
			(at 118.16 242.868 0)
			(layer "F.Fab")
			(hide yes)
			(effects
				(font
					(size 1 1)
					(thickness 0.15)
				)
			)
		)
		(sheetname "/Connectors/")
		(sheetfile "connectors.kicad_sch")
		(attr smd)
		(fp_rect
			(start -0.925 -0.47)
			(end 0.925 0.47)
			(stroke
				(width 0.05)
				(type default)
			)
			(fill no)
			(layer "F.CrtYd")
		)
		(fp_line
			(start -0.494 0.248)
			(end -0.494 -0.25)
			(stroke
				(width 0.15)
				(type solid)
			)
			(layer "F.Fab")
		)
		(fp_line
			(start 0.504 0.248)
			(end -0.494 0.248)
			(stroke
				(width 0.15)
				(type solid)
			)
			(layer "F.Fab")
		)
		(fp_line
			(start -0.494 -0.25)
			(end 0.504 -0.25)
			(stroke
				(width 0.15)
				(type solid)
			)
			(layer "F.Fab")
		)
		(fp_line
			(start 0.504 -0.25)
			(end 0.504 0.248)
			(stroke
				(width 0.15)
				(type solid)
			)
			(layer "F.Fab")
		)
		(pad "1" smd roundrect
			(at -0.48 0 270)
			(size 0.59 0.64)
			(layers "F.Cu" "F.Mask" "F.Paste")
			(roundrect_rratio 0.25)
			(net 1 "GND")
			(pintype "passive")
		)
		(pad "2" smd roundrect
			(at 0.48 0 270)
			(size 0.59 0.64)
			(layers "F.Cu" "F.Mask" "F.Paste")
			(roundrect_rratio 0.25)
			(net 50 "/Connectors/FFC_3V3")
			(pintype "passive")
		)
	)
	(footprint "antmicro-footprints:TP_SMD_0.75mm"
		(layer "F.Cu")
		(at 156.972 97.89)
		(property "Reference" "TP8"
			(at 0 -0.6 0)
			(layer "F.SilkS")
			(hide yes)
			(effects
				(font
					(size 0.7 0.7)
					(thickness 0.15)
				)
				(justify left bottom)
			)
		)
		(property "Value" "TP_0.75mm_SMD"
			(at 0 1.2 0)
			(layer "F.Fab")
			(effects
				(font
					(size 0.7 0.7)
					(thickness 0.15)
				)
				(justify left bottom)
			)
		)
		(property "Description" "SMT test point"
			(at 0 0 0)
			(layer "F.Fab")
			(hide yes)
			(effects
				(font
					(size 1.27 1.27)
					(thickness 0.15)
				)
			)
		)
		(property "Author" "Antmicro"
			(at 0 0 0)
			(layer "F.Fab")
			(hide yes)
			(effects
				(font
					(size 1 1)
					(thickness 0.15)
				)
			)
		)
		(property "License" "Apache-2.0"
			(at 0 0 0)
			(layer "F.Fab")
			(hide yes)
			(effects
				(font
					(size 1 1)
					(thickness 0.15)
				)
			)
		)
		(property "MPN" ""
			(at 0 0 0)
			(layer "F.Fab")
			(hide yes)
			(effects
				(font
					(size 1 1)
					(thickness 0.15)
				)
			)
		)
		(property "Manufacturer" ""
			(at 0 0 0)
			(layer "F.Fab")
			(hide yes)
			(effects
				(font
					(size 1 1)
					(thickness 0.15)
				)
			)
		)
		(sheetname "/Connectors/")
		(sheetfile "connectors.kicad_sch")
		(fp_circle
			(center 0 0)
			(end 0.475 0)
			(stroke
				(width 0.05)
				(type default)
			)
			(fill no)
			(layer "F.CrtYd")
		)
		(pad "1" smd circle
			(at 0 0)
			(size 0.75 0.75)
			(layers "F.Cu" "F.Mask")
			(net 50 "/Connectors/FFC_3V3")
			(pinfunction "1")
			(pintype "passive")
		)
	)
	(footprint "antmicro-footprints:R_0402_1005Metric"
		(layer "F.Cu")
		(at 127.255 61.976 90)
		(descr "Resistor SMD 0402")
		(tags "resistor SMD 0402")
		(property "Reference" "R19"
			(at -1.1405 1.27 90)
			(layer "F.SilkS")
			(effects
				(font
					(size 0.7 0.7)
					(thickness 0.15)
				)
				(justify left bottom)
			)
		)
		(property "Value" "R_5k1_0402"
			(at -1.011843 1.772047 90)
			(layer "F.Fab")
			(effects
				(font
					(size 0.7 0.7)
					(thickness 0.15)
				)
				(justify left bottom)
			)
		)
		(property "Datasheet" "https://www.bourns.com/docs/product-datasheets/cr.pdf"
			(at 0 0 90)
			(layer "F.Fab")
			(hide yes)
			(effects
				(font
					(size 1.27 1.27)
					(thickness 0.15)
				)
			)
		)
		(property "Description" "SMD Chip Resistor, 5.1 kohm, ± 1%, 63 mW, 0402 [1005 Metric], Thick Film, General Purpose"
			(at 0 0 90)
			(layer "F.Fab")
			(hide yes)
			(effects
				(font
					(size 1.27 1.27)
					(thickness 0.15)
				)
			)
		)
		(property "Author" "Antmicro"
			(at 189.231 -65.279 0)
			(layer "F.Fab")
			(hide yes)
			(effects
				(font
					(size 1 1)
					(thickness 0.15)
				)
			)
		)
		(property "License" "Apache-2.0"
			(at 189.231 -65.279 0)
			(layer "F.Fab")
			(hide yes)
			(effects
				(font
					(size 1 1)
					(thickness 0.15)
				)
			)
		)
		(property "MPN" "CR0402-FX-5101GLF"
			(at 189.231 -65.279 0)
			(layer "F.Fab")
			(hide yes)
			(effects
				(font
					(size 1 1)
					(thickness 0.15)
				)
			)
		)
		(property "Manufacturer" "Bourns"
			(at 189.231 -65.279 0)
			(layer "F.Fab")
			(hide yes)
			(effects
				(font
					(size 1 1)
					(thickness 0.15)
				)
			)
		)
		(property "Tolerance" "1%"
			(at 189.231 -65.279 0)
			(layer "F.Fab")
			(hide yes)
			(effects
				(font
					(size 1 1)
					(thickness 0.15)
				)
			)
		)
		(property "Val" "5k1"
			(at 189.231 -65.279 0)
			(layer "F.Fab")
			(hide yes)
			(effects
				(font
					(size 1 1)
					(thickness 0.15)
				)
			)
		)
		(sheetname "/Power/")
		(sheetfile "power.kicad_sch")
		(attr smd)
		(fp_rect
			(start -0.925 -0.47)
			(end 0.925 0.47)
			(stroke
				(width 0.05)
				(type default)
			)
			(fill no)
			(layer "F.CrtYd")
		)
		(fp_rect
			(start -0.5 -0.25)
			(end 0.5 0.25)
			(stroke
				(width 0.15)
				(type solid)
			)
			(fill no)
			(layer "F.Fab")
		)
		(pad "1" smd roundrect
			(at -0.48 0 90)
			(size 0.59 0.64)
			(layers "F.Cu" "F.Mask" "F.Paste")
			(roundrect_rratio 0.25)
			(net 4 "+12V")
			(pintype "passive")
		)
		(pad "2" smd roundrect
			(at 0.48 0 90)
			(size 0.59 0.64)
			(layers "F.Cu" "F.Mask" "F.Paste")
			(roundrect_rratio 0.25)
			(net 51 "Net-(L1-Pad2)")
			(pintype "passive")
		)
	)
	(footprint "antmicro-footprints:C_0402_1005Metric"
		(layer "F.Cu")
		(at 173.91 61.722 90)
		(descr "Capacitor SMD 0402")
		(tags "capacitor SMD 0402")
		(property "Reference" "C26"
			(at 0.830095 0.424135 90)
			(layer "F.SilkS")
			(effects
				(font
					(size 0.7 0.7)
					(thickness 0.15)
				)
				(justify left bottom)
			)
		)
		(property "Value" "C_100n_0402"
			(at -1.022927 2.155213 90)
			(layer "F.Fab")
			(effects
				(font
					(size 0.7 0.7)
					(thickness 0.15)
				)
				(justify left bottom)
			)
		)
		(property "Datasheet" "https://www.murata.com/products/productdetail?partno=GRM155R61H104KE14%23"
			(at 0 0 90)
			(layer "F.Fab")
			(hide yes)
			(effects
				(font
					(size 1.27 1.27)
					(thickness 0.15)
				)
			)
		)
		(property "Description" "SMD Multilayer Ceramic Capacitor, 0.1 µF, 50 V, 0402 [1005 Metric], ± 10%, X5R, GRM Series"
			(at 0 0 90)
			(layer "F.Fab")
			(hide yes)
			(effects
				(font
					(size 1.27 1.27)
					(thickness 0.15)
				)
			)
		)
		(property "Author" "Antmicro"
			(at 235.632 -112.188 0)
			(layer "F.Fab")
			(hide yes)
			(effects
				(font
					(size 1 1)
					(thickness 0.15)
				)
			)
		)
		(property "Dielectric" "X5R"
			(at 235.632 -112.188 0)
			(layer "F.Fab")
			(hide yes)
			(effects
				(font
					(size 1 1)
					(thickness 0.15)
				)
			)
		)
		(property "License" "Apache-2.0"
			(at 235.632 -112.188 0)
			(layer "F.Fab")
			(hide yes)
			(effects
				(font
					(size 1 1)
					(thickness 0.15)
				)
			)
		)
		(property "MPN" "GRM155R61H104KE14D"
			(at 235.632 -112.188 0)
			(layer "F.Fab")
			(hide yes)
			(effects
				(font
					(size 1 1)
					(thickness 0.15)
				)
			)
		)
		(property "Manufacturer" "Murata"
			(at 235.632 -112.188 0)
			(layer "F.Fab")
			(hide yes)
			(effects
				(font
					(size 1 1)
					(thickness 0.15)
				)
			)
		)
		(property "Val" "100n"
			(at 235.632 -112.188 0)
			(layer "F.Fab")
			(hide yes)
			(effects
				(font
					(size 1 1)
					(thickness 0.15)
				)
			)
		)
		(property "Voltage" "50V"
			(at 235.632 -112.188 0)
			(layer "F.Fab")
			(hide yes)
			(effects
				(font
					(size 1 1)
					(thickness 0.15)
				)
			)
		)
		(sheetname "/Connectors/")
		(sheetfile "connectors.kicad_sch")
		(attr smd)
		(fp_rect
			(start -0.925 -0.47)
			(end 0.925 0.47)
			(stroke
				(width 0.05)
				(type default)
			)
			(fill no)
			(layer "F.CrtYd")
		)
		(fp_line
			(start 0.504 -0.25)
			(end 0.504 0.248)
			(stroke
				(width 0.15)
				(type solid)
			)
			(layer "F.Fab")
		)
		(fp_line
			(start -0.494 -0.25)
			(end 0.504 -0.25)
			(stroke
				(width 0.15)
				(type solid)
			)
			(layer "F.Fab")
		)
		(fp_line
			(start 0.504 0.248)
			(end -0.494 0.248)
			(stroke
				(width 0.15)
				(type solid)
			)
			(layer "F.Fab")
		)
		(fp_line
			(start -0.494 0.248)
			(end -0.494 -0.25)
			(stroke
				(width 0.15)
				(type solid)
			)
			(layer "F.Fab")
		)
		(pad "1" smd roundrect
			(at -0.48 0 90)
			(size 0.59 0.64)
			(layers "F.Cu" "F.Mask" "F.Paste")
			(roundrect_rratio 0.25)
			(net 1 "GND")
			(pintype "passive")
		)
		(pad "2" smd roundrect
			(at 0.48 0 90)
			(size 0.59 0.64)
			(layers "F.Cu" "F.Mask" "F.Paste")
			(roundrect_rratio 0.25)
			(net 3 "+1V8")
			(pintype "passive")
		)
	)
	(footprint "antmicro-footprints:Vishay_PowerPAK_1212-8_Single"
		(layer "F.Cu")
		(at 174.752 56.134 90)
		(descr "PowerPAK 1212-8 Single")
		(tags "Vishay PowerPAK 1212-8 Single")
		(property "Reference" "Q2"
			(at 1.957953 0.923594 180)
			(layer "F.SilkS")
			(effects
				(font
					(size 0.7 0.7)
					(thickness 0.15)
				)
				(justify left bottom)
			)
		)
		(property "Value" "SQS401EN-T1_BE3"
			(at 0 2.7 90)
			(layer "F.Fab")
			(effects
				(font
					(size 0.7 0.7)
					(thickness 0.15)
				)
				(justify left bottom)
			)
		)
		(property "Datasheet" "https://www.vishay.com/docs/65529/sqs401en.pdf"
			(at 0 0 90)
			(layer "F.Fab")
			(hide yes)
			(effects
				(font
					(size 1.27 1.27)
					(thickness 0.15)
				)
			)
		)
		(property "Description" "MOSFET, P Channel, 40 V, 16A, 0.047 ohm, PowerPAK 1212-8, Surface Mount"
			(at 0 0 90)
			(layer "F.Fab")
			(hide yes)
			(effects
				(font
					(size 1.27 1.27)
					(thickness 0.15)
				)
			)
		)
		(property "Author" "Antmicro"
			(at 230.886 -118.618 0)
			(layer "F.Fab")
			(hide yes)
			(effects
				(font
					(size 1 1)
					(thickness 0.15)
				)
			)
		)
		(property "License" "Apache-2.0"
			(at 230.886 -118.618 0)
			(layer "F.Fab")
			(hide yes)
			(effects
				(font
					(size 1 1)
					(thickness 0.15)
				)
			)
		)
		(property "MPN" "SQS401EN-T1_BE3"
			(at 230.886 -118.618 0)
			(layer "F.Fab")
			(hide yes)
			(effects
				(font
					(size 1 1)
					(thickness 0.15)
				)
			)
		)
		(property "Manufacturer" "Vishay"
			(at 230.886 -118.618 0)
			(layer "F.Fab")
			(hide yes)
			(effects
				(font
					(size 1 1)
					(thickness 0.15)
				)
			)
		)
		(sheetname "/Power/")
		(sheetfile "power.kicad_sch")
		(attr smd)
		(fp_line
			(start 1.648 -1.651)
			(end 1.648 -1.317)
			(stroke
				(width 0.15)
				(type solid)
			)
			(layer "F.SilkS")
		)
		(fp_line
			(start -1.651 -1.651)
			(end 1.648 -1.651)
			(stroke
				(width 0.15)
				(type solid)
			)
			(layer "F.SilkS")
		)
		(fp_line
			(start -1.651 -1.651)
			(end -1.651 -1.317)
			(stroke
				(width 0.15)
				(type solid)
			)
			(layer "F.SilkS")
		)
		(fp_line
			(start 1.634 1.3)
			(end 1.634 1.634)
			(stroke
				(width 0.15)
				(type solid)
			)
			(layer "F.SilkS")
		)
		(fp_line
			(start -1.635 1.3)
			(end -1.635 1.634)
			(stroke
				(width 0.15)
				(type solid)
			)
			(layer "F.SilkS")
		)
		(fp_line
			(start -1.635 1.634)
			(end 1.634 1.634)
			(stroke
				(width 0.15)
				(type solid)
			)
			(layer "F.SilkS")
		)
		(fp_circle
			(center -1.9 -1.4)
			(end -1.85 -1.4)
			(stroke
				(width 0.15)
				(type solid)
			)
			(fill yes)
			(layer "F.SilkS")
		)
		(fp_rect
			(start -2 -1.8)
			(end 2 1.798)
			(stroke
				(width 0.05)
				(type solid)
			)
			(fill no)
			(layer "F.CrtYd")
		)
		(fp_line
			(start -1.6425 -1.4175)
			(end -1.4175 -1.6425)
			(stroke
				(width 0.15)
				(type solid)
			)
			(layer "F.Fab")
		)
		(fp_rect
			(start -1.651 -1.651)
			(end 1.648 1.648)
			(stroke
				(width 0.15)
				(type solid)
			)
			(fill no)
			(layer "F.Fab")
		)
		(pad "1" smd rect
			(at -1.436 -0.99 90)
			(size 0.99 0.405)
			(layers "F.Cu" "F.Mask" "F.Paste")
			(net 4 "+12V")
			(pinfunction "S")
			(pintype "passive")
		)
		(pad "2" smd rect
			(at -1.436 -0.332 90)
			(size 0.99 0.405)
			(layers "F.Cu" "F.Mask" "F.Paste")
			(net 4 "+12V")
			(pinfunction "S")
			(pintype "passive")
		)
		(pad "3" smd rect
			(at -1.436 0.33 90)
			(size 0.99 0.405)
			(layers "F.Cu" "F.Mask" "F.Paste")
			(net 4 "+12V")
			(pinfunction "S")
			(pintype "passive")
		)
		(pad "4" smd rect
			(at -1.436 0.988 90)
			(size 0.99 0.405)
			(layers "F.Cu" "F.Mask" "F.Paste")
			(net 127 "Net-(Q2-G)")
			(pinfunction "G")
			(pintype "input")
		)
		(pad "5" smd custom
			(at 0.557 0 90)
			(size 1.725 2.235)
			(layers "F.Cu" "F.Mask" "F.Paste")
			(net 118 "/Connectors/DC_IN")
			(pinfunction "D")
			(pintype "passive")
			(zone_connect 2)
			(options
				(clearance outline)
				(anchor rect)
			)
			(primitives
				(gr_poly
					(pts
						(xy 0.8625 0.1275) (xy 0.8625 -0.1275) (xy 1.3725 -0.1275) (xy 1.3725 -0.5325) (xy 0.8625 -0.5325)
						(xy 0.8625 -0.7875) (xy 1.3725 -0.7875) (xy 1.3725 -1.195) (xy 0.6125 -1.195) (xy 0.6125 1.195)
						(xy 1.3725 1.195) (xy 1.3725 0.7875) (xy 0.8625 0.7875) (xy 0.8625 0.5325) (xy 1.3725 0.5325)
						(xy 1.3725 0.1275)
					)
					(width 0)
					(fill yes)
				)
			)
		)
	)
	(footprint "antmicro-footprints:C_0603_1608Metric"
		(layer "F.Cu")
		(at 173.99 53.34 180)
		(descr "Capacitor SMD 0603")
		(tags "capacitor 0603")
		(property "Reference" "C1"
			(at -1.156321 0.115777 0)
			(layer "F.SilkS")
			(effects
				(font
					(size 0.7 0.7)
					(thickness 0.15)
				)
				(justify left bottom)
			)
		)
		(property "Value" "C_10u_25V_0603"
			(at -1.42757 1.770288 0)
			(layer "F.Fab")
			(effects
				(font
					(size 0.7 0.7)
					(thickness 0.15)
				)
				(justify right bottom)
			)
		)
		(property "Datasheet" "https://product.tdk.com/en/search/capacitor/ceramic/mlcc/info?part_no=C1608X5R1E106M080AC"
			(at 0 0 180)
			(layer "F.Fab")
			(hide yes)
			(effects
				(font
					(size 1.27 1.27)
					(thickness 0.15)
				)
			)
		)
		(property "Description" "SMD Multilayer Ceramic Capacitor, 10 µF, 25 V, 0603 [1608 Metric], ± 20%, X5R, C"
			(at 0 0 180)
			(layer "F.Fab")
			(hide yes)
			(effects
				(font
					(size 1.27 1.27)
					(thickness 0.15)
				)
			)
		)
		(property "Author" "Antmicro"
			(at 347.98 106.68 0)
			(layer "F.Fab")
			(hide yes)
			(effects
				(font
					(size 1 1)
					(thickness 0.15)
				)
			)
		)
		(property "Dielectric" ""
			(at 347.98 106.68 0)
			(layer "F.Fab")
			(hide yes)
			(effects
				(font
					(size 1 1)
					(thickness 0.15)
				)
			)
		)
		(property "License" "Apache-2.0"
			(at 347.98 106.68 0)
			(layer "F.Fab")
			(hide yes)
			(effects
				(font
					(size 1 1)
					(thickness 0.15)
				)
			)
		)
		(property "MPN" "C1608X5R1E106M080AC"
			(at 347.98 106.68 0)
			(layer "F.Fab")
			(hide yes)
			(effects
				(font
					(size 1 1)
					(thickness 0.15)
				)
			)
		)
		(property "Manufacturer" "TDK"
			(at 347.98 106.68 0)
			(layer "F.Fab")
			(hide yes)
			(effects
				(font
					(size 1 1)
					(thickness 0.15)
				)
			)
		)
		(property "Val" "10u"
			(at 347.98 106.68 0)
			(layer "F.Fab")
			(hide yes)
			(effects
				(font
					(size 1 1)
					(thickness 0.15)
				)
			)
		)
		(property "Voltage" "25V"
			(at 347.98 106.68 0)
			(layer "F.Fab")
			(hide yes)
			(effects
				(font
					(size 1 1)
					(thickness 0.15)
				)
			)
		)
		(sheetname "/Connectors/")
		(sheetfile "connectors.kicad_sch")
		(attr smd)
		(fp_line
			(start -0.15 0.4)
			(end 0.15 0.4)
			(stroke
				(width 0.15)
				(type solid)
			)
			(layer "F.SilkS")
		)
		(fp_line
			(start -0.15 -0.4)
			(end 0.15 -0.4)
			(stroke
				(width 0.15)
				(type solid)
			)
			(layer "F.SilkS")
		)
		(fp_rect
			(start -1.25 -0.65)
			(end 1.25 0.65)
			(stroke
				(width 0.05)
				(type solid)
			)
			(fill no)
			(layer "F.CrtYd")
		)
		(fp_rect
			(start -0.8 -0.4)
			(end 0.8 0.4)
			(stroke
				(width 0.15)
				(type solid)
			)
			(fill no)
			(layer "F.Fab")
		)
		(pad "1" smd roundrect
			(at -0.7 0 180)
			(size 0.8 1)
			(layers "F.Cu" "F.Mask" "F.Paste")
			(roundrect_rratio 0.2)
			(net 1 "GND")
			(pintype "passive")
		)
		(pad "2" smd roundrect
			(at 0.7 0 180)
			(size 0.8 1)
			(layers "F.Cu" "F.Mask" "F.Paste")
			(roundrect_rratio 0.2)
			(net 2 "/Connectors/DC_UNFUSED")
			(pintype "passive")
		)
	)
	(footprint "antmicro-footprints:C_0402_1005Metric"
		(layer "F.Cu")
		(at 123.571 66.548 90)
		(descr "Capacitor SMD 0402")
		(tags "capacitor SMD 0402")
		(property "Reference" "C10"
			(at -1.905 1.27 90)
			(layer "F.SilkS")
			(effects
				(font
					(size 0.7 0.7)
					(thickness 0.15)
				)
				(justify left bottom)
			)
		)
		(property "Value" "C_10n_0402"
			(at -1.022927 2.155213 90)
			(layer "F.Fab")
			(effects
				(font
					(size 0.7 0.7)
					(thickness 0.15)
				)
				(justify left bottom)
			)
		)
		(property "Datasheet" "https://www.murata.com/products/productdetail?partno=GRM155R71H103KA88%23"
			(at 0 0 90)
			(layer "F.Fab")
			(hide yes)
			(effects
				(font
					(size 1.27 1.27)
					(thickness 0.15)
				)
			)
		)
		(property "Description" "SMD Multilayer Ceramic Capacitor, 10000 pF, 50 V, 0402 [1005 Metric], ± 10%, X7R, GRM Series"
			(at 0 0 90)
			(layer "F.Fab")
			(hide yes)
			(effects
				(font
					(size 1.27 1.27)
					(thickness 0.15)
				)
			)
		)
		(property "Author" "Antmicro"
			(at 190.119 -57.023 0)
			(layer "F.Fab")
			(hide yes)
			(effects
				(font
					(size 1 1)
					(thickness 0.15)
				)
			)
		)
		(property "Dielectric" "X7R"
			(at 190.119 -57.023 0)
			(layer "F.Fab")
			(hide yes)
			(effects
				(font
					(size 1 1)
					(thickness 0.15)
				)
			)
		)
		(property "License" "Apache-2.0"
			(at 190.119 -57.023 0)
			(layer "F.Fab")
			(hide yes)
			(effects
				(font
					(size 1 1)
					(thickness 0.15)
				)
			)
		)
		(property "MPN" "GRM155R71H103KA88D"
			(at 190.119 -57.023 0)
			(layer "F.Fab")
			(hide yes)
			(effects
				(font
					(size 1 1)
					(thickness 0.15)
				)
			)
		)
		(property "Manufacturer" "Murata"
			(at 190.119 -57.023 0)
			(layer "F.Fab")
			(hide yes)
			(effects
				(font
					(size 1 1)
					(thickness 0.15)
				)
			)
		)
		(property "Val" "10n"
			(at 190.119 -57.023 0)
			(layer "F.Fab")
			(hide yes)
			(effects
				(font
					(size 1 1)
					(thickness 0.15)
				)
			)
		)
		(property "Voltage" "50V"
			(at 190.119 -57.023 0)
			(layer "F.Fab")
			(hide yes)
			(effects
				(font
					(size 1 1)
					(thickness 0.15)
				)
			)
		)
		(sheetname "/Power/")
		(sheetfile "power.kicad_sch")
		(attr smd)
		(fp_rect
			(start -0.925 -0.47)
			(end 0.925 0.47)
			(stroke
				(width 0.05)
				(type default)
			)
			(fill no)
			(layer "F.CrtYd")
		)
		(fp_line
			(start 0.504 -0.25)
			(end 0.504 0.248)
			(stroke
				(width 0.15)
				(type solid)
			)
			(layer "F.Fab")
		)
		(fp_line
			(start -0.494 -0.25)
			(end 0.504 -0.25)
			(stroke
				(width 0.15)
				(type solid)
			)
			(layer "F.Fab")
		)
		(fp_line
			(start 0.504 0.248)
			(end -0.494 0.248)
			(stroke
				(width 0.15)
				(type solid)
			)
			(layer "F.Fab")
		)
		(fp_line
			(start -0.494 0.248)
			(end -0.494 -0.25)
			(stroke
				(width 0.15)
				(type solid)
			)
			(layer "F.Fab")
		)
		(pad "1" smd roundrect
			(at -0.48 0 90)
			(size 0.59 0.64)
			(layers "F.Cu" "F.Mask" "F.Paste")
			(roundrect_rratio 0.25)
			(net 1 "GND")
			(pintype "passive")
		)
		(pad "2" smd roundrect
			(at 0.48 0 90)
			(size 0.59 0.64)
			(layers "F.Cu" "F.Mask" "F.Paste")
			(roundrect_rratio 0.25)
			(net 4 "+12V")
			(pintype "passive")
		)
	)
	(footprint "antmicro-footprints:R_0402_1005Metric"
		(layer "F.Cu")
		(at 170.687 67.818)
		(descr "Resistor SMD 0402")
		(tags "resistor SMD 0402")
		(property "Reference" "R69"
			(at -3.147968 0.344135 0)
			(layer "F.SilkS")
			(effects
				(font
					(size 0.7 0.7)
					(thickness 0.15)
				)
				(justify left bottom)
			)
		)
		(property "Value" "R_100R_0402"
			(at -1.011843 1.772047 0)
			(layer "F.Fab")
			(effects
				(font
					(size 0.7 0.7)
					(thickness 0.15)
				)
				(justify left bottom)
			)
		)
		(property "Datasheet" "https://www.bourns.com/docs/product-datasheets/cr.pdf"
			(at 0 0 0)
			(layer "F.Fab")
			(hide yes)
			(effects
				(font
					(size 1.27 1.27)
					(thickness 0.15)
				)
			)
		)
		(property "Description" "SMD Chip Resistor, 100 ohm, ± 1%, 62.5 mW, 0402 [1005 Metric], Thick Film, General Purpose"
			(at 0 0 0)
			(layer "F.Fab")
			(hide yes)
			(effects
				(font
					(size 1.27 1.27)
					(thickness 0.15)
				)
			)
		)
		(property "Author" "Antmicro"
			(at 0 0 0)
			(layer "F.Fab")
			(hide yes)
			(effects
				(font
					(size 1 1)
					(thickness 0.15)
				)
			)
		)
		(property "License" "Apache-2.0"
			(at 0 0 0)
			(layer "F.Fab")
			(hide yes)
			(effects
				(font
					(size 1 1)
					(thickness 0.15)
				)
			)
		)
		(property "MPN" "CR0402-FX-1000GLF"
			(at 0 0 0)
			(layer "F.Fab")
			(hide yes)
			(effects
				(font
					(size 1 1)
					(thickness 0.15)
				)
			)
		)
		(property "Manufacturer" "Bourns"
			(at 0 0 0)
			(layer "F.Fab")
			(hide yes)
			(effects
				(font
					(size 1 1)
					(thickness 0.15)
				)
			)
		)
		(property "Tolerance" "1%"
			(at 0 0 0)
			(layer "F.Fab")
			(hide yes)
			(effects
				(font
					(size 1 1)
					(thickness 0.15)
				)
			)
		)
		(property "Val" "100R"
			(at 0 0 0)
			(layer "F.Fab")
			(hide yes)
			(effects
				(font
					(size 1 1)
					(thickness 0.15)
				)
			)
		)
		(sheetname "/Connectors/")
		(sheetfile "connectors.kicad_sch")
		(attr smd exclude_from_pos_files exclude_from_bom dnp)
		(fp_rect
			(start -0.925 -0.47)
			(end 0.925 0.47)
			(stroke
				(width 0.05)
				(type default)
			)
			(fill no)
			(layer "F.CrtYd")
		)
		(fp_rect
			(start -0.5 -0.25)
			(end 0.5 0.25)
			(stroke
				(width 0.15)
				(type solid)
			)
			(fill no)
			(layer "F.Fab")
		)
		(pad "1" smd roundrect
			(at -0.48 0)
			(size 0.59 0.64)
			(layers "F.Cu" "F.Mask" "F.Paste")
			(roundrect_rratio 0.25)
			(net 87 "/Connectors/MFP8")
			(pintype "passive")
		)
		(pad "2" smd roundrect
			(at 0.48 0)
			(size 0.59 0.64)
			(layers "F.Cu" "F.Mask" "F.Paste")
			(roundrect_rratio 0.25)
			(net 134 "Net-(U8-A_{2})")
			(pintype "passive")
		)
	)
	(footprint "antmicro-footprints:TSOT23-6"
		(layer "F.Cu")
		(at 123.626 84.178 180)
		(property "Reference" "U5"
			(at -0.508 2.032 0)
			(layer "F.SilkS")
			(effects
				(font
					(size 0.7 0.7)
					(thickness 0.15)
				)
				(justify right bottom)
			)
		)
		(property "Value" "AP62301_TSOT"
			(at 0 2.6 0)
			(layer "F.Fab")
			(effects
				(font
					(size 0.7 0.7)
					(thickness 0.15)
				)
				(justify right bottom)
			)
		)
		(property "Datasheet" "https://www.diodes.com/assets/Datasheets/AP62300_AP62301_AP62300T.pdf"
			(at 0 0 180)
			(layer "F.Fab")
			(hide yes)
			(effects
				(font
					(size 1.27 1.27)
					(thickness 0.15)
				)
			)
		)
		(property "Description" "DC-DC Switching Synchronous Buck Regulator, Adjustable, 4.2V-18Vin, 0.8V-7V/3A out, TSOT-26-6"
			(at 0 0 180)
			(layer "F.Fab")
			(hide yes)
			(effects
				(font
					(size 1.27 1.27)
					(thickness 0.15)
				)
			)
		)
		(property "Author" "Antmicro"
			(at 247.252 168.356 0)
			(layer "F.Fab")
			(hide yes)
			(effects
				(font
					(size 1 1)
					(thickness 0.15)
				)
			)
		)
		(property "License" "Apache-2.0"
			(at 247.252 168.356 0)
			(layer "F.Fab")
			(hide yes)
			(effects
				(font
					(size 1 1)
					(thickness 0.15)
				)
			)
		)
		(property "MPN" "AP62301WU-7"
			(at 247.252 168.356 0)
			(layer "F.Fab")
			(hide yes)
			(effects
				(font
					(size 1 1)
					(thickness 0.15)
				)
			)
		)
		(property "Manufacturer" "Diodes Incorporated"
			(at 247.252 168.356 0)
			(layer "F.Fab")
			(hide yes)
			(effects
				(font
					(size 1 1)
					(thickness 0.15)
				)
			)
		)
		(sheetname "/Power/")
		(sheetfile "power.kicad_sch")
		(attr smd)
		(fp_line
			(start 1 1.55)
			(end 1 1.4)
			(stroke
				(width 0.15)
				(type solid)
			)
			(layer "F.SilkS")
		)
		(fp_line
			(start 1 1.55)
			(end -1 1.55)
			(stroke
				(width 0.15)
				(type solid)
			)
			(layer "F.SilkS")
		)
		(fp_line
			(start 1 -1.497)
			(end 1 -1.375)
			(stroke
				(width 0.15)
				(type solid)
			)
			(layer "F.SilkS")
		)
		(fp_line
			(start 1 -1.497)
			(end -1 -1.5)
			(stroke
				(width 0.15)
				(type solid)
			)
			(layer "F.SilkS")
		)
		(fp_line
			(start -1 1.55)
			(end -1 1.4)
			(stroke
				(width 0.15)
				(type solid)
			)
			(layer "F.SilkS")
		)
		(fp_line
			(start -1 -1.5)
			(end -1 -1.375)
			(stroke
				(width 0.15)
				(type solid)
			)
			(layer "F.SilkS")
		)
		(fp_circle
			(center -1.44 -1.5)
			(end -1.39 -1.5)
			(stroke
				(width 0.15)
				(type solid)
			)
			(fill yes)
			(layer "F.SilkS")
		)
		(fp_rect
			(start 1.93 -1.7)
			(end -1.93 1.7)
			(stroke
				(width 0.05)
				(type solid)
			)
			(fill no)
			(layer "F.CrtYd")
		)
		(fp_line
			(start -0.45 -1.521)
			(end -0.876 -1.096)
			(stroke
				(width 0.15)
				(type solid)
			)
			(layer "F.Fab")
		)
		(fp_rect
			(start 0.875 1.528)
			(end -0.875 -1.525)
			(stroke
				(width 0.15)
				(type solid)
			)
			(fill no)
			(layer "F.Fab")
		)
		(pad "1" smd rect
			(at -1.301 -0.947 90)
			(size 0.7 1.2)
			(layers "F.Cu" "F.Mask" "F.Paste")
			(net 1 "GND")
			(pinfunction "GND")
			(pintype "power_in")
		)
		(pad "2" smd rect
			(at -1.301 0.004 90)
			(size 0.7 1.2)
			(layers "F.Cu" "F.Mask" "F.Paste")
			(net 9 "/Power/SW_1V2")
			(pinfunction "SW")
			(pintype "power_out")
		)
		(pad "3" smd rect
			(at -1.301 0.954 90)
			(size 0.7 1.2)
			(layers "F.Cu" "F.Mask" "F.Paste")
			(net 4 "+12V")
			(pinfunction "VIN")
			(pintype "power_in")
		)
		(pad "4" smd rect
			(at 1.299 0.954 90)
			(size 0.7 1.2)
			(layers "F.Cu" "F.Mask" "F.Paste")
			(net 71 "/Power/FB_1V2")
			(pinfunction "FB")
			(pintype "input")
		)
		(pad "5" smd rect
			(at 1.299 0.004 90)
			(size 0.7 1.2)
			(layers "F.Cu" "F.Mask" "F.Paste")
			(net 68 "/Power/EN_1V2")
			(pinfunction "EN")
			(pintype "input")
		)
		(pad "6" smd rect
			(at 1.299 -0.947 90)
			(size 0.7 1.2)
			(layers "F.Cu" "F.Mask" "F.Paste")
			(net 8 "Net-(U5-BST)")
			(pinfunction "BST")
			(pintype "output")
		)
	)
	(footprint "antmicro-footprints:TP_SMD_0.75mm"
		(layer "F.Cu")
		(at 158.496 97.89)
		(property "Reference" "TP1"
			(at -0.6096 -0.5588 180)
			(layer "F.SilkS")
			(hide yes)
			(effects
				(font
					(size 0.7 0.7)
					(thickness 0.15)
				)
				(justify left bottom)
			)
		)
		(property "Value" "TP_0.75mm_SMD"
			(at 0 1.2 0)
			(layer "F.Fab")
			(effects
				(font
					(size 0.7 0.7)
					(thickness 0.15)
				)
				(justify left bottom)
			)
		)
		(property "Description" "SMT test point"
			(at 0 0 0)
			(layer "F.Fab")
			(hide yes)
			(effects
				(font
					(size 1.27 1.27)
					(thickness 0.15)
				)
			)
		)
		(property "Author" "Antmicro"
			(at 0 0 0)
			(layer "F.Fab")
			(hide yes)
			(effects
				(font
					(size 1 1)
					(thickness 0.15)
				)
			)
		)
		(property "License" "Apache-2.0"
			(at 0 0 0)
			(layer "F.Fab")
			(hide yes)
			(effects
				(font
					(size 1 1)
					(thickness 0.15)
				)
			)
		)
		(property "MPN" ""
			(at 0 0 0)
			(layer "F.Fab")
			(hide yes)
			(effects
				(font
					(size 1 1)
					(thickness 0.15)
				)
			)
		)
		(property "Manufacturer" ""
			(at 0 0 0)
			(layer "F.Fab")
			(hide yes)
			(effects
				(font
					(size 1 1)
					(thickness 0.15)
				)
			)
		)
		(sheetname "/Connectors/")
		(sheetfile "connectors.kicad_sch")
		(fp_circle
			(center 0 0)
			(end 0.475 0)
			(stroke
				(width 0.05)
				(type default)
			)
			(fill no)
			(layer "F.CrtYd")
		)
		(pad "1" smd circle
			(at 0 0)
			(size 0.75 0.75)
			(layers "F.Cu" "F.Mask")
			(net 84 "/Connectors/MFP4")
			(pinfunction "1")
			(pintype "passive")
		)
	)
	(footprint "antmicro-footprints:LED_0603_1608Metric_G"
		(layer "F.Cu")
		(at 149.352 96.1 -90)
		(descr "LED SMD 0603 Green")
		(tags "LED SMD 0603 Green")
		(property "Reference" "D17"
			(at -3.616666 30.935333 0)
			(layer "F.SilkS")
			(effects
				(font
					(size 0.7 0.7)
					(thickness 0.15)
				)
				(justify right bottom)
			)
		)
		(property "Value" "LED_G_0603_LTST-C190GKT"
			(at -0.001 1.599 90)
			(layer "F.Fab")
			(effects
				(font
					(size 0.7 0.7)
					(thickness 0.15)
				)
				(justify right bottom)
			)
		)
		(property "Datasheet" "https://media.digikey.com/pdf/Data%20Sheets/Lite-On%20PDFs/LTST-C190GKT.pdf"
			(at 0 0 270)
			(layer "F.Fab")
			(hide yes)
			(effects
				(font
					(size 1.27 1.27)
					(thickness 0.15)
				)
			)
		)
		(property "Description" "LED, Green, SMD, 0603, 20 mA, 2.1 V, 569 nm"
			(at 0 0 270)
			(layer "F.Fab")
			(hide yes)
			(effects
				(font
					(size 1.27 1.27)
					(thickness 0.15)
				)
			)
		)
		(property "Author" "Antmicro"
			(at 53.252 245.452 0)
			(layer "F.Fab")
			(hide yes)
			(effects
				(font
					(size 1 1)
					(thickness 0.15)
				)
			)
		)
		(property "Color" "Green"
			(at 53.252 245.452 0)
			(layer "F.Fab")
			(hide yes)
			(effects
				(font
					(size 1 1)
					(thickness 0.15)
				)
			)
		)
		(property "License" "Apache-2.0"
			(at 53.252 245.452 0)
			(layer "F.Fab")
			(hide yes)
			(effects
				(font
					(size 1 1)
					(thickness 0.15)
				)
			)
		)
		(property "MPN" "LTST-C190GKT"
			(at 53.252 245.452 0)
			(layer "F.Fab")
			(hide yes)
			(effects
				(font
					(size 1 1)
					(thickness 0.15)
				)
			)
		)
		(property "Manufacturer" "Lite-On"
			(at 53.252 245.452 0)
			(layer "F.Fab")
			(hide yes)
			(effects
				(font
					(size 1 1)
					(thickness 0.15)
				)
			)
		)
		(property "VSD_class" "LED"
			(at 53.252 245.452 0)
			(layer "F.Fab")
			(hide yes)
			(effects
				(font
					(size 1 1)
					(thickness 0.15)
				)
			)
		)
		(sheetname "/Power/")
		(sheetfile "power.kicad_sch")
		(attr smd)
		(fp_line
			(start 0.22 0.35)
			(end -0.22 0.35)
			(stroke
				(width 0.15)
				(type solid)
			)
			(layer "F.SilkS")
		)
		(fp_line
			(start -0.094672 0.201008)
			(end -0.094672 -0.198992)
			(stroke
				(width 0.1)
				(type solid)
			)
			(layer "F.SilkS")
		)
		(fp_line
			(start 0.105328 0.201008)
			(end -0.094672 0.001008)
			(stroke
				(width 0.1)
				(type solid)
			)
			(layer "F.SilkS")
		)
		(fp_line
			(start 0.105328 0.201008)
			(end 0.105328 -0.198992)
			(stroke
				(width 0.1)
				(type solid)
			)
			(layer "F.SilkS")
		)
		(fp_line
			(start -0.094672 0.001008)
			(end -0.24 0.001008)
			(stroke
				(width 0.1)
				(type solid)
			)
			(layer "F.SilkS")
		)
		(fp_line
			(start -0.094672 0.001008)
			(end 0.105328 -0.198992)
			(stroke
				(width 0.1)
				(type solid)
			)
			(layer "F.SilkS")
		)
		(fp_line
			(start 0.105328 0.001008)
			(end 0.24 0.001)
			(stroke
				(width 0.1)
				(type solid)
			)
			(layer "F.SilkS")
		)
		(fp_line
			(start -1.18 -0.319)
			(end -1.18 0.321)
			(stroke
				(width 0.15)
				(type solid)
			)
			(layer "F.SilkS")
		)
		(fp_line
			(start 0.22 -0.35)
			(end -0.22 -0.35)
			(stroke
				(width 0.15)
				(type solid)
			)
			(layer "F.SilkS")
		)
		(fp_rect
			(start 1.25 0.65)
			(end -1.25 -0.65)
			(stroke
				(width 0.05)
				(type solid)
			)
			(fill no)
			(layer "F.CrtYd")
		)
		(fp_line
			(start -0.199 0.2)
			(end -0.199 0.1)
			(stroke
				(width 0.15)
				(type solid)
			)
			(layer "F.Fab")
		)
		(fp_line
			(start 0.201 0.2)
			(end 0.201 0)
			(stroke
				(width 0.15)
				(type solid)
			)
			(layer "F.Fab")
		)
		(fp_line
			(start -0.199 0)
			(end -0.597 0)
			(stroke
				(width 0.15)
				(type solid)
			)
			(layer "F.Fab")
		)
		(fp_line
			(start -0.101 0)
			(end 0.201 0.2)
			(stroke
				(width 0.15)
				(type solid)
			)
			(layer "F.Fab")
		)
		(fp_line
			(start 0.201 0)
			(end 0.201 -0.202)
			(stroke
				(width 0.15)
				(type solid)
			)
			(layer "F.Fab")
		)
		(fp_line
			(start 0.599 0)
			(end 0.201 0)
			(stroke
				(width 0.15)
				(type solid)
			)
			(layer "F.Fab")
		)
		(fp_line
			(start -0.199 -0.202)
			(end -0.199 0.1)
			(stroke
				(width 0.15)
				(type solid)
			)
			(layer "F.Fab")
		)
		(fp_line
			(start 0.201 -0.202)
			(end -0.101 0)
			(stroke
				(width 0.15)
				(type solid)
			)
			(layer "F.Fab")
		)
		(fp_rect
			(start 0.848 0.4)
			(end -0.85 -0.402)
			(stroke
				(width 0.15)
				(type solid)
			)
			(fill no)
			(layer "F.Fab")
		)
		(pad "1" smd roundrect
			(at -0.7 0 90)
			(size 0.8 1)
			(layers "F.Cu" "F.Mask" "F.Paste")
			(roundrect_rratio 0.2)
			(net 141 "Net-(D17-C)")
			(pinfunction "C")
			(pintype "passive")
		)
		(pad "2" smd roundrect
			(at 0.7 0 90)
			(size 0.8 1)
			(layers "F.Cu" "F.Mask" "F.Paste")
			(roundrect_rratio 0.2)
			(net 4 "+12V")
			(pinfunction "A")
			(pintype "passive")
		)
	)
	(footprint "antmicro-footprints:R_0402_1005Metric"
		(layer "F.Cu")
		(at 184.077 52.7328 90)
		(descr "Resistor SMD 0402")
		(tags "resistor SMD 0402")
		(property "Reference" "R33"
			(at -1.27 -0.761 90)
			(layer "F.SilkS")
			(effects
				(font
					(size 0.7 0.7)
					(thickness 0.15)
				)
				(justify left bottom)
			)
		)
		(property "Value" "R_10k_0402"
			(at -1.011843 1.772047 90)
			(layer "F.Fab")
			(effects
				(font
					(size 0.7 0.7)
					(thickness 0.15)
				)
				(justify left bottom)
			)
		)
		(property "Datasheet" "https://www.bourns.com/docs/product-datasheets/cr.pdf"
			(at 0 0 90)
			(layer "F.Fab")
			(hide yes)
			(effects
				(font
					(size 1.27 1.27)
					(thickness 0.15)
				)
			)
		)
		(property "Description" "SMD Chip Resistor, 10 kohm, ± 1%, 62.5 mW, 0402 [1005 Metric], Thick Film, General Purpose"
			(at 0 0 90)
			(layer "F.Fab")
			(hide yes)
			(effects
				(font
					(size 1.27 1.27)
					(thickness 0.15)
				)
			)
		)
		(property "Author" "Antmicro"
			(at 236.8098 -131.3442 0)
			(layer "F.Fab")
			(hide yes)
			(effects
				(font
					(size 1 1)
					(thickness 0.15)
				)
			)
		)
		(property "License" "Apache-2.0"
			(at 236.8098 -131.3442 0)
			(layer "F.Fab")
			(hide yes)
			(effects
				(font
					(size 1 1)
					(thickness 0.15)
				)
			)
		)
		(property "MPN" "CR0402-FX-1002GLF"
			(at 236.8098 -131.3442 0)
			(layer "F.Fab")
			(hide yes)
			(effects
				(font
					(size 1 1)
					(thickness 0.15)
				)
			)
		)
		(property "Manufacturer" "Bourns"
			(at 236.8098 -131.3442 0)
			(layer "F.Fab")
			(hide yes)
			(effects
				(font
					(size 1 1)
					(thickness 0.15)
				)
			)
		)
		(property "Tolerance" "1%"
			(at 236.8098 -131.3442 0)
			(layer "F.Fab")
			(hide yes)
			(effects
				(font
					(size 1 1)
					(thickness 0.15)
				)
			)
		)
		(property "Val" "10k"
			(at 236.8098 -131.3442 0)
			(layer "F.Fab")
			(hide yes)
			(effects
				(font
					(size 1 1)
					(thickness 0.15)
				)
			)
		)
		(sheetname "/Power/")
		(sheetfile "power.kicad_sch")
		(attr smd)
		(fp_rect
			(start -0.925 -0.47)
			(end 0.925 0.47)
			(stroke
				(width 0.05)
				(type default)
			)
			(fill no)
			(layer "F.CrtYd")
		)
		(fp_rect
			(start -0.5 -0.25)
			(end 0.5 0.25)
			(stroke
				(width 0.15)
				(type solid)
			)
			(fill no)
			(layer "F.Fab")
		)
		(pad "1" smd roundrect
			(at -0.48 0 90)
			(size 0.59 0.64)
			(layers "F.Cu" "F.Mask" "F.Paste")
			(roundrect_rratio 0.25)
			(net 63 "/Power/FFC_5V_EN")
			(pintype "passive")
		)
		(pad "2" smd roundrect
			(at 0.48 0 90)
			(size 0.59 0.64)
			(layers "F.Cu" "F.Mask" "F.Paste")
			(roundrect_rratio 0.25)
			(net 113 "/Connectors/FFC_5V")
			(pintype "passive")
		)
	)
	(footprint "antmicro-footprints:LED_0603_1608Metric_G"
		(layer "F.Cu")
		(at 155.448 96.11 -90)
		(descr "LED SMD 0603 Green")
		(tags "LED SMD 0603 Green")
		(property "Reference" "D13"
			(at 0.062223 37.031333 0)
			(layer "F.SilkS")
			(effects
				(font
					(size 0.7 0.7)
					(thickness 0.15)
				)
				(justify right bottom)
			)
		)
		(property "Value" "LED_G_0603_LTST-C190GKT"
			(at -0.001 1.599 90)
			(layer "F.Fab")
			(effects
				(font
					(size 0.7 0.7)
					(thickness 0.15)
				)
				(justify right bottom)
			)
		)
		(property "Datasheet" "https://media.digikey.com/pdf/Data%20Sheets/Lite-On%20PDFs/LTST-C190GKT.pdf"
			(at 0 0 270)
			(layer "F.Fab")
			(hide yes)
			(effects
				(font
					(size 1.27 1.27)
					(thickness 0.15)
				)
			)
		)
		(property "Description" "LED, Green, SMD, 0603, 20 mA, 2.1 V, 569 nm"
			(at 0 0 270)
			(layer "F.Fab")
			(hide yes)
			(effects
				(font
					(size 1.27 1.27)
					(thickness 0.15)
				)
			)
		)
		(property "Author" "Antmicro"
			(at 59.338 251.558 0)
			(layer "F.Fab")
			(hide yes)
			(effects
				(font
					(size 1 1)
					(thickness 0.15)
				)
			)
		)
		(property "Color" "Green"
			(at 59.338 251.558 0)
			(layer "F.Fab")
			(hide yes)
			(effects
				(font
					(size 1 1)
					(thickness 0.15)
				)
			)
		)
		(property "License" "Apache-2.0"
			(at 59.338 251.558 0)
			(layer "F.Fab")
			(hide yes)
			(effects
				(font
					(size 1 1)
					(thickness 0.15)
				)
			)
		)
		(property "MPN" "LTST-C190GKT"
			(at 59.338 251.558 0)
			(layer "F.Fab")
			(hide yes)
			(effects
				(font
					(size 1 1)
					(thickness 0.15)
				)
			)
		)
		(property "Manufacturer" "Lite-On"
			(at 59.338 251.558 0)
			(layer "F.Fab")
			(hide yes)
			(effects
				(font
					(size 1 1)
					(thickness 0.15)
				)
			)
		)
		(property "VSD_class" "LED"
			(at 59.338 251.558 0)
			(layer "F.Fab")
			(hide yes)
			(effects
				(font
					(size 1 1)
					(thickness 0.15)
				)
			)
		)
		(sheetname "/Connectors/")
		(sheetfile "connectors.kicad_sch")
		(attr smd)
		(fp_line
			(start 0.22 0.35)
			(end -0.22 0.35)
			(stroke
				(width 0.15)
				(type solid)
			)
			(layer "F.SilkS")
		)
		(fp_line
			(start -0.094672 0.201008)
			(end -0.094672 -0.198992)
			(stroke
				(width 0.1)
				(type solid)
			)
			(layer "F.SilkS")
		)
		(fp_line
			(start 0.105328 0.201008)
			(end -0.094672 0.001008)
			(stroke
				(width 0.1)
				(type solid)
			)
			(layer "F.SilkS")
		)
		(fp_line
			(start 0.105328 0.201008)
			(end 0.105328 -0.198992)
			(stroke
				(width 0.1)
				(type solid)
			)
			(layer "F.SilkS")
		)
		(fp_line
			(start -0.094672 0.001008)
			(end -0.24 0.001008)
			(stroke
				(width 0.1)
				(type solid)
			)
			(layer "F.SilkS")
		)
		(fp_line
			(start -0.094672 0.001008)
			(end 0.105328 -0.198992)
			(stroke
				(width 0.1)
				(type solid)
			)
			(layer "F.SilkS")
		)
		(fp_line
			(start 0.105328 0.001008)
			(end 0.24 0.001)
			(stroke
				(width 0.1)
				(type solid)
			)
			(layer "F.SilkS")
		)
		(fp_line
			(start -1.18 -0.319)
			(end -1.18 0.321)
			(stroke
				(width 0.15)
				(type solid)
			)
			(layer "F.SilkS")
		)
		(fp_line
			(start 0.22 -0.35)
			(end -0.22 -0.35)
			(stroke
				(width 0.15)
				(type solid)
			)
			(layer "F.SilkS")
		)
		(fp_rect
			(start 1.25 0.65)
			(end -1.25 -0.65)
			(stroke
				(width 0.05)
				(type solid)
			)
			(fill no)
			(layer "F.CrtYd")
		)
		(fp_line
			(start -0.199 0.2)
			(end -0.199 0.1)
			(stroke
				(width 0.15)
				(type solid)
			)
			(layer "F.Fab")
		)
		(fp_line
			(start 0.201 0.2)
			(end 0.201 0)
			(stroke
				(width 0.15)
				(type solid)
			)
			(layer "F.Fab")
		)
		(fp_line
			(start -0.199 0)
			(end -0.597 0)
			(stroke
				(width 0.15)
				(type solid)
			)
			(layer "F.Fab")
		)
		(fp_line
			(start -0.101 0)
			(end 0.201 0.2)
			(stroke
				(width 0.15)
				(type solid)
			)
			(layer "F.Fab")
		)
		(fp_line
			(start 0.201 0)
			(end 0.201 -0.202)
			(stroke
				(width 0.15)
				(type solid)
			)
			(layer "F.Fab")
		)
		(fp_line
			(start 0.599 0)
			(end 0.201 0)
			(stroke
				(width 0.15)
				(type solid)
			)
			(layer "F.Fab")
		)
		(fp_line
			(start -0.199 -0.202)
			(end -0.199 0.1)
			(stroke
				(width 0.15)
				(type solid)
			)
			(layer "F.Fab")
		)
		(fp_line
			(start 0.201 -0.202)
			(end -0.101 0)
			(stroke
				(width 0.15)
				(type solid)
			)
			(layer "F.Fab")
		)
		(fp_rect
			(start 0.848 0.4)
			(end -0.85 -0.402)
			(stroke
				(width 0.15)
				(type solid)
			)
			(fill no)
			(layer "F.Fab")
		)
		(pad "1" smd roundrect
			(at -0.7 0 90)
			(size 0.8 1)
			(layers "F.Cu" "F.Mask" "F.Paste")
			(roundrect_rratio 0.2)
			(net 109 "Net-(D13-C)")
			(pinfunction "C")
			(pintype "passive")
		)
		(pad "2" smd roundrect
			(at 0.7 0 90)
			(size 0.8 1)
			(layers "F.Cu" "F.Mask" "F.Paste")
			(roundrect_rratio 0.2)
			(net 113 "/Connectors/FFC_5V")
			(pinfunction "A")
			(pintype "passive")
		)
	)
	(footprint "antmicro-footprints:R_0402_1005Metric"
		(layer "F.Cu")
		(at 143.692 73.66 -90)
		(descr "Resistor SMD 0402")
		(tags "resistor SMD 0402")
		(property "Reference" "R54"
			(at -3.0226 1.325 270)
			(layer "F.SilkS")
			(effects
				(font
					(size 0.7 0.7)
					(thickness 0.15)
				)
				(justify right bottom)
			)
		)
		(property "Value" "R_402R_0402"
			(at -1.011843 1.772047 90)
			(layer "F.Fab")
			(effects
				(font
					(size 0.7 0.7)
					(thickness 0.15)
				)
				(justify right bottom)
			)
		)
		(property "Datasheet" "https://www.mouser.com/datasheet/2/54/cr-1858361.pdf"
			(at 0 0 270)
			(layer "F.Fab")
			(hide yes)
			(effects
				(font
					(size 1.27 1.27)
					(thickness 0.15)
				)
			)
		)
		(property "Description" "SMD Chip Resistor, 402 ohm, ± 1%, 63 mW, 0402 [1005 Metric], Thick Film, General Purpose"
			(at 0 0 270)
			(layer "F.Fab")
			(hide yes)
			(effects
				(font
					(size 1.27 1.27)
					(thickness 0.15)
				)
			)
		)
		(property "Author" "Antmicro"
			(at 70.032 217.352 0)
			(layer "F.Fab")
			(hide yes)
			(effects
				(font
					(size 1 1)
					(thickness 0.15)
				)
			)
		)
		(property "License" "Apache-2.0"
			(at 70.032 217.352 0)
			(layer "F.Fab")
			(hide yes)
			(effects
				(font
					(size 1 1)
					(thickness 0.15)
				)
			)
		)
		(property "MPN" "CR0402-FX-4020GLF"
			(at 70.032 217.352 0)
			(layer "F.Fab")
			(hide yes)
			(effects
				(font
					(size 1 1)
					(thickness 0.15)
				)
			)
		)
		(property "Manufacturer" "Bourns"
			(at 70.032 217.352 0)
			(layer "F.Fab")
			(hide yes)
			(effects
				(font
					(size 1 1)
					(thickness 0.15)
				)
			)
		)
		(property "Tolerance" "1%"
			(at 70.032 217.352 0)
			(layer "F.Fab")
			(hide yes)
			(effects
				(font
					(size 1 1)
					(thickness 0.15)
				)
			)
		)
		(property "Val" "402R"
			(at 70.032 217.352 0)
			(layer "F.Fab")
			(hide yes)
			(effects
				(font
					(size 1 1)
					(thickness 0.15)
				)
			)
		)
		(sheetname "/Deserializer/")
		(sheetfile "deserializer.kicad_sch")
		(attr smd)
		(fp_rect
			(start -0.925 -0.47)
			(end 0.925 0.47)
			(stroke
				(width 0.05)
				(type default)
			)
			(fill no)
			(layer "F.CrtYd")
		)
		(fp_rect
			(start -0.5 -0.25)
			(end 0.5 0.25)
			(stroke
				(width 0.15)
				(type solid)
			)
			(fill no)
			(layer "F.Fab")
		)
		(pad "1" smd roundrect
			(at -0.48 0 270)
			(size 0.59 0.64)
			(layers "F.Cu" "F.Mask" "F.Paste")
			(roundrect_rratio 0.25)
			(net 1 "GND")
			(pintype "passive")
		)
		(pad "2" smd roundrect
			(at 0.48 0 270)
			(size 0.59 0.64)
			(layers "F.Cu" "F.Mask" "F.Paste")
			(roundrect_rratio 0.25)
			(net 78 "/Deserializer/XRES")
			(pintype "passive")
		)
	)
	(footprint "antmicro-footprints:C_0402_1005Metric"
		(layer "F.Cu")
		(at 139.827 76.581 135)
		(descr "Capacitor SMD 0402")
		(tags "capacitor SMD 0402")
		(property "Reference" "C27"
			(at 6.272037 -0.486489 315)
			(unlocked yes)
			(layer "F.SilkS")
			(effects
				(font
					(size 0.7 0.7)
					(thickness 0.15)
				)
				(justify left bottom)
			)
		)
		(property "Value" "C_100n_0402"
			(at -21.596927 15.617213 135)
			(layer "F.Fab")
			(effects
				(font
					(size 0.7 0.7)
					(thickness 0.15)
				)
				(justify left bottom)
			)
		)
		(property "Datasheet" "https://www.murata.com/products/productdetail?partno=GRM155R61H104KE14%23"
			(at 0 0 135)
			(layer "F.Fab")
			(hide yes)
			(effects
				(font
					(size 1.27 1.27)
					(thickness 0.15)
				)
			)
		)
		(property "Description" "SMD Multilayer Ceramic Capacitor, 0.1 µF, 50 V, 0402 [1005 Metric], ± 10%, X5R, GRM Series"
			(at 0 0 135)
			(layer "F.Fab")
			(hide yes)
			(effects
				(font
					(size 1.27 1.27)
					(thickness 0.15)
				)
			)
		)
		(property "Author" "Antmicro"
			(at 292.850564 31.859325 0)
			(layer "F.Fab")
			(hide yes)
			(effects
				(font
					(size 1 1)
					(thickness 0.15)
				)
			)
		)
		(property "Dielectric" "X5R"
			(at 292.850564 31.859325 0)
			(layer "F.Fab")
			(hide yes)
			(effects
				(font
					(size 1 1)
					(thickness 0.15)
				)
			)
		)
		(property "License" "Apache-2.0"
			(at 292.850564 31.859325 0)
			(layer "F.Fab")
			(hide yes)
			(effects
				(font
					(size 1 1)
					(thickness 0.15)
				)
			)
		)
		(property "MPN" "GRM155R61H104KE14D"
			(at 292.850564 31.859325 0)
			(layer "F.Fab")
			(hide yes)
			(effects
				(font
					(size 1 1)
					(thickness 0.15)
				)
			)
		)
		(property "Manufacturer" "Murata"
			(at 292.850564 31.859325 0)
			(layer "F.Fab")
			(hide yes)
			(effects
				(font
					(size 1 1)
					(thickness 0.15)
				)
			)
		)
		(property "Val" "100n"
			(at 292.850564 31.859325 0)
			(layer "F.Fab")
			(hide yes)
			(effects
				(font
					(size 1 1)
					(thickness 0.15)
				)
			)
		)
		(property "Voltage" "50V"
			(at 292.850564 31.859325 0)
			(layer "F.Fab")
			(hide yes)
			(effects
				(font
					(size 1 1)
					(thickness 0.15)
				)
			)
		)
		(sheetname "/Deserializer/")
		(sheetfile "deserializer.kicad_sch")
		(attr smd)
		(fp_poly
			(pts
				(xy -0.925 -0.47) (xy 0.925 -0.47) (xy 0.925 0.47) (xy -0.925 0.47)
			)
			(stroke
				(width 0.05)
				(type default)
			)
			(fill no)
			(layer "F.CrtYd")
		)
		(fp_line
			(start 0.504 -0.25)
			(end 0.504 0.248)
			(stroke
				(width 0.15)
				(type solid)
			)
			(layer "F.Fab")
		)
		(fp_line
			(start 0.504 0.248)
			(end -0.494 0.248)
			(stroke
				(width 0.15)
				(type solid)
			)
			(layer "F.Fab")
		)
		(fp_line
			(start -0.494 -0.25)
			(end 0.504 -0.25)
			(stroke
				(width 0.15)
				(type solid)
			)
			(layer "F.Fab")
		)
		(fp_line
			(start -0.494 0.248)
			(end -0.494 -0.25)
			(stroke
				(width 0.15)
				(type solid)
			)
			(layer "F.Fab")
		)
		(pad "1" smd roundrect
			(at -0.48 0 135)
			(size 0.59 0.64)
			(layers "F.Cu" "F.Mask" "F.Paste")
			(roundrect_rratio 0.25)
			(net 13 "/Deserializer/SIOA_P")
			(pintype "passive")
		)
		(pad "2" smd roundrect
			(at 0.48 0 135)
			(size 0.59 0.64)
			(layers "F.Cu" "F.Mask" "F.Paste")
			(roundrect_rratio 0.25)
			(net 114 "/Connectors/PoCA")
			(pintype "passive")
		)
	)
	(footprint "antmicro-footprints:R_0402_1005Metric"
		(layer "F.Cu")
		(at 137.313 97.142 90)
		(descr "Resistor SMD 0402")
		(tags "resistor SMD 0402")
		(property "Reference" "R36"
			(at -1.41 -0.661 90)
			(layer "F.SilkS")
			(effects
				(font
					(size 0.7 0.7)
					(thickness 0.15)
				)
				(justify left bottom)
			)
		)
		(property "Value" "R_10k_0402"
			(at -1.011843 1.772047 90)
			(layer "F.Fab")
			(effects
				(font
					(size 0.7 0.7)
					(thickness 0.15)
				)
				(justify left bottom)
			)
		)
		(property "Datasheet" "https://www.bourns.com/docs/product-datasheets/cr.pdf"
			(at 0 0 90)
			(layer "F.Fab")
			(hide yes)
			(effects
				(font
					(size 1.27 1.27)
					(thickness 0.15)
				)
			)
		)
		(property "Description" "SMD Chip Resistor, 10 kohm, ± 1%, 62.5 mW, 0402 [1005 Metric], Thick Film, General Purpose"
			(at 0 0 90)
			(layer "F.Fab")
			(hide yes)
			(effects
				(font
					(size 1.27 1.27)
					(thickness 0.15)
				)
			)
		)
		(property "Author" "Antmicro"
			(at 234.455 -40.171 0)
			(layer "F.Fab")
			(hide yes)
			(effects
				(font
					(size 1 1)
					(thickness 0.15)
				)
			)
		)
		(property "License" "Apache-2.0"
			(at 234.455 -40.171 0)
			(layer "F.Fab")
			(hide yes)
			(effects
				(font
					(size 1 1)
					(thickness 0.15)
				)
			)
		)
		(property "MPN" "CR0402-FX-1002GLF"
			(at 234.455 -40.171 0)
			(layer "F.Fab")
			(hide yes)
			(effects
				(font
					(size 1 1)
					(thickness 0.15)
				)
			)
		)
		(property "Manufacturer" "Bourns"
			(at 234.455 -40.171 0)
			(layer "F.Fab")
			(hide yes)
			(effects
				(font
					(size 1 1)
					(thickness 0.15)
				)
			)
		)
		(property "Tolerance" "1%"
			(at 234.455 -40.171 0)
			(layer "F.Fab")
			(hide yes)
			(effects
				(font
					(size 1 1)
					(thickness 0.15)
				)
			)
		)
		(property "Val" "10k"
			(at 234.455 -40.171 0)
			(layer "F.Fab")
			(hide yes)
			(effects
				(font
					(size 1 1)
					(thickness 0.15)
				)
			)
		)
		(sheetname "/Power/")
		(sheetfile "power.kicad_sch")
		(attr smd)
		(fp_rect
			(start -0.925 -0.47)
			(end 0.925 0.47)
			(stroke
				(width 0.05)
				(type default)
			)
			(fill no)
			(layer "F.CrtYd")
		)
		(fp_rect
			(start -0.5 -0.25)
			(end 0.5 0.25)
			(stroke
				(width 0.15)
				(type solid)
			)
			(fill no)
			(layer "F.Fab")
		)
		(pad "1" smd roundrect
			(at -0.48 0 90)
			(size 0.59 0.64)
			(layers "F.Cu" "F.Mask" "F.Paste")
			(roundrect_rratio 0.25)
			(net 1 "GND")
			(pintype "passive")
		)
		(pad "2" smd roundrect
			(at 0.48 0 90)
			(size 0.59 0.64)
			(layers "F.Cu" "F.Mask" "F.Paste")
			(roundrect_rratio 0.25)
			(net 70 "/Power/FB_1V8")
			(pintype "passive")
		)
	)
	(footprint "antmicro-footprints:R_0402_1005Metric"
		(layer "F.Cu")
		(at 139.065 74.295 135)
		(descr "Resistor SMD 0402")
		(tags "resistor SMD 0402")
		(property "Reference" "R43"
			(at 6.164274 -0.378726 315)
			(unlocked yes)
			(layer "F.SilkS")
			(effects
				(font
					(size 0.7 0.7)
					(thickness 0.15)
				)
				(justify left bottom)
			)
		)
		(property "Value" "R_49R9_0402"
			(at -0.962843 2.788047 135)
			(layer "F.Fab")
			(effects
				(font
					(size 0.7 0.7)
					(thickness 0.15)
				)
				(justify left bottom)
			)
		)
		(property "Datasheet" "https://www.bourns.com/docs/product-datasheets/cr.pdf"
			(at 0 0 135)
			(layer "F.Fab")
			(hide yes)
			(effects
				(font
					(size 1.27 1.27)
					(thickness 0.15)
				)
			)
		)
		(property "Description" "SMD Chip Resistor, 49.9 ohm, ± 1%, 62.5 mW, 0402 [1005 Metric], Thick Film, General Purpose"
			(at 0 0 135)
			(layer "F.Fab")
			(hide yes)
			(effects
				(font
					(size 1.27 1.27)
					(thickness 0.15)
				)
			)
		)
		(property "Author" "Antmicro"
			(at 289.933303 28.495694 0)
			(layer "F.Fab")
			(hide yes)
			(effects
				(font
					(size 1 1)
					(thickness 0.15)
				)
			)
		)
		(property "License" "Apache-2.0"
			(at 289.933303 28.495694 0)
			(layer "F.Fab")
			(hide yes)
			(effects
				(font
					(size 1 1)
					(thickness 0.15)
				)
			)
		)
		(property "MPN" "CR0402-FX-49R9GLF"
			(at 289.933303 28.495694 0)
			(layer "F.Fab")
			(hide yes)
			(effects
				(font
					(size 1 1)
					(thickness 0.15)
				)
			)
		)
		(property "Manufacturer" "Bourns"
			(at 289.933303 28.495694 0)
			(layer "F.Fab")
			(hide yes)
			(effects
				(font
					(size 1 1)
					(thickness 0.15)
				)
			)
		)
		(property "Tolerance" "1%"
			(at 289.933303 28.495694 0)
			(layer "F.Fab")
			(hide yes)
			(effects
				(font
					(size 1 1)
					(thickness 0.15)
				)
			)
		)
		(property "Val" "49R9"
			(at 289.933303 28.495694 0)
			(layer "F.Fab")
			(hide yes)
			(effects
				(font
					(size 1 1)
					(thickness 0.15)
				)
			)
		)
		(sheetname "/Deserializer/")
		(sheetfile "deserializer.kicad_sch")
		(attr smd)
		(fp_poly
			(pts
				(xy -0.925 -0.47) (xy 0.925 -0.47) (xy 0.925 0.47) (xy -0.925 0.47)
			)
			(stroke
				(width 0.05)
				(type default)
			)
			(fill no)
			(layer "F.CrtYd")
		)
		(fp_poly
			(pts
				(xy -0.5 -0.25) (xy 0.5 -0.25) (xy 0.5 0.25) (xy -0.5 0.25)
			)
			(stroke
				(width 0.15)
				(type solid)
			)
			(fill no)
			(layer "F.Fab")
		)
		(pad "1" smd roundrect
			(at -0.48 0 135)
			(size 0.59 0.64)
			(layers "F.Cu" "F.Mask" "F.Paste")
			(roundrect_rratio 0.25)
			(net 19 "Net-(C32-Pad2)")
			(pintype "passive")
		)
		(pad "2" smd roundrect
			(at 0.48 0 135)
			(size 0.59 0.64)
			(layers "F.Cu" "F.Mask" "F.Paste")
			(roundrect_rratio 0.25)
			(net 1 "GND")
			(pintype "passive")
		)
	)
	(footprint "antmicro-footprints:L_0806_2016Metric"
		(layer "F.Cu")
		(at 123.88 87.226)
		(property "Reference" "L19"
			(at -1.524 2.032 0)
			(layer "F.SilkS")
			(effects
				(font
					(size 0.7 0.7)
					(thickness 0.15)
				)
				(justify left bottom)
			)
		)
		(property "Value" "L_1u_2.6A_0806"
			(at 0 2 0)
			(layer "F.Fab")
			(effects
				(font
					(size 0.7 0.7)
					(thickness 0.15)
				)
				(justify left bottom)
			)
		)
		(property "Datasheet" "https://www.bourns.com/docs/Product-Datasheets/SRP2010.pdf"
			(at 0 0 0)
			(layer "F.Fab")
			(hide yes)
			(effects
				(font
					(size 1.27 1.27)
					(thickness 0.15)
				)
			)
		)
		(property "Description" "Wirewound Inductor, 1 µH, 0.072 ohm, 2.6 A, SRP2010"
			(at 0 0 0)
			(layer "F.Fab")
			(hide yes)
			(effects
				(font
					(size 1.27 1.27)
					(thickness 0.15)
				)
			)
		)
		(property "Author" "Antmicro"
			(at 0 0 0)
			(layer "F.Fab")
			(hide yes)
			(effects
				(font
					(size 1 1)
					(thickness 0.15)
				)
			)
		)
		(property "IMax" "2.6 A"
			(at 0 0 0)
			(layer "F.Fab")
			(hide yes)
			(effects
				(font
					(size 1 1)
					(thickness 0.15)
				)
			)
		)
		(property "ISat" "2.9 A"
			(at 0 0 0)
			(layer "F.Fab")
			(hide yes)
			(effects
				(font
					(size 1 1)
					(thickness 0.15)
				)
			)
		)
		(property "License" "Apache-2.0"
			(at 0 0 0)
			(layer "F.Fab")
			(hide yes)
			(effects
				(font
					(size 1 1)
					(thickness 0.15)
				)
			)
		)
		(property "MPN" "SRP2010-1R0M"
			(at 0 0 0)
			(layer "F.Fab")
			(hide yes)
			(effects
				(font
					(size 1 1)
					(thickness 0.15)
				)
			)
		)
		(property "Manufacturer" "Bourns"
			(at 0 0 0)
			(layer "F.Fab")
			(hide yes)
			(effects
				(font
					(size 1 1)
					(thickness 0.15)
				)
			)
		)
		(property "Size" "2.0x1.6"
			(at 0 0 0)
			(layer "F.Fab")
			(hide yes)
			(effects
				(font
					(size 1 1)
					(thickness 0.15)
				)
			)
		)
		(property "Val" "1u/2.6A"
			(at 0 0 0)
			(layer "F.Fab")
			(hide yes)
			(effects
				(font
					(size 1 1)
					(thickness 0.15)
				)
			)
		)
		(sheetname "/Power/")
		(sheetfile "power.kicad_sch")
		(attr smd)
		(fp_line
			(start -0.301 0.9)
			(end 0.299 0.9)
			(stroke
				(width 0.15)
				(type solid)
			)
			(layer "F.SilkS")
		)
		(fp_line
			(start -0.3 -0.9)
			(end 0.298 -0.9)
			(stroke
				(width 0.15)
				(type solid)
			)
			(layer "F.SilkS")
		)
		(fp_rect
			(start -1.75 -1.05)
			(end 1.75 1.05)
			(stroke
				(width 0.05)
				(type solid)
			)
			(fill no)
			(layer "F.CrtYd")
		)
		(fp_rect
			(start -0.951 -0.882)
			(end 0.949 0.875)
			(stroke
				(width 0.15)
				(type solid)
			)
			(fill no)
			(layer "F.Fab")
		)
		(pad "1" smd roundrect
			(at -1.1 -0.001)
			(size 1 1.8)
			(layers "F.Cu" "F.Mask" "F.Paste")
			(roundrect_rratio 0.15)
			(net 9 "/Power/SW_1V2")
			(pintype "passive")
		)
		(pad "2" smd roundrect
			(at 1.1 -0.001)
			(size 1 1.8)
			(layers "F.Cu" "F.Mask" "F.Paste")
			(roundrect_rratio 0.15)
			(net 11 "/Power/OUT_1V2")
			(pintype "passive")
		)
	)
	(footprint "antmicro-footprints:LED_0603_1608Metric_G"
		(layer "F.Cu")
		(at 156.972 96.1 -90)
		(descr "LED SMD 0603 Green")
		(tags "LED SMD 0603 Green")
		(property "Reference" "D12"
			(at 0.994444 38.555333 0)
			(layer "F.SilkS")
			(effects
				(font
					(size 0.7 0.7)
					(thickness 0.15)
				)
				(justify right bottom)
			)
		)
		(property "Value" "LED_G_0603_LTST-C190GKT"
			(at -0.001 1.599 90)
			(layer "F.Fab")
			(effects
				(font
					(size 0.7 0.7)
					(thickness 0.15)
				)
				(justify right bottom)
			)
		)
		(property "Datasheet" "https://media.digikey.com/pdf/Data%20Sheets/Lite-On%20PDFs/LTST-C190GKT.pdf"
			(at 0 0 270)
			(layer "F.Fab")
			(hide yes)
			(effects
				(font
					(size 1.27 1.27)
					(thickness 0.15)
				)
			)
		)
		(property "Description" "LED, Green, SMD, 0603, 20 mA, 2.1 V, 569 nm"
			(at 0 0 270)
			(layer "F.Fab")
			(hide yes)
			(effects
				(font
					(size 1.27 1.27)
					(thickness 0.15)
				)
			)
		)
		(property "Author" "Antmicro"
			(at 60.872 253.072 0)
			(layer "F.Fab")
			(hide yes)
			(effects
				(font
					(size 1 1)
					(thickness 0.15)
				)
			)
		)
		(property "Color" "Green"
			(at 60.872 253.072 0)
			(layer "F.Fab")
			(hide yes)
			(effects
				(font
					(size 1 1)
					(thickness 0.15)
				)
			)
		)
		(property "License" "Apache-2.0"
			(at 60.872 253.072 0)
			(layer "F.Fab")
			(hide yes)
			(effects
				(font
					(size 1 1)
					(thickness 0.15)
				)
			)
		)
		(property "MPN" "LTST-C190GKT"
			(at 60.872 253.072 0)
			(layer "F.Fab")
			(hide yes)
			(effects
				(font
					(size 1 1)
					(thickness 0.15)
				)
			)
		)
		(property "Manufacturer" "Lite-On"
			(at 60.872 253.072 0)
			(layer "F.Fab")
			(hide yes)
			(effects
				(font
					(size 1 1)
					(thickness 0.15)
				)
			)
		)
		(property "VSD_class" "LED"
			(at 60.872 253.072 0)
			(layer "F.Fab")
			(hide yes)
			(effects
				(font
					(size 1 1)
					(thickness 0.15)
				)
			)
		)
		(sheetname "/Connectors/")
		(sheetfile "connectors.kicad_sch")
		(attr smd)
		(fp_line
			(start 0.22 0.35)
			(end -0.22 0.35)
			(stroke
				(width 0.15)
				(type solid)
			)
			(layer "F.SilkS")
		)
		(fp_line
			(start -0.094672 0.201008)
			(end -0.094672 -0.198992)
			(stroke
				(width 0.1)
				(type solid)
			)
			(layer "F.SilkS")
		)
		(fp_line
			(start 0.105328 0.201008)
			(end -0.094672 0.001008)
			(stroke
				(width 0.1)
				(type solid)
			)
			(layer "F.SilkS")
		)
		(fp_line
			(start 0.105328 0.201008)
			(end 0.105328 -0.198992)
			(stroke
				(width 0.1)
				(type solid)
			)
			(layer "F.SilkS")
		)
		(fp_line
			(start -0.094672 0.001008)
			(end -0.24 0.001008)
			(stroke
				(width 0.1)
				(type solid)
			)
			(layer "F.SilkS")
		)
		(fp_line
			(start -0.094672 0.001008)
			(end 0.105328 -0.198992)
			(stroke
				(width 0.1)
				(type solid)
			)
			(layer "F.SilkS")
		)
		(fp_line
			(start 0.105328 0.001008)
			(end 0.24 0.001)
			(stroke
				(width 0.1)
				(type solid)
			)
			(layer "F.SilkS")
		)
		(fp_line
			(start -1.18 -0.319)
			(end -1.18 0.321)
			(stroke
				(width 0.15)
				(type solid)
			)
			(layer "F.SilkS")
		)
		(fp_line
			(start 0.22 -0.35)
			(end -0.22 -0.35)
			(stroke
				(width 0.15)
				(type solid)
			)
			(layer "F.SilkS")
		)
		(fp_rect
			(start 1.25 0.65)
			(end -1.25 -0.65)
			(stroke
				(width 0.05)
				(type solid)
			)
			(fill no)
			(layer "F.CrtYd")
		)
		(fp_line
			(start -0.199 0.2)
			(end -0.199 0.1)
			(stroke
				(width 0.15)
				(type solid)
			)
			(layer "F.Fab")
		)
		(fp_line
			(start 0.201 0.2)
			(end 0.201 0)
			(stroke
				(width 0.15)
				(type solid)
			)
			(layer "F.Fab")
		)
		(fp_line
			(start -0.199 0)
			(end -0.597 0)
			(stroke
				(width 0.15)
				(type solid)
			)
			(layer "F.Fab")
		)
		(fp_line
			(start -0.101 0)
			(end 0.201 0.2)
			(stroke
				(width 0.15)
				(type solid)
			)
			(layer "F.Fab")
		)
		(fp_line
			(start 0.201 0)
			(end 0.201 -0.202)
			(stroke
				(width 0.15)
				(type solid)
			)
			(layer "F.Fab")
		)
		(fp_line
			(start 0.599 0)
			(end 0.201 0)
			(stroke
				(width 0.15)
				(type solid)
			)
			(layer "F.Fab")
		)
		(fp_line
			(start -0.199 -0.202)
			(end -0.199 0.1)
			(stroke
				(width 0.15)
				(type solid)
			)
			(layer "F.Fab")
		)
		(fp_line
			(start 0.201 -0.202)
			(end -0.101 0)
			(stroke
				(width 0.15)
				(type solid)
			)
			(layer "F.Fab")
		)
		(fp_rect
			(start 0.848 0.4)
			(end -0.85 -0.402)
			(stroke
				(width 0.15)
				(type solid)
			)
			(fill no)
			(layer "F.Fab")
		)
		(pad "1" smd roundrect
			(at -0.7 0 90)
			(size 0.8 1)
			(layers "F.Cu" "F.Mask" "F.Paste")
			(roundrect_rratio 0.2)
			(net 65 "Net-(D12-C)")
			(pinfunction "C")
			(pintype "passive")
		)
		(pad "2" smd roundrect
			(at 0.7 0 90)
			(size 0.8 1)
			(layers "F.Cu" "F.Mask" "F.Paste")
			(roundrect_rratio 0.2)
			(net 50 "/Connectors/FFC_3V3")
			(pinfunction "A")
			(pintype "passive")
		)
	)
	(footprint "antmicro-footprints:R_0402_1005Metric"
		(layer "F.Cu")
		(at 128.198 72.24 180)
		(descr "Resistor SMD 0402")
		(tags "resistor SMD 0402")
		(property "Reference" "R28"
			(at -1.016 0.739 0)
			(layer "F.SilkS")
			(effects
				(font
					(size 0.7 0.7)
					(thickness 0.15)
				)
				(justify right bottom)
			)
		)
		(property "Value" "R_0R_0402"
			(at -1.011843 1.772047 0)
			(layer "F.Fab")
			(effects
				(font
					(size 0.7 0.7)
					(thickness 0.15)
				)
				(justify right bottom)
			)
		)
		(property "Datasheet" "https://industrial.panasonic.com/cdbs/www-data/pdf/RDA0000/AOA0000C301.pdf"
			(at 0 0 180)
			(layer "F.Fab")
			(hide yes)
			(effects
				(font
					(size 1.27 1.27)
					(thickness 0.15)
				)
			)
		)
		(property "Description" "SMD Chip Resistor, Jumper, 0 ohm, 100 mW, 0402 [1005 Metric], Thick Film, General Purpose"
			(at 0 0 180)
			(layer "F.Fab")
			(hide yes)
			(effects
				(font
					(size 1.27 1.27)
					(thickness 0.15)
				)
			)
		)
		(property "Author" "Antmicro"
			(at 256.396 144.48 0)
			(layer "F.Fab")
			(hide yes)
			(effects
				(font
					(size 1 1)
					(thickness 0.15)
				)
			)
		)
		(property "Current" "1A"
			(at 256.396 144.48 0)
			(layer "F.Fab")
			(hide yes)
			(effects
				(font
					(size 1 1)
					(thickness 0.15)
				)
			)
		)
		(property "License" "Apache-2.0"
			(at 256.396 144.48 0)
			(layer "F.Fab")
			(hide yes)
			(effects
				(font
					(size 1 1)
					(thickness 0.15)
				)
			)
		)
		(property "MPN" "ERJ2GE0R00X"
			(at 256.396 144.48 0)
			(layer "F.Fab")
			(hide yes)
			(effects
				(font
					(size 1 1)
					(thickness 0.15)
				)
			)
		)
		(property "Manufacturer" "Panasonic"
			(at 256.396 144.48 0)
			(layer "F.Fab")
			(hide yes)
			(effects
				(font
					(size 1 1)
					(thickness 0.15)
				)
			)
		)
		(property "Tolerance" ""
			(at 256.396 144.48 0)
			(layer "F.Fab")
			(hide yes)
			(effects
				(font
					(size 1 1)
					(thickness 0.15)
				)
			)
		)
		(property "Val" "0R"
			(at 256.396 144.48 0)
			(layer "F.Fab")
			(hide yes)
			(effects
				(font
					(size 1 1)
					(thickness 0.15)
				)
			)
		)
		(sheetname "/Power/")
		(sheetfile "power.kicad_sch")
		(attr smd)
		(fp_rect
			(start -0.925 -0.47)
			(end 0.925 0.47)
			(stroke
				(width 0.05)
				(type default)
			)
			(fill no)
			(layer "F.CrtYd")
		)
		(fp_rect
			(start -0.5 -0.25)
			(end 0.5 0.25)
			(stroke
				(width 0.15)
				(type solid)
			)
			(fill no)
			(layer "F.Fab")
		)
		(pad "1" smd roundrect
			(at -0.48 0 180)
			(size 0.59 0.64)
			(layers "F.Cu" "F.Mask" "F.Paste")
			(roundrect_rratio 0.25)
			(net 125 "/Power/EN_12V")
			(pintype "passive")
		)
		(pad "2" smd roundrect
			(at 0.48 0 180)
			(size 0.59 0.64)
			(layers "F.Cu" "F.Mask" "F.Paste")
			(roundrect_rratio 0.25)
			(net 5 "+5V")
			(pintype "passive")
		)
	)
	(footprint "antmicro-footprints:C_0402_1005Metric"
		(layer "F.Cu")
		(at 152.654 76.2 45)
		(descr "Capacitor SMD 0402")
		(tags "capacitor SMD 0402")
		(property "Reference" "C35"
			(at 4.003639 0.193747 45)
			(layer "F.SilkS")
			(effects
				(font
					(size 0.7 0.7)
					(thickness 0.15)
				)
				(justify left bottom)
			)
		)
		(property "Value" "C_100n_0402"
			(at -1.022927 2.155213 45)
			(layer "F.Fab")
			(effects
				(font
					(size 0.7 0.7)
					(thickness 0.15)
				)
				(justify left bottom)
			)
		)
		(property "Datasheet" "https://www.murata.com/products/productdetail?partno=GRM155R61H104KE14%23"
			(at 0 0 45)
			(layer "F.Fab")
			(hide yes)
			(effects
				(font
					(size 1.27 1.27)
					(thickness 0.15)
				)
			)
		)
		(property "Description" "SMD Multilayer Ceramic Capacitor, 0.1 µF, 50 V, 0402 [1005 Metric], ± 10%, X5R, GRM Series"
			(at 0 0 45)
			(layer "F.Fab")
			(hide yes)
			(effects
				(font
					(size 1.27 1.27)
					(thickness 0.15)
				)
			)
		)
		(property "Author" "Antmicro"
			(at 98.592858 -85.624216 0)
			(layer "F.Fab")
			(hide yes)
			(effects
				(font
					(size 1 1)
					(thickness 0.15)
				)
			)
		)
		(property "Dielectric" "X5R"
			(at 98.592858 -85.624216 0)
			(layer "F.Fab")
			(hide yes)
			(effects
				(font
					(size 1 1)
					(thickness 0.15)
				)
			)
		)
		(property "License" "Apache-2.0"
			(at 98.592858 -85.624216 0)
			(layer "F.Fab")
			(hide yes)
			(effects
				(font
					(size 1 1)
					(thickness 0.15)
				)
			)
		)
		(property "MPN" "GRM155R61H104KE14D"
			(at 98.592858 -85.624216 0)
			(layer "F.Fab")
			(hide yes)
			(effects
				(font
					(size 1 1)
					(thickness 0.15)
				)
			)
		)
		(property "Manufacturer" "Murata"
			(at 98.592858 -85.624216 0)
			(layer "F.Fab")
			(hide yes)
			(effects
				(font
					(size 1 1)
					(thickness 0.15)
				)
			)
		)
		(property "Val" "100n"
			(at 98.592858 -85.624216 0)
			(layer "F.Fab")
			(hide yes)
			(effects
				(font
					(size 1 1)
					(thickness 0.15)
				)
			)
		)
		(property "Voltage" "50V"
			(at 98.592858 -85.624216 0)
			(layer "F.Fab")
			(hide yes)
			(effects
				(font
					(size 1 1)
					(thickness 0.15)
				)
			)
		)
		(sheetname "/Deserializer/")
		(sheetfile "deserializer.kicad_sch")
		(attr smd)
		(fp_poly
			(pts
				(xy -0.925 -0.47) (xy 0.925 -0.47) (xy 0.925 0.47) (xy -0.925 0.47)
			)
			(stroke
				(width 0.05)
				(type default)
			)
			(fill no)
			(layer "F.CrtYd")
		)
		(fp_line
			(start -0.494 -0.25)
			(end 0.504 -0.25)
			(stroke
				(width 0.15)
				(type solid)
			)
			(layer "F.Fab")
		)
		(fp_line
			(start -0.494 0.248)
			(end -0.494 -0.25)
			(stroke
				(width 0.15)
				(type solid)
			)
			(layer "F.Fab")
		)
		(fp_line
			(start 0.504 -0.25)
			(end 0.504 0.248)
			(stroke
				(width 0.15)
				(type solid)
			)
			(layer "F.Fab")
		)
		(fp_line
			(start 0.504 0.248)
			(end -0.494 0.248)
			(stroke
				(width 0.15)
				(type solid)
			)
			(layer "F.Fab")
		)
		(pad "1" smd roundrect
			(at -0.48 0 45)
			(size 0.59 0.64)
			(layers "F.Cu" "F.Mask" "F.Paste")
			(roundrect_rratio 0.25)
			(net 24 "/Deserializer/SIOD_N")
			(pintype "passive")
		)
		(pad "2" smd roundrect
			(at 0.48 0 45)
			(size 0.59 0.64)
			(layers "F.Cu" "F.Mask" "F.Paste")
			(roundrect_rratio 0.25)
			(net 25 "Net-(C35-Pad2)")
			(pintype "passive")
		)
	)
	(footprint "antmicro-footprints:R_0402_1005Metric"
		(layer "F.Cu")
		(at 168.91 64.135 90)
		(descr "Resistor SMD 0402")
		(tags "resistor SMD 0402")
		(property "Reference" "R3"
			(at -2.248717 0.4705 90)
			(layer "F.SilkS")
			(effects
				(font
					(size 0.7 0.7)
					(thickness 0.15)
				)
				(justify left bottom)
			)
		)
		(property "Value" "R_0R_0402"
			(at -1.011843 1.772047 90)
			(layer "F.Fab")
			(effects
				(font
					(size 0.7 0.7)
					(thickness 0.15)
				)
				(justify left bottom)
			)
		)
		(property "Datasheet" "https://industrial.panasonic.com/cdbs/www-data/pdf/RDA0000/AOA0000C301.pdf"
			(at 0 0 90)
			(layer "F.Fab")
			(hide yes)
			(effects
				(font
					(size 1.27 1.27)
					(thickness 0.15)
				)
			)
		)
		(property "Description" "SMD Chip Resistor, Jumper, 0 ohm, 100 mW, 0402 [1005 Metric], Thick Film, General Purpose"
			(at 0 0 90)
			(layer "F.Fab")
			(hide yes)
			(effects
				(font
					(size 1.27 1.27)
					(thickness 0.15)
				)
			)
		)
		(property "Author" "Antmicro"
			(at 233.045 -104.775 0)
			(layer "F.Fab")
			(hide yes)
			(effects
				(font
					(size 1 1)
					(thickness 0.15)
				)
			)
		)
		(property "Current" "1A"
			(at 233.045 -104.775 0)
			(layer "F.Fab")
			(hide yes)
			(effects
				(font
					(size 1 1)
					(thickness 0.15)
				)
			)
		)
		(property "License" "Apache-2.0"
			(at 233.045 -104.775 0)
			(layer "F.Fab")
			(hide yes)
			(effects
				(font
					(size 1 1)
					(thickness 0.15)
				)
			)
		)
		(property "MPN" "ERJ2GE0R00X"
			(at 233.045 -104.775 0)
			(layer "F.Fab")
			(hide yes)
			(effects
				(font
					(size 1 1)
					(thickness 0.15)
				)
			)
		)
		(property "Manufacturer" "Panasonic"
			(at 233.045 -104.775 0)
			(layer "F.Fab")
			(hide yes)
			(effects
				(font
					(size 1 1)
					(thickness 0.15)
				)
			)
		)
		(property "Tolerance" ""
			(at 233.045 -104.775 0)
			(layer "F.Fab")
			(hide yes)
			(effects
				(font
					(size 1 1)
					(thickness 0.15)
				)
			)
		)
		(property "Val" "0R"
			(at 233.045 -104.775 0)
			(layer "F.Fab")
			(hide yes)
			(effects
				(font
					(size 1 1)
					(thickness 0.15)
				)
			)
		)
		(sheetname "/Connectors/")
		(sheetfile "connectors.kicad_sch")
		(attr smd)
		(fp_rect
			(start -0.925 -0.47)
			(end 0.925 0.47)
			(stroke
				(width 0.05)
				(type default)
			)
			(fill no)
			(layer "F.CrtYd")
		)
		(fp_rect
			(start -0.5 -0.25)
			(end 0.5 0.25)
			(stroke
				(width 0.15)
				(type solid)
			)
			(fill no)
			(layer "F.Fab")
		)
		(pad "1" smd roundrect
			(at -0.48 0 90)
			(size 0.59 0.64)
			(layers "F.Cu" "F.Mask" "F.Paste")
			(roundrect_rratio 0.25)
			(net 81 "/Connectors/MFP1")
			(pintype "passive")
		)
		(pad "2" smd roundrect
			(at 0.48 0 90)
			(size 0.59 0.64)
			(layers "F.Cu" "F.Mask" "F.Paste")
			(roundrect_rratio 0.25)
			(net 130 "Net-(U1-Y)")
			(pintype "passive")
		)
	)
	(footprint "antmicro-footprints:Conn_FAKRA_7-2287906-0"
		(layer "F.Cu")
		(at 152.283332 38.348)
		(descr "Connector FAKRA, 5 pins")
		(property "Reference" "J4"
			(at 5.054 5.3 0)
			(layer "F.SilkS")
			(effects
				(font
					(size 0.7 0.7)
					(thickness 0.15)
				)
				(justify left bottom)
			)
		)
		(property "Value" "Conn_FAKRA_59S2AQ-40MT5-Z_1"
			(at -6.55 15.019 0)
			(layer "F.Fab")
			(effects
				(font
					(size 0.7 0.7)
					(thickness 0.15)
				)
				(justify left bottom)
			)
		)
		(property ki_fp_filters "*BNC* *SMA* *SMB* *SMC* *Cinch*")
		(sheetname "/Connectors/")
		(sheetfile "connectors.kicad_sch")
		(attr through_hole)
		(fp_line
			(start -4.572 0.94)
			(end -4.572 13.919)
			(stroke
				(width 0.15)
				(type solid)
			)
			(layer "F.SilkS")
		)
		(fp_line
			(start -4.572 13.919)
			(end 4.572 13.919)
			(stroke
				(width 0.15)
				(type solid)
			)
			(layer "F.SilkS")
		)
		(fp_line
			(start 4.572 0.94)
			(end -4.572 0.94)
			(stroke
				(width 0.15)
				(type solid)
			)
			(layer "F.SilkS")
		)
		(fp_line
			(start 4.572 13.919)
			(end 4.572 0.94)
			(stroke
				(width 0.15)
				(type solid)
			)
			(layer "F.SilkS")
		)
		(fp_rect
			(start -5.14 -12.64)
			(end 5.131 14.164)
			(stroke
				(width 0.05)
				(type solid)
			)
			(fill no)
			(layer "F.CrtYd")
		)
		(fp_text user "${REFERENCE}"
			(at -6.55 18.619 0)
			(layer "F.Fab")
			(effects
				(font
					(size 0.7 0.7)
					(thickness 0.15)
				)
				(justify left bottom)
			)
		)
		(fp_text user "Author: Antmicro"
			(at -6.55 17.419 0)
			(layer "F.Fab")
			(effects
				(font
					(size 0.7 0.7)
					(thickness 0.15)
				)
				(justify left bottom)
			)
		)
		(fp_text user "License: Apache-2.0"
			(at -6.55 16.219 0)
			(layer "F.Fab")
			(effects
				(font
					(size 0.7 0.7)
					(thickness 0.15)
				)
				(justify left bottom)
			)
		)
		(pad "1" smd roundrect
			(at 0 3.62 270)
			(size 4.79 1.9)
			(layers "F.Cu" "F.Mask" "F.Paste")
			(roundrect_rratio 0.25)
			(net 116 "/Connectors/PoCC")
			(pinfunction "1")
			(pintype "passive")
		)
		(pad "2" thru_hole circle
			(at -3 3.315 270)
			(size 1.8 1.8)
			(drill 1.45)
			(layers "*.Cu" "*.Mask")
			(remove_unused_layers no)
			(net 1 "GND")
			(pinfunction "2")
			(pintype "passive")
		)
		(pad "2" smd roundrect
			(at -2.9975 3.7175 270)
			(size 4.985 1.8)
			(layers "F.Cu" "F.Mask" "F.Paste")
			(roundrect_rratio 0.25)
			(net 1 "GND")
			(pinfunction "2")
			(pintype "passive")
		)
		(pad "3" thru_hole circle
			(at -3 10.315 270)
			(size 1.8 1.8)
			(drill 1.45)
			(layers "*.Cu" "*.Mask")
			(remove_unused_layers no)
			(net 1 "GND")
			(pinfunction "3")
			(pintype "passive")
		)
		(pad "3" smd roundrect
			(at -3 10.815 270)
			(size 5.6 1.8)
			(layers "F.Cu" "F.Mask" "F.Paste")
			(roundrect_rratio 0.25)
			(net 1 "GND")
			(pinfunction "3")
			(pintype "passive")
		)
		(pad "4" thru_hole circle
			(at 3 10.315 270)
			(size 1.8 1.8)
			(drill 1.45)
			(layers "*.Cu" "*.Mask")
			(remove_unused_layers no)
			(net 1 "GND")
			(pinfunction "4")
			(pintype "passive")
		)
		(pad "4" smd roundrect
			(at 3 10.815 270)
			(size 5.6 1.8)
			(layers "F.Cu" "F.Mask" "F.Paste")
			(roundrect_rratio 0.25)
			(net 1 "GND")
			(pinfunction "4")
			(pintype "passive")
		)
		(pad "5" thru_hole circle
			(at 3 3.315 270)
			(size 1.8 1.8)
			(drill 1.45)
			(layers "*.Cu" "*.Mask")
			(remove_unused_layers no)
			(net 1 "GND")
			(pinfunction "5")
			(pintype "passive")
		)
		(pad "5" smd roundrect
			(at 3 3.72 270)
			(size 4.99 1.8)
			(layers "F.Cu" "F.Mask" "F.Paste")
			(roundrect_rratio 0.25)
			(net 1 "GND")
			(pinfunction "5")
			(pintype "passive")
		)
	)
	(footprint "antmicro-footprints:F_1206_3216Metric"
		(layer "F.Cu")
		(at 171.45 53.34 -90)
		(property "Reference" "F1"
			(at -1.184797 1.152333 90)
			(layer "F.SilkS")
			(effects
				(font
					(size 0.7 0.7)
					(thickness 0.15)
				)
				(justify right bottom)
			)
		)
		(property "Value" "F_4A_1206"
			(at 0 2 90)
			(layer "F.Fab")
			(effects
				(font
					(size 0.7 0.7)
					(thickness 0.15)
				)
				(justify right bottom)
			)
		)
		(property "Datasheet" "https://www.littelfuse.com/media?resourcetype=datasheets&itemid=dbe9bcd7-6072-4adf-bf5b-d33e52a6b90f&filename=littelfuse-fuse-466-datasheet"
			(at 0 0 270)
			(layer "F.Fab")
			(hide yes)
			(effects
				(font
					(size 1.27 1.27)
					(thickness 0.15)
				)
			)
		)
		(property "Description" "Fuse, Surface Mount, 4 A, Very Fast Acting, 32 V, 32 V, 1206 (3216 Metric), 466"
			(at 0 0 270)
			(layer "F.Fab")
			(hide yes)
			(effects
				(font
					(size 1.27 1.27)
					(thickness 0.15)
				)
			)
		)
		(property "Author" "Antmicro"
			(at 118.11 224.79 0)
			(layer "F.Fab")
			(hide yes)
			(effects
				(font
					(size 1 1)
					(thickness 0.15)
				)
			)
		)
		(property "License" "Apache-2.0"
			(at 118.11 224.79 0)
			(layer "F.Fab")
			(hide yes)
			(effects
				(font
					(size 1 1)
					(thickness 0.15)
				)
			)
		)
		(property "MPN" "0466004.NR "
			(at 118.11 224.79 0)
			(layer "F.Fab")
			(hide yes)
			(effects
				(font
					(size 1 1)
					(thickness 0.15)
				)
			)
		)
		(property "Manufacturer" "Littelfuse"
			(at 118.11 224.79 0)
			(layer "F.Fab")
			(hide yes)
			(effects
				(font
					(size 1 1)
					(thickness 0.15)
				)
			)
		)
		(sheetname "/Connectors/")
		(sheetfile "connectors.kicad_sch")
		(attr smd)
		(fp_line
			(start 0.8 0.901)
			(end -0.8 0.901)
			(stroke
				(width 0.15)
				(type solid)
			)
			(layer "F.SilkS")
		)
		(fp_line
			(start 0.8 -0.899)
			(end -0.8 -0.899)
			(stroke
				(width 0.15)
				(type solid)
			)
			(layer "F.SilkS")
		)
		(fp_rect
			(start -2.325 -1.15)
			(end 2.325 1.15)
			(stroke
				(width 0.05)
				(type default)
			)
			(fill no)
			(layer "F.CrtYd")
		)
		(fp_line
			(start -1.677 0.792)
			(end -1.677 -0.861)
			(stroke
				(width 0.15)
				(type solid)
			)
			(layer "F.Fab")
		)
		(fp_line
			(start 1.624 0.792)
			(end -1.677 0.792)
			(stroke
				(width 0.15)
				(type solid)
			)
			(layer "F.Fab")
		)
		(fp_line
			(start -1.677 -0.861)
			(end 1.624 -0.861)
			(stroke
				(width 0.15)
				(type solid)
			)
			(layer "F.Fab")
		)
		(fp_line
			(start 1.624 -0.861)
			(end 1.624 0.792)
			(stroke
				(width 0.15)
				(type solid)
			)
			(layer "F.Fab")
		)
		(pad "1" smd roundrect
			(at -1.5 0.001 270)
			(size 1.15 1.8)
			(layers "F.Cu" "F.Mask" "F.Paste")
			(roundrect_rratio 0.25)
			(net 2 "/Connectors/DC_UNFUSED")
			(pintype "passive")
		)
		(pad "2" smd roundrect
			(at 1.5 0.001 270)
			(size 1.15 1.8)
			(layers "F.Cu" "F.Mask" "F.Paste")
			(roundrect_rratio 0.25)
			(net 118 "/Connectors/DC_IN")
			(pintype "passive")
		)
	)
	(footprint "antmicro-footprints:C_0402_1005Metric"
		(layer "F.Cu")
		(at 126.42 85.702 -90)
		(descr "Capacitor SMD 0402")
		(tags "capacitor SMD 0402")
		(property "Reference" "C22"
			(at -0.485 -2.231 90)
			(layer "F.SilkS")
			(effects
				(font
					(size 0.7 0.7)
					(thickness 0.15)
				)
				(justify right bottom)
			)
		)
		(property "Value" "C_22u_0402"
			(at -1.022927 2.155213 90)
			(layer "F.Fab")
			(effects
				(font
					(size 0.7 0.7)
					(thickness 0.15)
				)
				(justify right bottom)
			)
		)
		(property "Datasheet" "https://www.murata.com/products/productdetail?partno=GRM158R60J226ME01%23"
			(at 0 0 270)
			(layer "F.Fab")
			(hide yes)
			(effects
				(font
					(size 1.27 1.27)
					(thickness 0.15)
				)
			)
		)
		(property "Description" "SMD Multilayer Ceramic Capacitor, 22 uF, 4 V, 0402 [1005 Metric], X6S"
			(at 0 0 270)
			(layer "F.Fab")
			(hide yes)
			(effects
				(font
					(size 1.27 1.27)
					(thickness 0.15)
				)
			)
		)
		(property "Author" "Antmicro"
			(at 40.718 212.122 0)
			(layer "F.Fab")
			(hide yes)
			(effects
				(font
					(size 1 1)
					(thickness 0.15)
				)
			)
		)
		(property "Dielectric" ""
			(at 40.718 212.122 0)
			(layer "F.Fab")
			(hide yes)
			(effects
				(font
					(size 1 1)
					(thickness 0.15)
				)
			)
		)
		(property "License" "Apache-2.0"
			(at 40.718 212.122 0)
			(layer "F.Fab")
			(hide yes)
			(effects
				(font
					(size 1 1)
					(thickness 0.15)
				)
			)
		)
		(property "MPN" "GRM158R60J226ME01D"
			(at 40.718 212.122 0)
			(layer "F.Fab")
			(hide yes)
			(effects
				(font
					(size 1 1)
					(thickness 0.15)
				)
			)
		)
		(property "Manufacturer" "Murata"
			(at 40.718 212.122 0)
			(layer "F.Fab")
			(hide yes)
			(effects
				(font
					(size 1 1)
					(thickness 0.15)
				)
			)
		)
		(property "Val" "22u"
			(at 40.718 212.122 0)
			(layer "F.Fab")
			(hide yes)
			(effects
				(font
					(size 1 1)
					(thickness 0.15)
				)
			)
		)
		(property "Voltage" ""
			(at 40.718 212.122 0)
			(layer "F.Fab")
			(hide yes)
			(effects
				(font
					(size 1 1)
					(thickness 0.15)
				)
			)
		)
		(sheetname "/Power/")
		(sheetfile "power.kicad_sch")
		(attr smd)
		(fp_rect
			(start -0.925 -0.47)
			(end 0.925 0.47)
			(stroke
				(width 0.05)
				(type default)
			)
			(fill no)
			(layer "F.CrtYd")
		)
		(fp_line
			(start -0.494 0.248)
			(end -0.494 -0.25)
			(stroke
				(width 0.15)
				(type solid)
			)
			(layer "F.Fab")
		)
		(fp_line
			(start 0.504 0.248)
			(end -0.494 0.248)
			(stroke
				(width 0.15)
				(type solid)
			)
			(layer "F.Fab")
		)
		(fp_line
			(start -0.494 -0.25)
			(end 0.504 -0.25)
			(stroke
				(width 0.15)
				(type solid)
			)
			(layer "F.Fab")
		)
		(fp_line
			(start 0.504 -0.25)
			(end 0.504 0.248)
			(stroke
				(width 0.15)
				(type solid)
			)
			(layer "F.Fab")
		)
		(pad "1" smd roundrect
			(at -0.48 0 270)
			(size 0.59 0.64)
			(layers "F.Cu" "F.Mask" "F.Paste")
			(roundrect_rratio 0.25)
			(net 1 "GND")
			(pintype "passive")
		)
		(pad "2" smd roundrect
			(at 0.48 0 270)
			(size 0.59 0.64)
			(layers "F.Cu" "F.Mask" "F.Paste")
			(roundrect_rratio 0.25)
			(net 11 "/Power/OUT_1V2")
			(pintype "passive")
		)
	)
	(footprint "antmicro-footprints:TSSOP-8_3x3mm_P0.65mm"
		(layer "F.Cu")
		(at 176.196 62.584 -90)
		(property "Reference" "U8"
			(at -3.406179 -2.154 90)
			(layer "F.SilkS")
			(effects
				(font
					(size 0.7 0.7)
					(thickness 0.15)
				)
				(justify right bottom)
			)
		)
		(property "Value" "NTS0102_TSSOP"
			(at 0 2.8 90)
			(layer "F.Fab")
			(effects
				(font
					(size 0.7 0.7)
					(thickness 0.15)
				)
				(justify right bottom)
			)
		)
		(property "Datasheet" "https://www.mouser.com/datasheet/2/302/NTS0102-1127324.pdf"
			(at 0 0 270)
			(layer "F.Fab")
			(hide yes)
			(effects
				(font
					(size 1.27 1.27)
					(thickness 0.15)
				)
			)
		)
		(property "Description" "Transceiver, 1.65 V to 3.6 V, TSSOP-8"
			(at 0 0 270)
			(layer "F.Fab")
			(hide yes)
			(effects
				(font
					(size 1.27 1.27)
					(thickness 0.15)
				)
			)
		)
		(property "Author" "Antmicro"
			(at 113.612 238.78 0)
			(layer "F.Fab")
			(hide yes)
			(effects
				(font
					(size 1 1)
					(thickness 0.15)
				)
			)
		)
		(property "License" "Apache-2.0"
			(at 113.612 238.78 0)
			(layer "F.Fab")
			(hide yes)
			(effects
				(font
					(size 1 1)
					(thickness 0.15)
				)
			)
		)
		(property "MPN" "NTS0102DP"
			(at 113.612 238.78 0)
			(layer "F.Fab")
			(hide yes)
			(effects
				(font
					(size 1 1)
					(thickness 0.15)
				)
			)
		)
		(property "Manufacturer" "NXP"
			(at 113.612 238.78 0)
			(layer "F.Fab")
			(hide yes)
			(effects
				(font
					(size 1 1)
					(thickness 0.15)
				)
			)
		)
		(sheetname "/Connectors/")
		(sheetfile "connectors.kicad_sch")
		(attr smd)
		(fp_line
			(start -1.55 1.561)
			(end 1.552 1.561)
			(stroke
				(width 0.15)
				(type solid)
			)
			(layer "F.SilkS")
		)
		(fp_line
			(start -1.525 -1.537)
			(end 1.552 -1.539)
			(stroke
				(width 0.15)
				(type solid)
			)
			(layer "F.SilkS")
		)
		(fp_circle
			(center -1.87 -1.4)
			(end -1.82 -1.4)
			(stroke
				(width 0.15)
				(type solid)
			)
			(fill yes)
			(layer "F.SilkS")
		)
		(fp_rect
			(start -3.15 -1.789)
			(end 3.15 1.811)
			(stroke
				(width 0.05)
				(type solid)
			)
			(fill no)
			(layer "F.CrtYd")
		)
		(fp_line
			(start -1.55 1.561)
			(end 1.552 1.561)
			(stroke
				(width 0.15)
				(type solid)
			)
			(layer "F.Fab")
		)
		(fp_line
			(start -1.55 -0.937)
			(end -1.55 1.561)
			(stroke
				(width 0.15)
				(type solid)
			)
			(layer "F.Fab")
		)
		(fp_line
			(start -1.55 -0.937)
			(end -0.949 -1.539)
			(stroke
				(width 0.15)
				(type solid)
			)
			(layer "F.Fab")
		)
		(fp_line
			(start -0.949 -1.539)
			(end 1.552 -1.539)
			(stroke
				(width 0.15)
				(type solid)
			)
			(layer "F.Fab")
		)
		(fp_line
			(start 1.552 -1.539)
			(end 1.552 1.561)
			(stroke
				(width 0.15)
				(type solid)
			)
			(layer "F.Fab")
		)
		(pad "1" smd roundrect
			(at -2.148 -0.962 270)
			(size 1.47 0.4)
			(layers "F.Cu" "F.Mask" "F.Paste")
			(roundrect_rratio 0.25)
			(net 45 "/Connectors/SCL_CAM")
			(pinfunction "B_{2}")
			(pintype "bidirectional")
		)
		(pad "2" smd roundrect
			(at -2.148 -0.313 270)
			(size 1.47 0.4)
			(layers "F.Cu" "F.Mask" "F.Paste")
			(roundrect_rratio 0.25)
			(net 1 "GND")
			(pinfunction "GND")
			(pintype "power_in")
		)
		(pad "3" smd roundrect
			(at -2.148 0.338 270)
			(size 1.47 0.4)
			(layers "F.Cu" "F.Mask" "F.Paste")
			(roundrect_rratio 0.25)
			(net 3 "+1V8")
			(pinfunction "VCC_{A}")
			(pintype "power_in")
		)
		(pad "4" smd roundrect
			(at -2.148 0.987 270)
			(size 1.47 0.4)
			(layers "F.Cu" "F.Mask" "F.Paste")
			(roundrect_rratio 0.25)
			(net 134 "Net-(U8-A_{2})")
			(pinfunction "A_{2}")
			(pintype "bidirectional")
		)
		(pad "5" smd roundrect
			(at 2.151 0.987 270)
			(size 1.47 0.4)
			(layers "F.Cu" "F.Mask" "F.Paste")
			(roundrect_rratio 0.25)
			(net 133 "Net-(U8-A_{1})")
			(pinfunction "A_{1}")
			(pintype "bidirectional")
		)
		(pad "6" smd roundrect
			(at 2.151 0.338 270)
			(size 1.47 0.4)
			(layers "F.Cu" "F.Mask" "F.Paste")
			(roundrect_rratio 0.25)
			(net 135 "Net-(U8-OE)")
			(pinfunction "OE")
			(pintype "input")
		)
		(pad "7" smd roundrect
			(at 2.151 -0.313 270)
			(size 1.47 0.4)
			(layers "F.Cu" "F.Mask" "F.Paste")
			(roundrect_rratio 0.25)
			(net 50 "/Connectors/FFC_3V3")
			(pinfunction "VCC_{B}")
			(pintype "power_in")
		)
		(pad "8" smd roundrect
			(at 2.151 -0.962 270)
			(size 1.47 0.4)
			(layers "F.Cu" "F.Mask" "F.Paste")
			(roundrect_rratio 0.25)
			(net 44 "/Connectors/SDA_CAM")
			(pinfunction "B_{1}")
			(pintype "bidirectional")
		)
	)
	(footprint "antmicro-footprints:Resonator_SMD_Abracon_ABM8G_3.2x2.5mm"
		(layer "F.Cu")
		(at 147.248 71.732 180)
		(property "Reference" "Y1"
			(at -1.75 -1.75 0)
			(layer "F.SilkS")
			(effects
				(font
					(size 0.7 0.7)
					(thickness 0.15)
				)
				(justify left bottom)
			)
		)
		(property "Value" "Resonator_25MHz_ABM8G"
			(at -1.75 2.548 180)
			(layer "F.Fab")
			(effects
				(font
					(size 0.7 0.7)
					(thickness 0.15)
				)
				(justify left bottom)
			)
		)
		(property "Datasheet" "https://abracon.com/Resonators/ABM8G.pdf"
			(at 0 0 180)
			(layer "F.Fab")
			(hide yes)
			(effects
				(font
					(size 1.27 1.27)
					(thickness 0.15)
				)
			)
		)
		(property "Description" "Crystal, 25 MHz, SMD, 3.2mm x 2.5mm, 30 ppm, 18 pF, 20 ppm, ABM8G"
			(at 0 0 180)
			(layer "F.Fab")
			(hide yes)
			(effects
				(font
					(size 1.27 1.27)
					(thickness 0.15)
				)
			)
		)
		(property "Author" "Antmicro"
			(at 294.496 143.464 0)
			(layer "F.Fab")
			(hide yes)
			(effects
				(font
					(size 1 1)
					(thickness 0.15)
				)
			)
		)
		(property "License" "Apache-2.0"
			(at 294.496 143.464 0)
			(layer "F.Fab")
			(hide yes)
			(effects
				(font
					(size 1 1)
					(thickness 0.15)
				)
			)
		)
		(property "MPN" "ABM8G-25.000MHZ-18-D2Y-T3"
			(at 294.496 143.464 0)
			(layer "F.Fab")
			(hide yes)
			(effects
				(font
					(size 1 1)
					(thickness 0.15)
				)
			)
		)
		(property "Manufacturer" "Abracon"
			(at 294.496 143.464 0)
			(layer "F.Fab")
			(hide yes)
			(effects
				(font
					(size 1 1)
					(thickness 0.15)
				)
			)
		)
		(property "Val" "25 MHz"
			(at 294.496 143.464 0)
			(layer "F.Fab")
			(hide yes)
			(effects
				(font
					(size 1 1)
					(thickness 0.15)
				)
			)
		)
		(sheetname "/Deserializer/")
		(sheetfile "deserializer.kicad_sch")
		(attr smd)
		(fp_line
			(start 1.6 0.3)
			(end 1.6 -0.2)
			(stroke
				(width 0.15)
				(type solid)
			)
			(layer "F.SilkS")
		)
		(fp_line
			(start -0.35 1.25)
			(end 0.45 1.25)
			(stroke
				(width 0.15)
				(type solid)
			)
			(layer "F.SilkS")
		)
		(fp_line
			(start -0.35 -1.25)
			(end 0.45 -1.25)
			(stroke
				(width 0.15)
				(type solid)
			)
			(layer "F.SilkS")
		)
		(fp_line
			(start -1.6 0.3)
			(end -1.6 -0.2)
			(stroke
				(width 0.15)
				(type solid)
			)
			(layer "F.SilkS")
		)
		(fp_circle
			(center -1.75 1.5)
			(end -1.7 1.5)
			(stroke
				(width 0.15)
				(type solid)
			)
			(fill no)
			(layer "F.SilkS")
		)
		(fp_rect
			(start -1.907 -1.55)
			(end 2.006 1.649)
			(stroke
				(width 0.05)
				(type solid)
			)
			(fill no)
			(layer "F.CrtYd")
		)
		(pad "1" smd roundrect
			(at -1.101 0.949 180)
			(size 1.3 1.1)
			(layers "F.Cu" "F.Mask" "F.Paste")
			(roundrect_rratio 0)
			(chamfer_ratio 0.2)
			(chamfer bottom_left)
			(net 12 "/Deserializer/X1")
			(pintype "passive")
		)
		(pad "2" smd rect
			(at 1.199 0.949 180)
			(size 1.3 1.1)
			(layers "F.Cu" "F.Mask" "F.Paste")
			(net 1 "GND")
			(pinfunction "SH")
			(pintype "passive")
		)
		(pad "3" smd rect
			(at 1.199 -0.85 180)
			(size 1.3 1.1)
			(layers "F.Cu" "F.Mask" "F.Paste")
			(net 17 "/Deserializer/X2_R")
			(pintype "passive")
		)
		(pad "4" smd rect
			(at -1.101 -0.85 180)
			(size 1.3 1.1)
			(layers "F.Cu" "F.Mask" "F.Paste")
			(net 1 "GND")
			(pinfunction "SH")
			(pintype "passive")
		)
	)
	(footprint "antmicro-footprints:TP_SMD_0.75mm"
		(layer "F.Cu")
		(at 152.4 97.89)
		(property "Reference" "TP6"
			(at 0 -0.6 0)
			(layer "F.SilkS")
			(hide yes)
			(effects
				(font
					(size 0.7 0.7)
					(thickness 0.15)
				)
				(justify left bottom)
			)
		)
		(property "Value" "TP_0.75mm_SMD"
			(at 0 1.2 0)
			(layer "F.Fab")
			(effects
				(font
					(size 0.7 0.7)
					(thickness 0.15)
				)
				(justify left bottom)
			)
		)
		(property "Description" "SMT test point"
			(at 0 0 0)
			(layer "F.Fab")
			(hide yes)
			(effects
				(font
					(size 1.27 1.27)
					(thickness 0.15)
				)
			)
		)
		(property "Author" "Antmicro"
			(at 0 0 0)
			(layer "F.Fab")
			(hide yes)
			(effects
				(font
					(size 1 1)
					(thickness 0.15)
				)
			)
		)
		(property "License" "Apache-2.0"
			(at 0 0 0)
			(layer "F.Fab")
			(hide yes)
			(effects
				(font
					(size 1 1)
					(thickness 0.15)
				)
			)
		)
		(property "MPN" ""
			(at 0 0 0)
			(layer "F.Fab")
			(hide yes)
			(effects
				(font
					(size 1 1)
					(thickness 0.15)
				)
			)
		)
		(property "Manufacturer" ""
			(at 0 0 0)
			(layer "F.Fab")
			(hide yes)
			(effects
				(font
					(size 1 1)
					(thickness 0.15)
				)
			)
		)
		(sheetname "/Connectors/")
		(sheetfile "connectors.kicad_sch")
		(fp_circle
			(center 0 0)
			(end 0.475 0)
			(stroke
				(width 0.05)
				(type default)
			)
			(fill no)
			(layer "F.CrtYd")
		)
		(pad "1" smd circle
			(at 0 0)
			(size 0.75 0.75)
			(layers "F.Cu" "F.Mask")
			(net 2 "/Connectors/DC_UNFUSED")
			(pinfunction "1")
			(pintype "passive")
		)
	)
	(footprint "antmicro-footprints:LED_0603_1608Metric_G"
		(layer "F.Cu")
		(at 146.3 96.09 90)
		(descr "LED SMD 0603 Green")
		(tags "LED SMD 0603 Green")
		(property "Reference" "D19"
			(at 5.41111 -27.883333 180)
			(layer "F.SilkS")
			(effects
				(font
					(size 0.7 0.7)
					(thickness 0.15)
				)
				(justify right bottom)
			)
		)
		(property "Value" "LED_G_0603_LTST-C190GKT"
			(at -0.001 1.599 90)
			(layer "F.Fab")
			(effects
				(font
					(size 0.7 0.7)
					(thickness 0.15)
				)
				(justify left bottom)
			)
		)
		(property "Datasheet" "https://media.digikey.com/pdf/Data%20Sheets/Lite-On%20PDFs/LTST-C190GKT.pdf"
			(at 0 0 90)
			(layer "F.Fab")
			(hide yes)
			(effects
				(font
					(size 1.27 1.27)
					(thickness 0.15)
				)
			)
		)
		(property "Description" "LED, Green, SMD, 0603, 20 mA, 2.1 V, 569 nm"
			(at 0 0 90)
			(layer "F.Fab")
			(hide yes)
			(effects
				(font
					(size 1.27 1.27)
					(thickness 0.15)
				)
			)
		)
		(property "Author" "Antmicro"
			(at 242.39 -50.21 0)
			(layer "F.Fab")
			(hide yes)
			(effects
				(font
					(size 1 1)
					(thickness 0.15)
				)
			)
		)
		(property "Color" "Green"
			(at 242.39 -50.21 0)
			(layer "F.Fab")
			(hide yes)
			(effects
				(font
					(size 1 1)
					(thickness 0.15)
				)
			)
		)
		(property "License" "Apache-2.0"
			(at 242.39 -50.21 0)
			(layer "F.Fab")
			(hide yes)
			(effects
				(font
					(size 1 1)
					(thickness 0.15)
				)
			)
		)
		(property "MPN" "LTST-C190GKT"
			(at 242.39 -50.21 0)
			(layer "F.Fab")
			(hide yes)
			(effects
				(font
					(size 1 1)
					(thickness 0.15)
				)
			)
		)
		(property "Manufacturer" "Lite-On"
			(at 242.39 -50.21 0)
			(layer "F.Fab")
			(hide yes)
			(effects
				(font
					(size 1 1)
					(thickness 0.15)
				)
			)
		)
		(property "VSD_class" "LED"
			(at 242.39 -50.21 0)
			(layer "F.Fab")
			(hide yes)
			(effects
				(font
					(size 1 1)
					(thickness 0.15)
				)
			)
		)
		(sheetname "/Power/")
		(sheetfile "power.kicad_sch")
		(attr smd)
		(fp_line
			(start 0.22 -0.35)
			(end -0.22 -0.35)
			(stroke
				(width 0.15)
				(type solid)
			)
			(layer "F.SilkS")
		)
		(fp_line
			(start -1.18 -0.319)
			(end -1.18 0.321)
			(stroke
				(width 0.15)
				(type solid)
			)
			(layer "F.SilkS")
		)
		(fp_line
			(start 0.105328 0.001008)
			(end 0.24 0.001)
			(stroke
				(width 0.1)
				(type solid)
			)
			(layer "F.SilkS")
		)
		(fp_line
			(start -0.094672 0.001008)
			(end 0.105328 -0.198992)
			(stroke
				(width 0.1)
				(type solid)
			)
			(layer "F.SilkS")
		)
		(fp_line
			(start -0.094672 0.001008)
			(end -0.24 0.001008)
			(stroke
				(width 0.1)
				(type solid)
			)
			(layer "F.SilkS")
		)
		(fp_line
			(start 0.105328 0.201008)
			(end 0.105328 -0.198992)
			(stroke
				(width 0.1)
				(type solid)
			)
			(layer "F.SilkS")
		)
		(fp_line
			(start 0.105328 0.201008)
			(end -0.094672 0.001008)
			(stroke
				(width 0.1)
				(type solid)
			)
			(layer "F.SilkS")
		)
		(fp_line
			(start -0.094672 0.201008)
			(end -0.094672 -0.198992)
			(stroke
				(width 0.1)
				(type solid)
			)
			(layer "F.SilkS")
		)
		(fp_line
			(start 0.22 0.35)
			(end -0.22 0.35)
			(stroke
				(width 0.15)
				(type solid)
			)
			(layer "F.SilkS")
		)
		(fp_rect
			(start 1.25 0.65)
			(end -1.25 -0.65)
			(stroke
				(width 0.05)
				(type solid)
			)
			(fill no)
			(layer "F.CrtYd")
		)
		(fp_line
			(start 0.201 -0.202)
			(end -0.101 0)
			(stroke
				(width 0.15)
				(type solid)
			)
			(layer "F.Fab")
		)
		(fp_line
			(start -0.199 -0.202)
			(end -0.199 0.1)
			(stroke
				(width 0.15)
				(type solid)
			)
			(layer "F.Fab")
		)
		(fp_line
			(start 0.599 0)
			(end 0.201 0)
			(stroke
				(width 0.15)
				(type solid)
			)
			(layer "F.Fab")
		)
		(fp_line
			(start 0.201 0)
			(end 0.201 -0.202)
			(stroke
				(width 0.15)
				(type solid)
			)
			(layer "F.Fab")
		)
		(fp_line
			(start -0.101 0)
			(end 0.201 0.2)
			(stroke
				(width 0.15)
				(type solid)
			)
			(layer "F.Fab")
		)
		(fp_line
			(start -0.199 0)
			(end -0.597 0)
			(stroke
				(width 0.15)
				(type solid)
			)
			(layer "F.Fab")
		)
		(fp_line
			(start 0.201 0.2)
			(end 0.201 0)
			(stroke
				(width 0.15)
				(type solid)
			)
			(layer "F.Fab")
		)
		(fp_line
			(start -0.199 0.2)
			(end -0.199 0.1)
			(stroke
				(width 0.15)
				(type solid)
			)
			(layer "F.Fab")
		)
		(fp_rect
			(start 0.848 0.4)
			(end -0.85 -0.402)
			(stroke
				(width 0.15)
				(type solid)
			)
			(fill no)
			(layer "F.Fab")
		)
		(pad "1" smd roundrect
			(at -0.7 0 270)
			(size 0.8 1)
			(layers "F.Cu" "F.Mask" "F.Paste")
			(roundrect_rratio 0.2)
			(net 143 "Net-(D19-C)")
			(pinfunction "C")
			(pintype "passive")
		)
		(pad "2" smd roundrect
			(at 0.7 0 270)
			(size 0.8 1)
			(layers "F.Cu" "F.Mask" "F.Paste")
			(roundrect_rratio 0.2)
			(net 144 "Net-(D19-A)")
			(pinfunction "A")
			(pintype "passive")
		)
	)
	(footprint "antmicro-footprints:C_0402_1005Metric"
		(layer "F.Cu")
		(at 151.892 75.438 45)
		(descr "Capacitor SMD 0402")
		(tags "capacitor SMD 0402")
		(property "Reference" "C34"
			(at 4.003639 0.193747 45)
			(layer "F.SilkS")
			(effects
				(font
					(size 0.7 0.7)
					(thickness 0.15)
				)
				(justify left bottom)
			)
		)
		(property "Value" "C_100n_0402"
			(at -1.022927 2.155213 45)
			(layer "F.Fab")
			(effects
				(font
					(size 0.7 0.7)
					(thickness 0.15)
				)
				(justify left bottom)
			)
		)
		(property "Datasheet" "https://www.murata.com/products/productdetail?partno=GRM155R61H104KE14%23"
			(at 0 0 45)
			(layer "F.Fab")
			(hide yes)
			(effects
				(font
					(size 1.27 1.27)
					(thickness 0.15)
				)
			)
		)
		(property "Description" "SMD Multilayer Ceramic Capacitor, 0.1 µF, 50 V, 0402 [1005 Metric], ± 10%, X5R, GRM Series"
			(at 0 0 45)
			(layer "F.Fab")
			(hide yes)
			(effects
				(font
					(size 1.27 1.27)
					(thickness 0.15)
				)
			)
		)
		(property "Author" "Antmicro"
			(at 97.830859 -85.308584 0)
			(layer "F.Fab")
			(hide yes)
			(effects
				(font
					(size 1 1)
					(thickness 0.15)
				)
			)
		)
		(property "Dielectric" "X5R"
			(at 97.830859 -85.308584 0)
			(layer "F.Fab")
			(hide yes)
			(effects
				(font
					(size 1 1)
					(thickness 0.15)
				)
			)
		)
		(property "License" "Apache-2.0"
			(at 97.830859 -85.308584 0)
			(layer "F.Fab")
			(hide yes)
			(effects
				(font
					(size 1 1)
					(thickness 0.15)
				)
			)
		)
		(property "MPN" "GRM155R61H104KE14D"
			(at 97.830859 -85.308584 0)
			(layer "F.Fab")
			(hide yes)
			(effects
				(font
					(size 1 1)
					(thickness 0.15)
				)
			)
		)
		(property "Manufacturer" "Murata"
			(at 97.830859 -85.308584 0)
			(layer "F.Fab")
			(hide yes)
			(effects
				(font
					(size 1 1)
					(thickness 0.15)
				)
			)
		)
		(property "Val" "100n"
			(at 97.830859 -85.308584 0)
			(layer "F.Fab")
			(hide yes)
			(effects
				(font
					(size 1 1)
					(thickness 0.15)
				)
			)
		)
		(property "Voltage" "50V"
			(at 97.830859 -85.308584 0)
			(layer "F.Fab")
			(hide yes)
			(effects
				(font
					(size 1 1)
					(thickness 0.15)
				)
			)
		)
		(sheetname "/Deserializer/")
		(sheetfile "deserializer.kicad_sch")
		(attr smd)
		(fp_poly
			(pts
				(xy -0.925 -0.47) (xy 0.925 -0.47) (xy 0.925 0.47) (xy -0.925 0.47)
			)
			(stroke
				(width 0.05)
				(type default)
			)
			(fill no)
			(layer "F.CrtYd")
		)
		(fp_line
			(start -0.494 -0.25)
			(end 0.504 -0.25)
			(stroke
				(width 0.15)
				(type solid)
			)
			(layer "F.Fab")
		)
		(fp_line
			(start -0.494 0.248)
			(end -0.494 -0.25)
			(stroke
				(width 0.15)
				(type solid)
			)
			(layer "F.Fab")
		)
		(fp_line
			(start 0.504 -0.25)
			(end 0.504 0.248)
			(stroke
				(width 0.15)
				(type solid)
			)
			(layer "F.Fab")
		)
		(fp_line
			(start 0.504 0.248)
			(end -0.494 0.248)
			(stroke
				(width 0.15)
				(type solid)
			)
			(layer "F.Fab")
		)
		(pad "1" smd roundrect
			(at -0.48 0 45)
			(size 0.59 0.64)
			(layers "F.Cu" "F.Mask" "F.Paste")
			(roundrect_rratio 0.25)
			(net 22 "/Deserializer/SIOC_N")
			(pintype "passive")
		)
		(pad "2" smd roundrect
			(at 0.48 0 45)
			(size 0.59 0.64)
			(layers "F.Cu" "F.Mask" "F.Paste")
			(roundrect_rratio 0.25)
			(net 23 "Net-(C34-Pad2)")
			(pintype "passive")
		)
	)
	(footprint "antmicro-footprints:C_0402_1005Metric"
		(layer "F.Cu")
		(at 120.832 85.956 -90)
		(descr "Capacitor SMD 0402")
		(tags "capacitor SMD 0402")
		(property "Reference" "C20"
			(at -0.205238 0.614176 90)
			(layer "F.SilkS")
			(effects
				(font
					(size 0.7 0.7)
					(thickness 0.15)
				)
				(justify right bottom)
			)
		)
		(property "Value" "C_100n_0402"
			(at -1.022927 2.155213 90)
			(layer "F.Fab")
			(effects
				(font
					(size 0.7 0.7)
					(thickness 0.15)
				)
				(justify right bottom)
			)
		)
		(property "Datasheet" "https://www.murata.com/products/productdetail?partno=GRM155R61H104KE14%23"
			(at 0 0 270)
			(layer "F.Fab")
			(hide yes)
			(effects
				(font
					(size 1.27 1.27)
					(thickness 0.15)
				)
			)
		)
		(property "Description" "SMD Multilayer Ceramic Capacitor, 0.1 µF, 50 V, 0402 [1005 Metric], ± 10%, X5R, GRM Series"
			(at 0 0 270)
			(layer "F.Fab")
			(hide yes)
			(effects
				(font
					(size 1.27 1.27)
					(thickness 0.15)
				)
			)
		)
		(property "Author" "Antmicro"
			(at 34.876 206.788 0)
			(layer "F.Fab")
			(hide yes)
			(effects
				(font
					(size 1 1)
					(thickness 0.15)
				)
			)
		)
		(property "Dielectric" "X5R"
			(at 34.876 206.788 0)
			(layer "F.Fab")
			(hide yes)
			(effects
				(font
					(size 1 1)
					(thickness 0.15)
				)
			)
		)
		(property "License" "Apache-2.0"
			(at 34.876 206.788 0)
			(layer "F.Fab")
			(hide yes)
			(effects
				(font
					(size 1 1)
					(thickness 0.15)
				)
			)
		)
		(property "MPN" "GRM155R61H104KE14D"
			(at 34.876 206.788 0)
			(layer "F.Fab")
			(hide yes)
			(effects
				(font
					(size 1 1)
					(thickness 0.15)
				)
			)
		)
		(property "Manufacturer" "Murata"
			(at 34.876 206.788 0)
			(layer "F.Fab")
			(hide yes)
			(effects
				(font
					(size 1 1)
					(thickness 0.15)
				)
			)
		)
		(property "Val" "100n"
			(at 34.876 206.788 0)
			(layer "F.Fab")
			(hide yes)
			(effects
				(font
					(size 1 1)
					(thickness 0.15)
				)
			)
		)
		(property "Voltage" "50V"
			(at 34.876 206.788 0)
			(layer "F.Fab")
			(hide yes)
			(effects
				(font
					(size 1 1)
					(thickness 0.15)
				)
			)
		)
		(sheetname "/Power/")
		(sheetfile "power.kicad_sch")
		(attr smd)
		(fp_rect
			(start -0.925 -0.47)
			(end 0.925 0.47)
			(stroke
				(width 0.05)
				(type default)
			)
			(fill no)
			(layer "F.CrtYd")
		)
		(fp_line
			(start -0.494 0.248)
			(end -0.494 -0.25)
			(stroke
				(width 0.15)
				(type solid)
			)
			(layer "F.Fab")
		)
		(fp_line
			(start 0.504 0.248)
			(end -0.494 0.248)
			(stroke
				(width 0.15)
				(type solid)
			)
			(layer "F.Fab")
		)
		(fp_line
			(start -0.494 -0.25)
			(end 0.504 -0.25)
			(stroke
				(width 0.15)
				(type solid)
			)
			(layer "F.Fab")
		)
		(fp_line
			(start 0.504 -0.25)
			(end 0.504 0.248)
			(stroke
				(width 0.15)
				(type solid)
			)
			(layer "F.Fab")
		)
		(pad "1" smd roundrect
			(at -0.48 0 270)
			(size 0.59 0.64)
			(layers "F.Cu" "F.Mask" "F.Paste")
			(roundrect_rratio 0.25)
			(net 8 "Net-(U5-BST)")
			(pintype "passive")
		)
		(pad "2" smd roundrect
			(at 0.48 0 270)
			(size 0.59 0.64)
			(layers "F.Cu" "F.Mask" "F.Paste")
			(roundrect_rratio 0.25)
			(net 9 "/Power/SW_1V2")
			(pintype "passive")
		)
	)
	(footprint "antmicro-footprints:R_0402_1005Metric"
		(layer "F.Cu")
		(at 170.18 64.135 90)
		(descr "Resistor SMD 0402")
		(tags "resistor SMD 0402")
		(property "Reference" "R2"
			(at -2.248717 0.3475 90)
			(layer "F.SilkS")
			(effects
				(font
					(size 0.7 0.7)
					(thickness 0.15)
				)
				(justify left bottom)
			)
		)
		(property "Value" "R_0R_0402"
			(at -1.011843 1.772047 90)
			(layer "F.Fab")
			(effects
				(font
					(size 0.7 0.7)
					(thickness 0.15)
				)
				(justify left bottom)
			)
		)
		(property "Datasheet" "https://industrial.panasonic.com/cdbs/www-data/pdf/RDA0000/AOA0000C301.pdf"
			(at 0 0 90)
			(layer "F.Fab")
			(hide yes)
			(effects
				(font
					(size 1.27 1.27)
					(thickness 0.15)
				)
			)
		)
		(property "Description" "SMD Chip Resistor, Jumper, 0 ohm, 100 mW, 0402 [1005 Metric], Thick Film, General Purpose"
			(at 0 0 90)
			(layer "F.Fab")
			(hide yes)
			(effects
				(font
					(size 1.27 1.27)
					(thickness 0.15)
				)
			)
		)
		(property "Author" "Antmicro"
			(at 234.315 -106.045 0)
			(layer "F.Fab")
			(hide yes)
			(effects
				(font
					(size 1 1)
					(thickness 0.15)
				)
			)
		)
		(property "Current" "1A"
			(at 234.315 -106.045 0)
			(layer "F.Fab")
			(hide yes)
			(effects
				(font
					(size 1 1)
					(thickness 0.15)
				)
			)
		)
		(property "License" "Apache-2.0"
			(at 234.315 -106.045 0)
			(layer "F.Fab")
			(hide yes)
			(effects
				(font
					(size 1 1)
					(thickness 0.15)
				)
			)
		)
		(property "MPN" "ERJ2GE0R00X"
			(at 234.315 -106.045 0)
			(layer "F.Fab")
			(hide yes)
			(effects
				(font
					(size 1 1)
					(thickness 0.15)
				)
			)
		)
		(property "Manufacturer" "Panasonic"
			(at 234.315 -106.045 0)
			(layer "F.Fab")
			(hide yes)
			(effects
				(font
					(size 1 1)
					(thickness 0.15)
				)
			)
		)
		(property "Tolerance" ""
			(at 234.315 -106.045 0)
			(layer "F.Fab")
			(hide yes)
			(effects
				(font
					(size 1 1)
					(thickness 0.15)
				)
			)
		)
		(property "Val" "0R"
			(at 234.315 -106.045 0)
			(layer "F.Fab")
			(hide yes)
			(effects
				(font
					(size 1 1)
					(thickness 0.15)
				)
			)
		)
		(sheetname "/Connectors/")
		(sheetfile "connectors.kicad_sch")
		(attr smd)
		(fp_rect
			(start -0.925 -0.47)
			(end 0.925 0.47)
			(stroke
				(width 0.05)
				(type default)
			)
			(fill no)
			(layer "F.CrtYd")
		)
		(fp_rect
			(start -0.5 -0.25)
			(end 0.5 0.25)
			(stroke
				(width 0.15)
				(type solid)
			)
			(fill no)
			(layer "F.Fab")
		)
		(pad "1" smd roundrect
			(at -0.48 0 90)
			(size 0.59 0.64)
			(layers "F.Cu" "F.Mask" "F.Paste")
			(roundrect_rratio 0.25)
			(net 80 "/Connectors/MFP0")
			(pintype "passive")
		)
		(pad "2" smd roundrect
			(at 0.48 0 90)
			(size 0.59 0.64)
			(layers "F.Cu" "F.Mask" "F.Paste")
			(roundrect_rratio 0.25)
			(net 130 "Net-(U1-Y)")
			(pintype "passive")
		)
	)
	(footprint "antmicro-footprints:Conn_FFC_WE_68715014x22"
		(layer "F.Cu")
		(at 186.036 73.183 90)
		(property "Reference" "J6"
			(at -14.868 -2.902 90)
			(layer "F.SilkS")
			(effects
				(font
					(size 0.7 0.7)
					(thickness 0.15)
				)
				(justify left bottom)
			)
		)
		(property "Value" "Conn_FFC_WE_68715014522"
			(at 0 4.5 90)
			(layer "F.Fab")
			(effects
				(font
					(size 0.7 0.7)
					(thickness 0.15)
				)
				(justify left bottom)
			)
		)
		(property "Datasheet" "https://www.we-online.com/components/products/datasheet/68715014522.pdf"
			(at 0 0 90)
			(layer "F.Fab")
			(hide yes)
			(effects
				(font
					(size 1.27 1.27)
					(thickness 0.15)
				)
			)
		)
		(property "Description" "FFC connector"
			(at 0 0 90)
			(layer "F.Fab")
			(hide yes)
			(effects
				(font
					(size 1.27 1.27)
					(thickness 0.15)
				)
			)
		)
		(property "Author" "Antmicro"
			(at 259.219 -112.853 0)
			(layer "F.Fab")
			(hide yes)
			(effects
				(font
					(size 1 1)
					(thickness 0.15)
				)
			)
		)
		(property "License" "Apache-2.0"
			(at 259.219 -112.853 0)
			(layer "F.Fab")
			(hide yes)
			(effects
				(font
					(size 1 1)
					(thickness 0.15)
				)
			)
		)
		(property "MPN" "68715014522"
			(at 259.219 -112.853 0)
			(layer "F.Fab")
			(hide yes)
			(effects
				(font
					(size 1 1)
					(thickness 0.15)
				)
			)
		)
		(property "Manufacturer" "Würth Elektronik"
			(at 259.219 -112.853 0)
			(layer "F.Fab")
			(hide yes)
			(effects
				(font
					(size 1 1)
					(thickness 0.15)
				)
			)
		)
		(property "VSD_Class" "Antmicro Dual Camera interface"
			(at 259.219 -112.853 0)
			(layer "F.Fab")
			(hide yes)
			(effects
				(font
					(size 1 1)
					(thickness 0.15)
				)
			)
		)
		(sheetname "/Connectors/")
		(sheetfile "connectors.kicad_sch")
		(attr smd)
		(fp_line
			(start -12.5 -2.976)
			(end 12.499 -2.976)
			(stroke
				(width 0.15)
				(type solid)
			)
			(layer "F.SilkS")
		)
		(fp_line
			(start 15.85 -2.15)
			(end 12.499 -2.15)
			(stroke
				(width 0.15)
				(type solid)
			)
			(layer "F.SilkS")
		)
		(fp_line
			(start 12.499 -2.15)
			(end 12.499 -2.976)
			(stroke
				(width 0.15)
				(type solid)
			)
			(layer "F.SilkS")
		)
		(fp_line
			(start -12.5 -2.15)
			(end -12.5 -2.976)
			(stroke
				(width 0.15)
				(type solid)
			)
			(layer "F.SilkS")
		)
		(fp_line
			(start -15.85 -2.15)
			(end -12.5 -2.15)
			(stroke
				(width 0.15)
				(type solid)
			)
			(layer "F.SilkS")
		)
		(fp_line
			(start 15.85 2.7)
			(end 15.85 -2.15)
			(stroke
				(width 0.15)
				(type solid)
			)
			(layer "F.SilkS")
		)
		(fp_line
			(start 15.85 2.7)
			(end -15.85 2.7)
			(stroke
				(width 0.15)
				(type solid)
			)
			(layer "F.SilkS")
		)
		(fp_line
			(start -15.85 2.7)
			(end -15.85 -2.15)
			(stroke
				(width 0.15)
				(type solid)
			)
			(layer "F.SilkS")
		)
		(fp_circle
			(center -12.9 -2.9)
			(end -12.85 -2.85)
			(stroke
				(width 0.15)
				(type solid)
			)
			(fill yes)
			(layer "F.SilkS")
		)
		(fp_rect
			(start -16.2 -3.25)
			(end 16.2 3.55)
			(stroke
				(width 0.05)
				(type solid)
			)
			(fill no)
			(layer "F.CrtYd")
		)
		(pad "1" smd roundrect
			(at -12.25 -2.15 90)
			(size 0.3 1.2)
			(layers "F.Cu" "F.Mask" "F.Paste")
			(roundrect_rratio 0.25)
			(net 99 "/Connectors/CSI0.D3_N")
			(pintype "passive")
		)
		(pad "2" smd roundrect
			(at -11.75 -2.15 90)
			(size 0.3 1.2)
			(layers "F.Cu" "F.Mask" "F.Paste")
			(roundrect_rratio 0.25)
			(net 100 "/Connectors/CSI0.D3_P")
			(pintype "passive")
		)
		(pad "3" smd roundrect
			(at -11.25 -2.15 90)
			(size 0.3 1.2)
			(layers "F.Cu" "F.Mask" "F.Paste")
			(roundrect_rratio 0.25)
			(net 101 "/Connectors/CSI0.D2_N")
			(pintype "passive")
		)
		(pad "4" smd roundrect
			(at -10.75 -2.15 90)
			(size 0.3 1.2)
			(layers "F.Cu" "F.Mask" "F.Paste")
			(roundrect_rratio 0.25)
			(net 102 "/Connectors/CSI0.D2_P")
			(pintype "passive")
		)
		(pad "5" smd roundrect
			(at -10.25 -2.15 90)
			(size 0.3 1.2)
			(layers "F.Cu" "F.Mask" "F.Paste")
			(roundrect_rratio 0.25)
			(net 89 "/Connectors/CSI0.D1_N")
			(pintype "passive")
		)
		(pad "6" smd roundrect
			(at -9.75 -2.15 90)
			(size 0.3 1.2)
			(layers "F.Cu" "F.Mask" "F.Paste")
			(roundrect_rratio 0.25)
			(net 90 "/Connectors/CSI0.D1_P")
			(pintype "passive")
		)
		(pad "7" smd roundrect
			(at -9.25 -2.15 90)
			(size 0.3 1.2)
			(layers "F.Cu" "F.Mask" "F.Paste")
			(roundrect_rratio 0.25)
			(net 91 "/Connectors/CSI0.D0_N")
			(pintype "passive")
		)
		(pad "8" smd roundrect
			(at -8.75 -2.15 90)
			(size 0.3 1.2)
			(layers "F.Cu" "F.Mask" "F.Paste")
			(roundrect_rratio 0.25)
			(net 92 "/Connectors/CSI0.D0_P")
			(pintype "passive")
		)
		(pad "9" smd roundrect
			(at -8.25 -2.15 90)
			(size 0.3 1.2)
			(layers "F.Cu" "F.Mask" "F.Paste")
			(roundrect_rratio 0.25)
			(net 1 "GND")
			(pintype "passive")
		)
		(pad "10" smd roundrect
			(at -7.75 -2.15 90)
			(size 0.3 1.2)
			(layers "F.Cu" "F.Mask" "F.Paste")
			(roundrect_rratio 0.25)
			(net 103 "/Connectors/CSI0.CLK_N")
			(pintype "passive")
		)
		(pad "11" smd roundrect
			(at -7.25 -2.15 90)
			(size 0.3 1.2)
			(layers "F.Cu" "F.Mask" "F.Paste")
			(roundrect_rratio 0.25)
			(net 104 "/Connectors/CSI0.CLK_P")
			(pintype "passive")
		)
		(pad "12" smd roundrect
			(at -6.75 -2.15 90)
			(size 0.3 1.2)
			(layers "F.Cu" "F.Mask" "F.Paste")
			(roundrect_rratio 0.25)
			(net 1 "GND")
			(pintype "passive")
		)
		(pad "13" smd roundrect
			(at -6.25 -2.15 90)
			(size 0.3 1.2)
			(layers "F.Cu" "F.Mask" "F.Paste")
			(roundrect_rratio 0.25)
			(net 30 "unconnected-(J6-Pad13)")
			(pintype "passive+no_connect")
		)
		(pad "14" smd roundrect
			(at -5.75 -2.15 90)
			(size 0.3 1.2)
			(layers "F.Cu" "F.Mask" "F.Paste")
			(roundrect_rratio 0.25)
			(net 31 "unconnected-(J6-Pad14)")
			(pintype "passive+no_connect")
		)
		(pad "15" smd roundrect
			(at -5.25 -2.15 90)
			(size 0.3 1.2)
			(layers "F.Cu" "F.Mask" "F.Paste")
			(roundrect_rratio 0.25)
			(net 1 "GND")
			(pintype "passive")
		)
		(pad "16" smd roundrect
			(at -4.75 -2.15 90)
			(size 0.3 1.2)
			(layers "F.Cu" "F.Mask" "F.Paste")
			(roundrect_rratio 0.25)
			(net 32 "unconnected-(J6-Pad16)")
			(pintype "passive+no_connect")
		)
		(pad "17" smd roundrect
			(at -4.25 -2.15 90)
			(size 0.3 1.2)
			(layers "F.Cu" "F.Mask" "F.Paste")
			(roundrect_rratio 0.25)
			(net 33 "unconnected-(J6-Pad17)")
			(pintype "passive+no_connect")
		)
		(pad "18" smd roundrect
			(at -3.75 -2.15 90)
			(size 0.3 1.2)
			(layers "F.Cu" "F.Mask" "F.Paste")
			(roundrect_rratio 0.25)
			(net 1 "GND")
			(pintype "passive")
		)
		(pad "19" smd roundrect
			(at -3.25 -2.15 90)
			(size 0.3 1.2)
			(layers "F.Cu" "F.Mask" "F.Paste")
			(roundrect_rratio 0.25)
			(net 105 "/Connectors/CSI1.D3_N")
			(pintype "passive")
		)
		(pad "20" smd roundrect
			(at -2.75 -2.15 90)
			(size 0.3 1.2)
			(layers "F.Cu" "F.Mask" "F.Paste")
			(roundrect_rratio 0.25)
			(net 106 "/Connectors/CSI1.D3_P")
			(pintype "passive")
		)
		(pad "21" smd roundrect
			(at -2.25 -2.15 90)
			(size 0.3 1.2)
			(layers "F.Cu" "F.Mask" "F.Paste")
			(roundrect_rratio 0.25)
			(net 107 "/Connectors/CSI1.D2_N")
			(pintype "passive")
		)
		(pad "22" smd roundrect
			(at -1.75 -2.15 90)
			(size 0.3 1.2)
			(layers "F.Cu" "F.Mask" "F.Paste")
			(roundrect_rratio 0.25)
			(net 108 "/Connectors/CSI1.D2_P")
			(pintype "passive")
		)
		(pad "23" smd roundrect
			(at -1.25 -2.15 90)
			(size 0.3 1.2)
			(layers "F.Cu" "F.Mask" "F.Paste")
			(roundrect_rratio 0.25)
			(net 93 "/Connectors/CSI1.D1_N")
			(pintype "passive")
		)
		(pad "24" smd roundrect
			(at -0.75 -2.15 90)
			(size 0.3 1.2)
			(layers "F.Cu" "F.Mask" "F.Paste")
			(roundrect_rratio 0.25)
			(net 94 "/Connectors/CSI1.D1_P")
			(pintype "passive")
		)
		(pad "25" smd roundrect
			(at -0.25 -2.15 90)
			(size 0.3 1.2)
			(layers "F.Cu" "F.Mask" "F.Paste")
			(roundrect_rratio 0.25)
			(net 95 "/Connectors/CSI1.D0_N")
			(pintype "passive")
		)
		(pad "26" smd roundrect
			(at 0.248 -2.15 90)
			(size 0.3 1.2)
			(layers "F.Cu" "F.Mask" "F.Paste")
			(roundrect_rratio 0.25)
			(net 96 "/Connectors/CSI1.D0_P")
			(pintype "passive")
		)
		(pad "27" smd roundrect
			(at 0.748 -2.15 90)
			(size 0.3 1.2)
			(layers "F.Cu" "F.Mask" "F.Paste")
			(roundrect_rratio 0.25)
			(net 1 "GND")
			(pintype "passive")
		)
		(pad "28" smd roundrect
			(at 1.249 -2.15 90)
			(size 0.3 1.2)
			(layers "F.Cu" "F.Mask" "F.Paste")
			(roundrect_rratio 0.25)
			(net 97 "/Connectors/CSI1.CLK_N")
			(pintype "passive")
		)
		(pad "29" smd roundrect
			(at 1.749 -2.15 90)
			(size 0.3 1.2)
			(layers "F.Cu" "F.Mask" "F.Paste")
			(roundrect_rratio 0.25)
			(net 98 "/Connectors/CSI1.CLK_P")
			(pintype "passive")
		)
		(pad "30" smd roundrect
			(at 2.249 -2.15 90)
			(size 0.3 1.2)
			(layers "F.Cu" "F.Mask" "F.Paste")
			(roundrect_rratio 0.25)
			(net 1 "GND")
			(pintype "passive")
		)
		(pad "31" smd roundrect
			(at 2.749 -2.15 90)
			(size 0.3 1.2)
			(layers "F.Cu" "F.Mask" "F.Paste")
			(roundrect_rratio 0.25)
			(net 34 "unconnected-(J6-Pad31)")
			(pintype "passive+no_connect")
		)
		(pad "32" smd roundrect
			(at 3.249 -2.15 90)
			(size 0.3 1.2)
			(layers "F.Cu" "F.Mask" "F.Paste")
			(roundrect_rratio 0.25)
			(net 35 "Net-(J6-Pad32)")
			(pintype "passive")
		)
		(pad "33" smd roundrect
			(at 3.749 -2.15 90)
			(size 0.3 1.2)
			(layers "F.Cu" "F.Mask" "F.Paste")
			(roundrect_rratio 0.25)
			(net 36 "unconnected-(J6-Pad33)")
			(pintype "passive+no_connect")
		)
		(pad "34" smd roundrect
			(at 4.248 -2.15 90)
			(size 0.3 1.2)
			(layers "F.Cu" "F.Mask" "F.Paste")
			(roundrect_rratio 0.25)
			(net 37 "Net-(J6-Pad34)")
			(pintype "passive")
		)
		(pad "35" smd roundrect
			(at 4.748 -2.15 90)
			(size 0.3 1.2)
			(layers "F.Cu" "F.Mask" "F.Paste")
			(roundrect_rratio 0.25)
			(net 38 "unconnected-(J6-Pad35)")
			(pintype "passive+no_connect")
		)
		(pad "36" smd roundrect
			(at 5.248 -2.15 90)
			(size 0.3 1.2)
			(layers "F.Cu" "F.Mask" "F.Paste")
			(roundrect_rratio 0.25)
			(net 39 "unconnected-(J6-Pad36)")
			(pintype "passive+no_connect")
		)
		(pad "37" smd roundrect
			(at 5.749 -2.15 90)
			(size 0.3 1.2)
			(layers "F.Cu" "F.Mask" "F.Paste")
			(roundrect_rratio 0.25)
			(net 40 "unconnected-(J6-Pad37)")
			(pintype "passive+no_connect")
		)
		(pad "38" smd roundrect
			(at 6.249 -2.15 90)
			(size 0.3 1.2)
			(layers "F.Cu" "F.Mask" "F.Paste")
			(roundrect_rratio 0.25)
			(net 41 "unconnected-(J6-Pad38)")
			(pintype "passive+no_connect")
		)
		(pad "39" smd roundrect
			(at 6.749 -2.15 90)
			(size 0.3 1.2)
			(layers "F.Cu" "F.Mask" "F.Paste")
			(roundrect_rratio 0.25)
			(net 119 "/Connectors/SDA_CAM0")
			(pintype "passive")
		)
		(pad "40" smd roundrect
			(at 7.249 -2.15 90)
			(size 0.3 1.2)
			(layers "F.Cu" "F.Mask" "F.Paste")
			(roundrect_rratio 0.25)
			(net 120 "/Connectors/SCL_CAM0")
			(pintype "passive")
		)
		(pad "41" smd roundrect
			(at 7.749 -2.15 90)
			(size 0.3 1.2)
			(layers "F.Cu" "F.Mask" "F.Paste")
			(roundrect_rratio 0.25)
			(net 42 "/Connectors/SDA_CAM1")
			(pintype "passive")
		)
		(pad "42" smd roundrect
			(at 8.249 -2.15 90)
			(size 0.3 1.2)
			(layers "F.Cu" "F.Mask" "F.Paste")
			(roundrect_rratio 0.25)
			(net 43 "/Connectors/SCL_CAM1")
			(pintype "passive")
		)
		(pad "43" smd roundrect
			(at 8.749 -2.15 90)
			(size 0.3 1.2)
			(layers "F.Cu" "F.Mask" "F.Paste")
			(roundrect_rratio 0.25)
			(net 46 "unconnected-(J6-Pad43)")
			(pintype "passive+no_connect")
		)
		(pad "44" smd roundrect
			(at 9.249 -2.15 90)
			(size 0.3 1.2)
			(layers "F.Cu" "F.Mask" "F.Paste")
			(roundrect_rratio 0.25)
			(net 47 "unconnected-(J6-Pad44)")
			(pintype "passive+no_connect")
		)
		(pad "45" smd roundrect
			(at 9.749 -2.15 90)
			(size 0.3 1.2)
			(layers "F.Cu" "F.Mask" "F.Paste")
			(roundrect_rratio 0.25)
			(net 48 "unconnected-(J6-Pad45)")
			(pintype "passive+no_connect")
		)
		(pad "46" smd roundrect
			(at 10.249 -2.15 90)
			(size 0.3 1.2)
			(layers "F.Cu" "F.Mask" "F.Paste")
			(roundrect_rratio 0.25)
			(net 49 "unconnected-(J6-Pad46)")
			(pintype "passive+no_connect")
		)
		(pad "47" smd roundrect
			(at 10.749 -2.15 90)
			(size 0.3 1.2)
			(layers "F.Cu" "F.Mask" "F.Paste")
			(roundrect_rratio 0.25)
			(net 50 "/Connectors/FFC_3V3")
			(pintype "passive")
		)
		(pad "48" smd roundrect
			(at 11.249 -2.15 90)
			(size 0.3 1.2)
			(layers "F.Cu" "F.Mask" "F.Paste")
			(roundrect_rratio 0.25)
			(net 50 "/Connectors/FFC_3V3")
			(pintype "passive")
		)
		(pad "49" smd roundrect
			(at 11.749 -2.15 90)
			(size 0.3 1.2)
			(layers "F.Cu" "F.Mask" "F.Paste")
			(roundrect_rratio 0.25)
			(net 113 "/Connectors/FFC_5V")
			(pintype "passive")
		)
		(pad "50" smd roundrect
			(at 12.249 -2.15 90)
			(size 0.3 1.2)
			(layers "F.Cu" "F.Mask" "F.Paste")
			(roundrect_rratio 0.25)
			(net 113 "/Connectors/FFC_5V")
			(pintype "passive")
		)
		(pad "MP1" smd roundrect
			(at -14.198 -0.3 90)
			(size 2.7 3)
			(layers "F.Cu" "F.Mask" "F.Paste")
			(roundrect_rratio 0.05)
			(net 1 "GND")
			(pinfunction "MP")
			(pintype "passive")
		)
		(pad "MP2" smd roundrect
			(at 14.198 -0.3 90)
			(size 2.7 3)
			(layers "F.Cu" "F.Mask" "F.Paste")
			(roundrect_rratio 0.05)
			(net 1 "GND")
			(pinfunction "MP")
			(pintype "passive")
		)
	)
	(footprint "antmicro-footprints:C_0603_1608Metric"
		(layer "F.Cu")
		(at 131.725 95.618 -90)
		(descr "Capacitor SMD 0603")
		(tags "capacitor 0603")
		(property "Reference" "C17"
			(at -1.638 0.915 90)
			(layer "F.SilkS")
			(effects
				(font
					(size 0.7 0.7)
					(thickness 0.15)
				)
				(justify right bottom)
			)
		)
		(property "Value" "C_10u_25V_0603"
			(at -1.42757 1.770288 90)
			(layer "F.Fab")
			(effects
				(font
					(size 0.7 0.7)
					(thickness 0.15)
				)
				(justify right bottom)
			)
		)
		(property "Datasheet" "https://product.tdk.com/en/search/capacitor/ceramic/mlcc/info?part_no=C1608X5R1E106M080AC"
			(at 0 0 270)
			(layer "F.Fab")
			(hide yes)
			(effects
				(font
					(size 1.27 1.27)
					(thickness 0.15)
				)
			)
		)
		(property "Description" "SMD Multilayer Ceramic Capacitor, 10 µF, 25 V, 0603 [1608 Metric], ± 20%, X5R, C"
			(at 0 0 270)
			(layer "F.Fab")
			(hide yes)
			(effects
				(font
					(size 1.27 1.27)
					(thickness 0.15)
				)
			)
		)
		(property "Author" "Antmicro"
			(at 36.107 227.343 0)
			(layer "F.Fab")
			(hide yes)
			(effects
				(font
					(size 1 1)
					(thickness 0.15)
				)
			)
		)
		(property "Dielectric" ""
			(at 36.107 227.343 0)
			(layer "F.Fab")
			(hide yes)
			(effects
				(font
					(size 1 1)
					(thickness 0.15)
				)
			)
		)
		(property "License" "Apache-2.0"
			(at 36.107 227.343 0)
			(layer "F.Fab")
			(hide yes)
			(effects
				(font
					(size 1 1)
					(thickness 0.15)
				)
			)
		)
		(property "MPN" "C1608X5R1E106M080AC"
			(at 36.107 227.343 0)
			(layer "F.Fab")
			(hide yes)
			(effects
				(font
					(size 1 1)
					(thickness 0.15)
				)
			)
		)
		(property "Manufacturer" "TDK"
			(at 36.107 227.343 0)
			(layer "F.Fab")
			(hide yes)
			(effects
				(font
					(size 1 1)
					(thickness 0.15)
				)
			)
		)
		(property "Val" "10u"
			(at 36.107 227.343 0)
			(layer "F.Fab")
			(hide yes)
			(effects
				(font
					(size 1 1)
					(thickness 0.15)
				)
			)
		)
		(property "Voltage" "25V"
			(at 36.107 227.343 0)
			(layer "F.Fab")
			(hide yes)
			(effects
				(font
					(size 1 1)
					(thickness 0.15)
				)
			)
		)
		(sheetname "/Power/")
		(sheetfile "power.kicad_sch")
		(attr smd)
		(fp_line
			(start -0.15 0.4)
			(end 0.15 0.4)
			(stroke
				(width 0.15)
				(type solid)
			)
			(layer "F.SilkS")
		)
		(fp_line
			(start -0.15 -0.4)
			(end 0.15 -0.4)
			(stroke
				(width 0.15)
				(type solid)
			)
			(layer "F.SilkS")
		)
		(fp_rect
			(start -1.25 -0.65)
			(end 1.25 0.65)
			(stroke
				(width 0.05)
				(type solid)
			)
			(fill no)
			(layer "F.CrtYd")
		)
		(fp_rect
			(start -0.8 -0.4)
			(end 0.8 0.4)
			(stroke
				(width 0.15)
				(type solid)
			)
			(fill no)
			(layer "F.Fab")
		)
		(pad "1" smd roundrect
			(at -0.7 0 270)
			(size 0.8 1)
			(layers "F.Cu" "F.Mask" "F.Paste")
			(roundrect_rratio 0.2)
			(net 1 "GND")
			(pintype "passive")
		)
		(pad "2" smd roundrect
			(at 0.7 0 270)
			(size 0.8 1)
			(layers "F.Cu" "F.Mask" "F.Paste")
			(roundrect_rratio 0.2)
			(net 4 "+12V")
			(pintype "passive")
		)
	)
	(footprint "antmicro-footprints:R_0402_1005Metric"
		(layer "F.Cu")
		(at 169.418 55.753 90)
		(descr "Resistor SMD 0402")
		(tags "resistor SMD 0402")
		(property "Reference" "R4"
			(at 0.891453 0.244264 270)
			(layer "F.SilkS")
			(effects
				(font
					(size 0.7 0.7)
					(thickness 0.15)
				)
				(justify left bottom)
			)
		)
		(property "Value" "R_10k_0402"
			(at -1.011843 1.772047 90)
			(layer "F.Fab")
			(effects
				(font
					(size 0.7 0.7)
					(thickness 0.15)
				)
				(justify left bottom)
			)
		)
		(property "Datasheet" "https://www.bourns.com/docs/product-datasheets/cr.pdf"
			(at 0 0 90)
			(layer "F.Fab")
			(hide yes)
			(effects
				(font
					(size 1.27 1.27)
					(thickness 0.15)
				)
			)
		)
		(property "Description" "SMD Chip Resistor, 10 kohm, ± 1%, 62.5 mW, 0402 [1005 Metric], Thick Film, General Purpose"
			(at 0 0 90)
			(layer "F.Fab")
			(hide yes)
			(effects
				(font
					(size 1.27 1.27)
					(thickness 0.15)
				)
			)
		)
		(property "Author" "Antmicro"
			(at 225.171 -113.665 0)
			(layer "F.Fab")
			(hide yes)
			(effects
				(font
					(size 1 1)
					(thickness 0.15)
				)
			)
		)
		(property "License" "Apache-2.0"
			(at 225.171 -113.665 0)
			(layer "F.Fab")
			(hide yes)
			(effects
				(font
					(size 1 1)
					(thickness 0.15)
				)
			)
		)
		(property "MPN" "CR0402-FX-1002GLF"
			(at 225.171 -113.665 0)
			(layer "F.Fab")
			(hide yes)
			(effects
				(font
					(size 1 1)
					(thickness 0.15)
				)
			)
		)
		(property "Manufacturer" "Bourns"
			(at 225.171 -113.665 0)
			(layer "F.Fab")
			(hide yes)
			(effects
				(font
					(size 1 1)
					(thickness 0.15)
				)
			)
		)
		(property "Tolerance" "1%"
			(at 225.171 -113.665 0)
			(layer "F.Fab")
			(hide yes)
			(effects
				(font
					(size 1 1)
					(thickness 0.15)
				)
			)
		)
		(property "Val" "10k"
			(at 225.171 -113.665 0)
			(layer "F.Fab")
			(hide yes)
			(effects
				(font
					(size 1 1)
					(thickness 0.15)
				)
			)
		)
		(sheetname "/Connectors/")
		(sheetfile "connectors.kicad_sch")
		(attr smd)
		(fp_rect
			(start -0.925 -0.47)
			(end 0.925 0.47)
			(stroke
				(width 0.05)
				(type default)
			)
			(fill no)
			(layer "F.CrtYd")
		)
		(fp_rect
			(start -0.5 -0.25)
			(end 0.5 0.25)
			(stroke
				(width 0.15)
				(type solid)
			)
			(fill no)
			(layer "F.Fab")
		)
		(pad "1" smd roundrect
			(at -0.48 0 90)
			(size 0.59 0.64)
			(layers "F.Cu" "F.Mask" "F.Paste")
			(roundrect_rratio 0.25)
			(net 1 "GND")
			(pintype "passive")
		)
		(pad "2" smd roundrect
			(at 0.48 0 90)
			(size 0.59 0.64)
			(layers "F.Cu" "F.Mask" "F.Paste")
			(roundrect_rratio 0.25)
			(net 131 "Net-(U2-~{OE})")
			(pintype "passive")
		)
	)
	(footprint "antmicro-footprints:R_0402_1005Metric"
		(layer "F.Cu")
		(at 149.225 75.692 45)
		(descr "Resistor SMD 0402")
		(tags "resistor SMD 0402")
		(property "Reference" "R55"
			(at -1.185394 -0.395131 45)
			(layer "F.SilkS")
			(effects
				(font
					(size 0.7 0.7)
					(thickness 0.15)
				)
				(justify left bottom)
			)
		)
		(property "Value" "R_10k_0402"
			(at -1.011843 1.772046 45)
			(layer "F.Fab")
			(effects
				(font
					(size 0.7 0.7)
					(thickness 0.15)
				)
				(justify left bottom)
			)
		)
		(property "Datasheet" "https://www.bourns.com/docs/product-datasheets/cr.pdf"
			(at 0 0 45)
			(layer "F.Fab")
			(hide yes)
			(effects
				(font
					(size 1.27 1.27)
					(thickness 0.15)
				)
			)
		)
		(property "Description" "SMD Chip Resistor, 10 kohm, ± 1%, 62.5 mW, 0402 [1005 Metric], Thick Film, General Purpose"
			(at 0 0 45)
			(layer "F.Fab")
			(hide yes)
			(effects
				(font
					(size 1.27 1.27)
					(thickness 0.15)
				)
			)
		)
		(property "Author" "Antmicro"
			(at 97.229317 -83.348336 0)
			(layer "F.Fab")
			(hide yes)
			(effects
				(font
					(size 1 1)
					(thickness 0.15)
				)
			)
		)
		(property "License" "Apache-2.0"
			(at 97.229317 -83.348336 0)
			(layer "F.Fab")
			(hide yes)
			(effects
				(font
					(size 1 1)
					(thickness 0.15)
				)
			)
		)
		(property "MPN" "CR0402-FX-1002GLF"
			(at 97.229317 -83.348336 0)
			(layer "F.Fab")
			(hide yes)
			(effects
				(font
					(size 1 1)
					(thickness 0.15)
				)
			)
		)
		(property "Manufacturer" "Bourns"
			(at 97.229317 -83.348336 0)
			(layer "F.Fab")
			(hide yes)
			(effects
				(font
					(size 1 1)
					(thickness 0.15)
				)
			)
		)
		(property "Tolerance" "1%"
			(at 97.229317 -83.348336 0)
			(layer "F.Fab")
			(hide yes)
			(effects
				(font
					(size 1 1)
					(thickness 0.15)
				)
			)
		)
		(property "Val" "10k"
			(at 97.229317 -83.348336 0)
			(layer "F.Fab")
			(hide yes)
			(effects
				(font
					(size 1 1)
					(thickness 0.15)
				)
			)
		)
		(sheetname "/Deserializer/")
		(sheetfile "deserializer.kicad_sch")
		(attr smd)
		(fp_poly
			(pts
				(xy -0.925 -0.47) (xy 0.925 -0.47) (xy 0.925 0.47) (xy -0.925 0.47)
			)
			(stroke
				(width 0.05)
				(type default)
			)
			(fill no)
			(layer "F.CrtYd")
		)
		(fp_poly
			(pts
				(xy -0.5 -0.25) (xy 0.5 -0.25) (xy 0.5 0.25) (xy -0.5 0.25)
			)
			(stroke
				(width 0.15)
				(type solid)
			)
			(fill no)
			(layer "F.Fab")
		)
		(pad "1" smd roundrect
			(at -0.48 0 45)
			(size 0.59 0.64)
			(layers "F.Cu" "F.Mask" "F.Paste")
			(roundrect_rratio 0.25)
			(net 79 "/Deserializer/PWDNB")
			(pintype "passive")
		)
		(pad "2" smd roundrect
			(at 0.48 0 45)
			(size 0.59 0.64)
			(layers "F.Cu" "F.Mask" "F.Paste")
			(roundrect_rratio 0.25)
			(net 146 "VDDIO")
			(pintype "passive")
		)
	)
	(footprint "antmicro-footprints:L_Coilcraft-MSS6132T"
		(layer "F.Cu")
		(at 157.988 61.976 90)
		(property "Reference" "L4"
			(at -0.635 -3.531 90)
			(layer "F.SilkS")
			(effects
				(font
					(size 0.7 0.7)
					(thickness 0.15)
				)
				(justify left bottom)
			)
		)
		(property "Value" "L_22u_1.12A_Coilcraft-MSS6132T"
			(at -0.508 4.826 90)
			(layer "F.Fab")
			(effects
				(font
					(size 0.7 0.7)
					(thickness 0.15)
				)
				(justify left bottom)
			)
		)
		(property "Datasheet" "https://www.coilcraft.com/getmedia/d035c9b3-191d-46aa-ab3f-5c1a849157c1/mss6132t.pdf"
			(at 0 0 90)
			(layer "F.Fab")
			(hide yes)
			(effects
				(font
					(size 1.27 1.27)
					(thickness 0.15)
				)
			)
		)
		(property "Description" "Power Inductor (SMT), 22 µH, 1.85 A, Shielded, 2.45 A, WE-MAPI"
			(at 0 0 90)
			(layer "F.Fab")
			(hide yes)
			(effects
				(font
					(size 1.27 1.27)
					(thickness 0.15)
				)
			)
		)
		(property "Author" "Antmicro"
			(at 219.964 -96.012 0)
			(layer "F.Fab")
			(hide yes)
			(effects
				(font
					(size 1 1)
					(thickness 0.15)
				)
			)
		)
		(property "IMax" "1.45A"
			(at 219.964 -96.012 0)
			(layer "F.Fab")
			(hide yes)
			(effects
				(font
					(size 1 1)
					(thickness 0.15)
				)
			)
		)
		(property "ISat" "1.12A"
			(at 219.964 -96.012 0)
			(layer "F.Fab")
			(hide yes)
			(effects
				(font
					(size 1 1)
					(thickness 0.15)
				)
			)
		)
		(property "License" "Apache-2.0"
			(at 219.964 -96.012 0)
			(layer "F.Fab")
			(hide yes)
			(effects
				(font
					(size 1 1)
					(thickness 0.15)
				)
			)
		)
		(property "MPN" "MSS6132T-223"
			(at 219.964 -96.012 0)
			(layer "F.Fab")
			(hide yes)
			(effects
				(font
					(size 1 1)
					(thickness 0.15)
				)
			)
		)
		(property "Manufacturer" "Coilcraft"
			(at 219.964 -96.012 0)
			(layer "F.Fab")
			(hide yes)
			(effects
				(font
					(size 1 1)
					(thickness 0.15)
				)
			)
		)
		(property "Size" "6.1x6.1"
			(at 219.964 -96.012 0)
			(layer "F.Fab")
			(hide yes)
			(effects
				(font
					(size 1 1)
					(thickness 0.15)
				)
			)
		)
		(property "Val" "22u/1.12A"
			(at 219.964 -96.012 0)
			(layer "F.Fab")
			(hide yes)
			(effects
				(font
					(size 1 1)
					(thickness 0.15)
				)
			)
		)
		(sheetname "/Power/")
		(sheetfile "power.kicad_sch")
		(attr smd)
		(fp_line
			(start -0.8 -3.05)
			(end 0.8 -3.05)
			(stroke
				(width 0.15)
				(type solid)
			)
			(layer "F.SilkS")
		)
		(fp_line
			(start -0.8 3.05)
			(end 0.8 3.05)
			(stroke
				(width 0.15)
				(type solid)
			)
			(layer "F.SilkS")
		)
		(fp_rect
			(start -3.35 -3.35)
			(end 3.35 3.35)
			(stroke
				(width 0.05)
				(type solid)
			)
			(fill no)
			(layer "F.CrtYd")
		)
		(fp_rect
			(start -3.1 -3.1)
			(end 3.1 3.1)
			(stroke
				(width 0.15)
				(type solid)
			)
			(fill no)
			(layer "F.Fab")
		)
		(pad "1" smd custom
			(at -2.71 0 180)
			(size 6 0.575)
			(layers "F.Cu" "F.Mask" "F.Paste")
			(net 4 "+12V")
			(pintype "passive")
			(options
				(clearance outline)
				(anchor rect)
			)
			(primitives
				(gr_poly
					(pts
						(xy 2.4 1.71) (xy 2.117646 1.21) (xy 1.9 0.96) (xy 1.65 0.71) (xy 1.2 0.41) (xy 0.4 0.11) (xy 0.4 0.01)
						(xy 2.9 0) (xy 2.9 1.71)
					)
					(width 0.2)
					(fill yes)
				)
				(gr_poly
					(pts
						(xy -2.4 1.731128) (xy -2.117646 1.231128) (xy -1.9 0.981128) (xy -1.65 0.731128) (xy -1.2 0.431128)
						(xy -0.4 0.131128) (xy -0.4 0.031128) (xy -2.9 0.021128) (xy -2.9 1.731128)
					)
					(width 0.2)
					(fill yes)
				)
			)
		)
		(pad "2" smd custom
			(at 2.71 0)
			(size 6 0.575)
			(layers "F.Cu" "F.Mask" "F.Paste")
			(net 54 "Net-(L4-Pad2)")
			(pintype "passive")
			(options
				(clearance outline)
				(anchor rect)
			)
			(primitives
				(gr_poly
					(pts
						(xy -2.4 1.731128) (xy -2.117646 1.231128) (xy -1.9 0.981128) (xy -1.65 0.731128) (xy -1.2 0.431128)
						(xy -0.4 0.131128) (xy -0.4 0.031128) (xy -2.9 0.021128) (xy -2.9 1.731128)
					)
					(width 0.2)
					(fill yes)
				)
				(gr_poly
					(pts
						(xy 2.4 1.71) (xy 2.117646 1.21) (xy 1.9 0.96) (xy 1.65 0.71) (xy 1.2 0.41) (xy 0.4 0.11) (xy 0.4 0.01)
						(xy 2.9 0) (xy 2.9 1.71)
					)
					(width 0.2)
					(fill yes)
				)
			)
		)
	)
	(footprint "antmicro-footprints:L_Coilcraft-PFL1609"
		(layer "F.Cu")
		(at 149.098 53.594)
		(property "Reference" "L11"
			(at -3.153254 0.380655 0)
			(layer "F.SilkS")
			(effects
				(font
					(size 0.7 0.7)
					(thickness 0.15)
				)
				(justify left bottom)
			)
		)
		(property "Value" "L_470n_1A_Coilcraft-PFL1609"
			(at 0 2 0)
			(layer "F.Fab")
			(effects
				(font
					(size 0.7 0.7)
					(thickness 0.15)
				)
				(justify left bottom)
			)
		)
		(property "Datasheet" "https://www.coilcraft.com/getmedia/2f4cd442-d64d-4413-a518-12fcfd03318d/pfl1609.pdf"
			(at 0 0 0)
			(layer "F.Fab")
			(hide yes)
			(effects
				(font
					(size 1.27 1.27)
					(thickness 0.15)
				)
			)
		)
		(property "Description" "Power Inductor (SMT), 6.8 µH, 9.2 A, Shielded, 12.8 A, XAL7070"
			(at 0 0 0)
			(layer "F.Fab")
			(hide yes)
			(effects
				(font
					(size 1.27 1.27)
					(thickness 0.15)
				)
			)
		)
		(property "Author" "Antmicro"
			(at 0 0 0)
			(layer "F.Fab")
			(hide yes)
			(effects
				(font
					(size 1 1)
					(thickness 0.15)
				)
			)
		)
		(property "IMax" "1 A"
			(at 0 0 0)
			(layer "F.Fab")
			(hide yes)
			(effects
				(font
					(size 1 1)
					(thickness 0.15)
				)
			)
		)
		(property "ISat" "0.99 A"
			(at 0 0 0)
			(layer "F.Fab")
			(hide yes)
			(effects
				(font
					(size 1 1)
					(thickness 0.15)
				)
			)
		)
		(property "License" "Apache-2.0"
			(at 0 0 0)
			(layer "F.Fab")
			(hide yes)
			(effects
				(font
					(size 1 1)
					(thickness 0.15)
				)
			)
		)
		(property "MPN" "PFL1609-471"
			(at 0 0 0)
			(layer "F.Fab")
			(hide yes)
			(effects
				(font
					(size 1 1)
					(thickness 0.15)
				)
			)
		)
		(property "Manufacturer" "Coilcraft"
			(at 0 0 0)
			(layer "F.Fab")
			(hide yes)
			(effects
				(font
					(size 1 1)
					(thickness 0.15)
				)
			)
		)
		(property "Size" "1.07x1.8"
			(at 0 0 0)
			(layer "F.Fab")
			(hide yes)
			(effects
				(font
					(size 1 1)
					(thickness 0.15)
				)
			)
		)
		(property "Val" "470n/0.99A"
			(at 0 0 0)
			(layer "F.Fab")
			(hide yes)
			(effects
				(font
					(size 1 1)
					(thickness 0.15)
				)
			)
		)
		(sheetname "/Power/")
		(sheetfile "power.kicad_sch")
		(attr smd)
		(fp_line
			(start -0.23 -0.45)
			(end 0.23 -0.45)
			(stroke
				(width 0.15)
				(type solid)
			)
			(layer "F.SilkS")
		)
		(fp_line
			(start -0.23 0.45)
			(end 0.23 0.45)
			(stroke
				(width 0.15)
				(type solid)
			)
			(layer "F.SilkS")
		)
		(fp_rect
			(start -1.2 -0.84)
			(end 1.2 0.84)
			(stroke
				(width 0.05)
				(type solid)
			)
			(fill no)
			(layer "F.CrtYd")
		)
		(fp_rect
			(start -0.9 -0.535)
			(end 0.9 0.535)
			(stroke
				(width 0.15)
				(type solid)
			)
			(fill no)
			(layer "F.Fab")
		)
		(pad "1" smd roundrect
			(at -0.635 0)
			(size 0.64 1.02)
			(layers "F.Cu" "F.Mask" "F.Paste")
			(roundrect_rratio 0.15)
			(net 57 "Net-(L11-Pad1)")
			(pintype "passive")
		)
		(pad "2" smd roundrect
			(at 0.635 0)
			(size 0.64 1.02)
			(layers "F.Cu" "F.Mask" "F.Paste")
			(roundrect_rratio 0.15)
			(net 61 "Net-(L11-Pad2)")
			(pintype "passive")
		)
	)
	(footprint "antmicro-footprints:R_0402_1005Metric"
		(layer "F.Cu")
		(at 166.116 59.817 90)
		(descr "Resistor SMD 0402")
		(tags "resistor SMD 0402")
		(property "Reference" "R6"
			(at -2.286 0.381 90)
			(layer "F.SilkS")
			(effects
				(font
					(size 0.7 0.7)
					(thickness 0.15)
				)
				(justify left bottom)
			)
		)
		(property "Value" "R_0R_0402"
			(at -1.011843 1.772047 90)
			(layer "F.Fab")
			(effects
				(font
					(size 0.7 0.7)
					(thickness 0.15)
				)
				(justify left bottom)
			)
		)
		(property "Datasheet" "https://industrial.panasonic.com/cdbs/www-data/pdf/RDA0000/AOA0000C301.pdf"
			(at 0 0 90)
			(layer "F.Fab")
			(hide yes)
			(effects
				(font
					(size 1.27 1.27)
					(thickness 0.15)
				)
			)
		)
		(property "Description" "SMD Chip Resistor, Jumper, 0 ohm, 100 mW, 0402 [1005 Metric], Thick Film, General Purpose"
			(at 0 0 90)
			(layer "F.Fab")
			(hide yes)
			(effects
				(font
					(size 1.27 1.27)
					(thickness 0.15)
				)
			)
		)
		(property "Author" "Antmicro"
			(at 225.933 -106.299 0)
			(layer "F.Fab")
			(hide yes)
			(effects
				(font
					(size 1 1)
					(thickness 0.15)
				)
			)
		)
		(property "Current" "1A"
			(at 225.933 -106.299 0)
			(layer "F.Fab")
			(hide yes)
			(effects
				(font
					(size 1 1)
					(thickness 0.15)
				)
			)
		)
		(property "License" "Apache-2.0"
			(at 225.933 -106.299 0)
			(layer "F.Fab")
			(hide yes)
			(effects
				(font
					(size 1 1)
					(thickness 0.15)
				)
			)
		)
		(property "MPN" "ERJ2GE0R00X"
			(at 225.933 -106.299 0)
			(layer "F.Fab")
			(hide yes)
			(effects
				(font
					(size 1 1)
					(thickness 0.15)
				)
			)
		)
		(property "Manufacturer" "Panasonic"
			(at 225.933 -106.299 0)
			(layer "F.Fab")
			(hide yes)
			(effects
				(font
					(size 1 1)
					(thickness 0.15)
				)
			)
		)
		(property "Tolerance" ""
			(at 225.933 -106.299 0)
			(layer "F.Fab")
			(hide yes)
			(effects
				(font
					(size 1 1)
					(thickness 0.15)
				)
			)
		)
		(property "Val" "0R"
			(at 225.933 -106.299 0)
			(layer "F.Fab")
			(hide yes)
			(effects
				(font
					(size 1 1)
					(thickness 0.15)
				)
			)
		)
		(sheetname "/Connectors/")
		(sheetfile "connectors.kicad_sch")
		(attr smd)
		(fp_rect
			(start -0.925 -0.47)
			(end 0.925 0.47)
			(stroke
				(width 0.05)
				(type default)
			)
			(fill no)
			(layer "F.CrtYd")
		)
		(fp_rect
			(start -0.5 -0.25)
			(end 0.5 0.25)
			(stroke
				(width 0.15)
				(type solid)
			)
			(fill no)
			(layer "F.Fab")
		)
		(pad "1" smd roundrect
			(at -0.48 0 90)
			(size 0.59 0.64)
			(layers "F.Cu" "F.Mask" "F.Paste")
			(roundrect_rratio 0.25)
			(net 83 "/Connectors/MFP3")
			(pintype "passive")
		)
		(pad "2" smd roundrect
			(at 0.48 0 90)
			(size 0.59 0.64)
			(layers "F.Cu" "F.Mask" "F.Paste")
			(roundrect_rratio 0.25)
			(net 132 "Net-(U2-Y)")
			(pintype "passive")
		)
	)
	(footprint "antmicro-footprints:R_0402_1005Metric"
		(layer "F.Cu")
		(at 150.622 56.642 90)
		(descr "Resistor SMD 0402")
		(tags "resistor SMD 0402")
		(property "Reference" "R26"
			(at -1.016 1.262 90)
			(layer "F.SilkS")
			(effects
				(font
					(size 0.7 0.7)
					(thickness 0.15)
				)
				(justify left bottom)
			)
		)
		(property "Value" "R_5k1_0402"
			(at -1.011843 1.772047 90)
			(layer "F.Fab")
			(effects
				(font
					(size 0.7 0.7)
					(thickness 0.15)
				)
				(justify left bottom)
			)
		)
		(property "Datasheet" "https://www.bourns.com/docs/product-datasheets/cr.pdf"
			(at 0 0 90)
			(layer "F.Fab")
			(hide yes)
			(effects
				(font
					(size 1.27 1.27)
					(thickness 0.15)
				)
			)
		)
		(property "Description" "SMD Chip Resistor, 5.1 kohm, ± 1%, 63 mW, 0402 [1005 Metric], Thick Film, General Purpose"
			(at 0 0 90)
			(layer "F.Fab")
			(hide yes)
			(effects
				(font
					(size 1.27 1.27)
					(thickness 0.15)
				)
			)
		)
		(property "Author" "Antmicro"
			(at 207.264 -93.98 0)
			(layer "F.Fab")
			(hide yes)
			(effects
				(font
					(size 1 1)
					(thickness 0.15)
				)
			)
		)
		(property "License" "Apache-2.0"
			(at 207.264 -93.98 0)
			(layer "F.Fab")
			(hide yes)
			(effects
				(font
					(size 1 1)
					(thickness 0.15)
				)
			)
		)
		(property "MPN" "CR0402-FX-5101GLF"
			(at 207.264 -93.98 0)
			(layer "F.Fab")
			(hide yes)
			(effects
				(font
					(size 1 1)
					(thickness 0.15)
				)
			)
		)
		(property "Manufacturer" "Bourns"
			(at 207.264 -93.98 0)
			(layer "F.Fab")
			(hide yes)
			(effects
				(font
					(size 1 1)
					(thickness 0.15)
				)
			)
		)
		(property "Tolerance" "1%"
			(at 207.264 -93.98 0)
			(layer "F.Fab")
			(hide yes)
			(effects
				(font
					(size 1 1)
					(thickness 0.15)
				)
			)
		)
		(property "Val" "5k1"
			(at 207.264 -93.98 0)
			(layer "F.Fab")
			(hide yes)
			(effects
				(font
					(size 1 1)
					(thickness 0.15)
				)
			)
		)
		(sheetname "/Power/")
		(sheetfile "power.kicad_sch")
		(attr smd)
		(fp_rect
			(start -0.925 -0.47)
			(end 0.925 0.47)
			(stroke
				(width 0.05)
				(type default)
			)
			(fill no)
			(layer "F.CrtYd")
		)
		(fp_rect
			(start -0.5 -0.25)
			(end 0.5 0.25)
			(stroke
				(width 0.15)
				(type solid)
			)
			(fill no)
			(layer "F.Fab")
		)
		(pad "1" smd roundrect
			(at -0.48 0 90)
			(size 0.59 0.64)
			(layers "F.Cu" "F.Mask" "F.Paste")
			(roundrect_rratio 0.25)
			(net 53 "Net-(L3-Pad2)")
			(pintype "passive")
		)
		(pad "2" smd roundrect
			(at 0.48 0 90)
			(size 0.59 0.64)
			(layers "F.Cu" "F.Mask" "F.Paste")
			(roundrect_rratio 0.25)
			(net 57 "Net-(L11-Pad1)")
			(pintype "passive")
		)
	)
	(footprint "antmicro-footprints:L_Coilcraft-PFL1609"
		(layer "F.Cu")
		(at 140.18 53.594)
		(property "Reference" "L14"
			(at -1.470634 1.480804 0)
			(layer "F.SilkS")
			(effects
				(font
					(size 0.7 0.7)
					(thickness 0.15)
				)
				(justify left bottom)
			)
		)
		(property "Value" "L_470n_1A_Coilcraft-PFL1609"
			(at 0 2 0)
			(layer "F.Fab")
			(effects
				(font
					(size 0.7 0.7)
					(thickness 0.15)
				)
				(justify left bottom)
			)
		)
		(property "Datasheet" "https://www.coilcraft.com/getmedia/2f4cd442-d64d-4413-a518-12fcfd03318d/pfl1609.pdf"
			(at 0 0 0)
			(layer "F.Fab")
			(hide yes)
			(effects
				(font
					(size 1.27 1.27)
					(thickness 0.15)
				)
			)
		)
		(property "Description" "Power Inductor (SMT), 6.8 µH, 9.2 A, Shielded, 12.8 A, XAL7070"
			(at 0 0 0)
			(layer "F.Fab")
			(hide yes)
			(effects
				(font
					(size 1.27 1.27)
					(thickness 0.15)
				)
			)
		)
		(property "Author" "Antmicro"
			(at 0 0 0)
			(layer "F.Fab")
			(hide yes)
			(effects
				(font
					(size 1 1)
					(thickness 0.15)
				)
			)
		)
		(property "IMax" "1 A"
			(at 0 0 0)
			(layer "F.Fab")
			(hide yes)
			(effects
				(font
					(size 1 1)
					(thickness 0.15)
				)
			)
		)
		(property "ISat" "0.99 A"
			(at 0 0 0)
			(layer "F.Fab")
			(hide yes)
			(effects
				(font
					(size 1 1)
					(thickness 0.15)
				)
			)
		)
		(property "License" "Apache-2.0"
			(at 0 0 0)
			(layer "F.Fab")
			(hide yes)
			(effects
				(font
					(size 1 1)
					(thickness 0.15)
				)
			)
		)
		(property "MPN" "PFL1609-471"
			(at 0 0 0)
			(layer "F.Fab")
			(hide yes)
			(effects
				(font
					(size 1 1)
					(thickness 0.15)
				)
			)
		)
		(property "Manufacturer" "Coilcraft"
			(at 0 0 0)
			(layer "F.Fab")
			(hide yes)
			(effects
				(font
					(size 1 1)
					(thickness 0.15)
				)
			)
		)
		(property "Size" "1.07x1.8"
			(at 0 0 0)
			(layer "F.Fab")
			(hide yes)
			(effects
				(font
					(size 1 1)
					(thickness 0.15)
				)
			)
		)
		(property "Val" "470n/0.99A"
			(at 0 0 0)
			(layer "F.Fab")
			(hide yes)
			(effects
				(font
					(size 1 1)
					(thickness 0.15)
				)
			)
		)
		(sheetname "/Power/")
		(sheetfile "power.kicad_sch")
		(attr smd)
		(fp_line
			(start -0.23 -0.45)
			(end 0.23 -0.45)
			(stroke
				(width 0.15)
				(type solid)
			)
			(layer "F.SilkS")
		)
		(fp_line
			(start -0.23 0.45)
			(end 0.23 0.45)
			(stroke
				(width 0.15)
				(type solid)
			)
			(layer "F.SilkS")
		)
		(fp_rect
			(start -1.2 -0.84)
			(end 1.2 0.84)
			(stroke
				(width 0.05)
				(type solid)
			)
			(fill no)
			(layer "F.CrtYd")
		)
		(fp_rect
			(start -0.9 -0.535)
			(end 0.9 0.535)
			(stroke
				(width 0.15)
				(type solid)
			)
			(fill no)
			(layer "F.Fab")
		)
		(pad "1" smd roundrect
			(at -0.635 0)
			(size 0.64 1.02)
			(layers "F.Cu" "F.Mask" "F.Paste")
			(roundrect_rratio 0.15)
			(net 60 "Net-(L10-Pad2)")
			(pintype "passive")
		)
		(pad "2" smd roundrect
			(at 0.635 0)
			(size 0.64 1.02)
			(layers "F.Cu" "F.Mask" "F.Paste")
			(roundrect_rratio 0.15)
			(net 115 "/Connectors/PoCB")
			(pintype "passive")
		)
	)
	(footprint "antmicro-footprints:L_Coilcraft-PFL1609"
		(layer "F.Cu")
		(at 151.638 53.594)
		(property "Reference" "L15"
			(at -1.498634 1.480804 0)
			(layer "F.SilkS")
			(effects
				(font
					(size 0.7 0.7)
					(thickness 0.15)
				)
				(justify left bottom)
			)
		)
		(property "Value" "L_470n_1A_Coilcraft-PFL1609"
			(at 0 2 0)
			(layer "F.Fab")
			(effects
				(font
					(size 0.7 0.7)
					(thickness 0.15)
				)
				(justify left bottom)
			)
		)
		(property "Datasheet" "https://www.coilcraft.com/getmedia/2f4cd442-d64d-4413-a518-12fcfd03318d/pfl1609.pdf"
			(at 0 0 0)
			(layer "F.Fab")
			(hide yes)
			(effects
				(font
					(size 1.27 1.27)
					(thickness 0.15)
				)
			)
		)
		(property "Description" "Power Inductor (SMT), 6.8 µH, 9.2 A, Shielded, 12.8 A, XAL7070"
			(at 0 0 0)
			(layer "F.Fab")
			(hide yes)
			(effects
				(font
					(size 1.27 1.27)
					(thickness 0.15)
				)
			)
		)
		(property "Author" "Antmicro"
			(at 0 0 0)
			(layer "F.Fab")
			(hide yes)
			(effects
				(font
					(size 1 1)
					(thickness 0.15)
				)
			)
		)
		(property "IMax" "1 A"
			(at 0 0 0)
			(layer "F.Fab")
			(hide yes)
			(effects
				(font
					(size 1 1)
					(thickness 0.15)
				)
			)
		)
		(property "ISat" "0.99 A"
			(at 0 0 0)
			(layer "F.Fab")
			(hide yes)
			(effects
				(font
					(size 1 1)
					(thickness 0.15)
				)
			)
		)
		(property "License" "Apache-2.0"
			(at 0 0 0)
			(layer "F.Fab")
			(hide yes)
			(effects
				(font
					(size 1 1)
					(thickness 0.15)
				)
			)
		)
		(property "MPN" "PFL1609-471"
			(at 0 0 0)
			(layer "F.Fab")
			(hide yes)
			(effects
				(font
					(size 1 1)
					(thickness 0.15)
				)
			)
		)
		(property "Manufacturer" "Coilcraft"
			(at 0 0 0)
			(layer "F.Fab")
			(hide yes)
			(effects
				(font
					(size 1 1)
					(thickness 0.15)
				)
			)
		)
		(property "Size" "1.07x1.8"
			(at 0 0 0)
			(layer "F.Fab")
			(hide yes)
			(effects
				(font
					(size 1 1)
					(thickness 0.15)
				)
			)
		)
		(property "Val" "470n/0.99A"
			(at 0 0 0)
			(layer "F.Fab")
			(hide yes)
			(effects
				(font
					(size 1 1)
					(thickness 0.15)
				)
			)
		)
		(sheetname "/Power/")
		(sheetfile "power.kicad_sch")
		(attr smd)
		(fp_line
			(start -0.23 -0.45)
			(end 0.23 -0.45)
			(stroke
				(width 0.15)
				(type solid)
			)
			(layer "F.SilkS")
		)
		(fp_line
			(start -0.23 0.45)
			(end 0.23 0.45)
			(stroke
				(width 0.15)
				(type solid)
			)
			(layer "F.SilkS")
		)
		(fp_rect
			(start -1.2 -0.84)
			(end 1.2 0.84)
			(stroke
				(width 0.05)
				(type solid)
			)
			(fill no)
			(layer "F.CrtYd")
		)
		(fp_rect
			(start -0.9 -0.535)
			(end 0.9 0.535)
			(stroke
				(width 0.15)
				(type solid)
			)
			(fill no)
			(layer "F.Fab")
		)
		(pad "1" smd roundrect
			(at -0.635 0)
			(size 0.64 1.02)
			(layers "F.Cu" "F.Mask" "F.Paste")
			(roundrect_rratio 0.15)
			(net 61 "Net-(L11-Pad2)")
			(pintype "passive")
		)
		(pad "2" smd roundrect
			(at 0.635 0)
			(size 0.64 1.02)
			(layers "F.Cu" "F.Mask" "F.Paste")
			(roundrect_rratio 0.15)
			(net 116 "/Connectors/PoCC")
			(pintype "passive")
		)
	)
	(footprint "antmicro-footprints:R_0402_1005Metric"
		(layer "F.Cu")
		(at 152.3492 78.8416 45)
		(descr "Resistor SMD 0402")
		(tags "resistor SMD 0402")
		(property "Reference" "R48"
			(at -0.933947 2.44263 45)
			(layer "F.SilkS")
			(effects
				(font
					(size 0.7 0.7)
					(thickness 0.15)
				)
				(justify left bottom)
			)
		)
		(property "Value" "R_80k6_0402"
			(at -1.011843 1.772046 45)
			(layer "F.Fab")
			(effects
				(font
					(size 0.7 0.7)
					(thickness 0.15)
				)
				(justify left bottom)
			)
		)
		(property "Datasheet" "https://www.bourns.com/docs/product-datasheets/cr.pdf"
			(at 0 0 45)
			(layer "F.Fab")
			(hide yes)
			(effects
				(font
					(size 1.27 1.27)
					(thickness 0.15)
				)
			)
		)
		(property "Description" "SMD Chip Resistor, 80.6 kohm, ± 1%, 100 mW, 0402 [1005 Metric], Thick Film, Precision"
			(at 0 0 45)
			(layer "F.Fab")
			(hide yes)
			(effects
				(font
					(size 1.27 1.27)
					(thickness 0.15)
				)
			)
		)
		(property "Author" "Antmicro"
			(at 100.371477 -84.634982 0)
			(layer "F.Fab")
			(hide yes)
			(effects
				(font
					(size 1 1)
					(thickness 0.15)
				)
			)
		)
		(property "License" "Apache-2.0"
			(at 100.371477 -84.634982 0)
			(layer "F.Fab")
			(hide yes)
			(effects
				(font
					(size 1 1)
					(thickness 0.15)
				)
			)
		)
		(property "MPN" "CR0402-FX-8062GLF"
			(at 100.371477 -84.634982 0)
			(layer "F.Fab")
			(hide yes)
			(effects
				(font
					(size 1 1)
					(thickness 0.15)
				)
			)
		)
		(property "Manufacturer" "Bourns"
			(at 100.371477 -84.634982 0)
			(layer "F.Fab")
			(hide yes)
			(effects
				(font
					(size 1 1)
					(thickness 0.15)
				)
			)
		)
		(property "Tolerance" "1%"
			(at 100.371477 -84.634982 0)
			(layer "F.Fab")
			(hide yes)
			(effects
				(font
					(size 1 1)
					(thickness 0.15)
				)
			)
		)
		(property "Val" "80k6"
			(at 100.371477 -84.634982 0)
			(layer "F.Fab")
			(hide yes)
			(effects
				(font
					(size 1 1)
					(thickness 0.15)
				)
			)
		)
		(sheetname "/Deserializer/")
		(sheetfile "deserializer.kicad_sch")
		(attr smd exclude_from_pos_files exclude_from_bom dnp)
		(fp_poly
			(pts
				(xy -0.925 -0.47) (xy 0.925 -0.47) (xy 0.925 0.47) (xy -0.925 0.47)
			)
			(stroke
				(width 0.05)
				(type default)
			)
			(fill no)
			(layer "F.CrtYd")
		)
		(fp_poly
			(pts
				(xy -0.5 -0.25) (xy 0.5 -0.25) (xy 0.5 0.25) (xy -0.5 0.25)
			)
			(stroke
				(width 0.15)
				(type solid)
			)
			(fill no)
			(layer "F.Fab")
		)
		(pad "1" smd roundrect
			(at -0.48 0 45)
			(size 0.59 0.64)
			(layers "F.Cu" "F.Mask" "F.Paste")
			(roundrect_rratio 0.25)
			(net 76 "/Deserializer/CFG0")
			(pintype "passive")
		)
		(pad "2" smd roundrect
			(at 0.48 0 45)
			(size 0.59 0.64)
			(layers "F.Cu" "F.Mask" "F.Paste")
			(roundrect_rratio 0.25)
			(net 146 "VDDIO")
			(pintype "passive")
		)
	)
	(footprint "antmicro-footprints:TSOT23-6"
		(layer "F.Cu")
		(at 134.773 94.602)
		(property "Reference" "U4"
			(at -1.042 2.553 180)
			(layer "F.SilkS")
			(effects
				(font
					(size 0.7 0.7)
					(thickness 0.15)
				)
				(justify left bottom)
			)
		)
		(property "Value" "AP62301_TSOT"
			(at 2.813 1.525 0)
			(layer "B.Fab")
			(effects
				(font
					(size 0.7 0.7)
					(thickness 0.15)
				)
				(justify left bottom mirror)
			)
		)
		(property "Datasheet" "https://www.diodes.com/assets/Datasheets/AP62300_AP62301_AP62300T.pdf"
			(at 0 0 0)
			(layer "F.Fab")
			(hide yes)
			(effects
				(font
					(size 1.27 1.27)
					(thickness 0.15)
				)
			)
		)
		(property "Description" "DC-DC Switching Synchronous Buck Regulator, Adjustable, 4.2V-18Vin, 0.8V-7V/3A out, TSOT-26-6"
			(at 0 0 0)
			(layer "F.Fab")
			(hide yes)
			(effects
				(font
					(size 1.27 1.27)
					(thickness 0.15)
				)
			)
		)
		(property "Author" "Antmicro"
			(at 0 0 0)
			(layer "F.Fab")
			(hide yes)
			(effects
				(font
					(size 1 1)
					(thickness 0.15)
				)
			)
		)
		(property "License" "Apache-2.0"
			(at 0 0 0)
			(layer "F.Fab")
			(hide yes)
			(effects
				(font
					(size 1 1)
					(thickness 0.15)
				)
			)
		)
		(property "MPN" "AP62301WU-7"
			(at 0 0 0)
			(layer "F.Fab")
			(hide yes)
			(effects
				(font
					(size 1 1)
					(thickness 0.15)
				)
			)
		)
		(property "Manufacturer" "Diodes Incorporated"
			(at 0 0 0)
			(layer "F.Fab")
			(hide yes)
			(effects
				(font
					(size 1 1)
					(thickness 0.15)
				)
			)
		)
		(sheetname "/Power/")
		(sheetfile "power.kicad_sch")
		(attr smd)
		(fp_line
			(start -1 -1.5)
			(end -1 -1.375)
			(stroke
				(width 0.15)
				(type solid)
			)
			(layer "F.SilkS")
		)
		(fp_line
			(start -1 1.55)
			(end -1 1.4)
			(stroke
				(width 0.15)
				(type solid)
			)
			(layer "F.SilkS")
		)
		(fp_line
			(start 1 -1.497)
			(end -1 -1.5)
			(stroke
				(width 0.15)
				(type solid)
			)
			(layer "F.SilkS")
		)
		(fp_line
			(start 1 -1.497)
			(end 1 -1.375)
			(stroke
				(width 0.15)
				(type solid)
			)
			(layer "F.SilkS")
		)
		(fp_line
			(start 1 1.55)
			(end -1 1.55)
			(stroke
				(width 0.15)
				(type solid)
			)
			(layer "F.SilkS")
		)
		(fp_line
			(start 1 1.55)
			(end 1 1.4)
			(stroke
				(width 0.15)
				(type solid)
			)
			(layer "F.SilkS")
		)
		(fp_circle
			(center -1.44 -1.5)
			(end -1.39 -1.5)
			(stroke
				(width 0.15)
				(type solid)
			)
			(fill yes)
			(layer "F.SilkS")
		)
		(fp_rect
			(start 1.93 -1.7)
			(end -1.93 1.7)
			(stroke
				(width 0.05)
				(type solid)
			)
			(fill no)
			(layer "F.CrtYd")
		)
		(fp_line
			(start -0.45 -1.521)
			(end -0.876 -1.096)
			(stroke
				(width 0.15)
				(type solid)
			)
			(layer "F.Fab")
		)
		(fp_rect
			(start 0.875 1.528)
			(end -0.875 -1.525)
			(stroke
				(width 0.15)
				(type solid)
			)
			(fill no)
			(layer "F.Fab")
		)
		(pad "1" smd rect
			(at -1.301 -0.947 270)
			(size 0.7 1.2)
			(layers "F.Cu" "F.Mask" "F.Paste")
			(net 1 "GND")
			(pinfunction "GND")
			(pintype "power_in")
		)
		(pad "2" smd rect
			(at -1.301 0.004 270)
			(size 0.7 1.2)
			(layers "F.Cu" "F.Mask" "F.Paste")
			(net 7 "/Power/SW_1V8")
			(pinfunction "SW")
			(pintype "power_out")
		)
		(pad "3" smd rect
			(at -1.301 0.954 270)
			(size 0.7 1.2)
			(layers "F.Cu" "F.Mask" "F.Paste")
			(net 4 "+12V")
			(pinfunction "VIN")
			(pintype "power_in")
		)
		(pad "4" smd rect
			(at 1.299 0.954 270)
			(size 0.7 1.2)
			(layers "F.Cu" "F.Mask" "F.Paste")
			(net 70 "/Power/FB_1V8")
			(pinfunction "FB")
			(pintype "input")
		)
		(pad "5" smd rect
			(at 1.299 0.004 270)
			(size 0.7 1.2)
			(layers "F.Cu" "F.Mask" "F.Paste")
			(net 69 "/Power/EN_1V8")
			(pinfunction "EN")
			(pintype "input")
		)
		(pad "6" smd rect
			(at 1.299 -0.947 270)
			(size 0.7 1.2)
			(layers "F.Cu" "F.Mask" "F.Paste")
			(net 6 "Net-(U4-BST)")
			(pinfunction "BST")
			(pintype "output")
		)
	)
	(footprint "antmicro-footprints:TP_SMD_0.75mm"
		(layer "F.Cu")
		(at 138.33 84.938)
		(property "Reference" "TP4"
			(at -3.3062 0.404 0)
			(layer "F.SilkS")
			(hide yes)
			(effects
				(font
					(size 0.7 0.7)
					(thickness 0.15)
				)
				(justify left bottom)
			)
		)
		(property "Value" "TP_0.75mm_SMD"
			(at 0 1.2 0)
			(layer "F.Fab")
			(effects
				(font
					(size 0.7 0.7)
					(thickness 0.15)
				)
				(justify left bottom)
			)
		)
		(property "Description" "SMT test point"
			(at 0 0 0)
			(layer "F.Fab")
			(hide yes)
			(effects
				(font
					(size 1.27 1.27)
					(thickness 0.15)
				)
			)
		)
		(property "Author" "Antmicro"
			(at 0 0 0)
			(layer "F.Fab")
			(hide yes)
			(effects
				(font
					(size 1 1)
					(thickness 0.15)
				)
			)
		)
		(property "License" "Apache-2.0"
			(at 0 0 0)
			(layer "F.Fab")
			(hide yes)
			(effects
				(font
					(size 1 1)
					(thickness 0.15)
				)
			)
		)
		(property "MPN" ""
			(at 0 0 0)
			(layer "F.Fab")
			(hide yes)
			(effects
				(font
					(size 1 1)
					(thickness 0.15)
				)
			)
		)
		(property "Manufacturer" ""
			(at 0 0 0)
			(layer "F.Fab")
			(hide yes)
			(effects
				(font
					(size 1 1)
					(thickness 0.15)
				)
			)
		)
		(sheetname "/Connectors/")
		(sheetfile "connectors.kicad_sch")
		(fp_circle
			(center 0 0)
			(end 0.475 0)
			(stroke
				(width 0.05)
				(type default)
			)
			(fill no)
			(layer "F.CrtYd")
		)
		(pad "1" smd circle
			(at 0 0)
			(size 0.75 0.75)
			(layers "F.Cu" "F.Mask")
			(net 87 "/Connectors/MFP8")
			(pinfunction "1")
			(pintype "passive")
		)
	)
	(footprint "antmicro-footprints:R_0402_1005Metric"
		(layer "F.Cu")
		(at 139.827 73.533 135)
		(descr "Resistor SMD 0402")
		(tags "resistor SMD 0402")
		(property "Reference" "R44"
			(at 6.254077 -0.468529 315)
			(unlocked yes)
			(layer "F.SilkS")
			(effects
				(font
					(size 0.7 0.7)
					(thickness 0.15)
				)
				(justify left bottom)
			)
		)
		(property "Value" "R_49R9_0402"
			(at -1.011843 1.772046 135)
			(layer "F.Fab")
			(effects
				(font
					(size 0.7 0.7)
					(thickness 0.15)
				)
				(justify left bottom)
			)
		)
		(property "Datasheet" "https://www.bourns.com/docs/product-datasheets/cr.pdf"
			(at 0 0 135)
			(layer "F.Fab")
			(hide yes)
			(effects
				(font
					(size 1.27 1.27)
					(thickness 0.15)
				)
			)
		)
		(property "Description" "SMD Chip Resistor, 49.9 ohm, ± 1%, 62.5 mW, 0402 [1005 Metric], Thick Film, General Purpose"
			(at 0 0 135)
			(layer "F.Fab")
			(hide yes)
			(effects
				(font
					(size 1.27 1.27)
					(thickness 0.15)
				)
			)
		)
		(property "Author" "Antmicro"
			(at 290.695303 26.656063 0)
			(layer "F.Fab")
			(hide yes)
			(effects
				(font
					(size 1 1)
					(thickness 0.15)
				)
			)
		)
		(property "License" "Apache-2.0"
			(at 290.695303 26.656063 0)
			(layer "F.Fab")
			(hide yes)
			(effects
				(font
					(size 1 1)
					(thickness 0.15)
				)
			)
		)
		(property "MPN" "CR0402-FX-49R9GLF"
			(at 290.695303 26.656063 0)
			(layer "F.Fab")
			(hide yes)
			(effects
				(font
					(size 1 1)
					(thickness 0.15)
				)
			)
		)
		(property "Manufacturer" "Bourns"
			(at 290.695303 26.656063 0)
			(layer "F.Fab")
			(hide yes)
			(effects
				(font
					(size 1 1)
					(thickness 0.15)
				)
			)
		)
		(property "Tolerance" "1%"
			(at 290.695303 26.656063 0)
			(layer "F.Fab")
			(hide yes)
			(effects
				(font
					(size 1 1)
					(thickness 0.15)
				)
			)
		)
		(property "Val" "49R9"
			(at 290.695303 26.656063 0)
			(layer "F.Fab")
			(hide yes)
			(effects
				(font
					(size 1 1)
					(thickness 0.15)
				)
			)
		)
		(sheetname "/Deserializer/")
		(sheetfile "deserializer.kicad_sch")
		(attr smd)
		(fp_poly
			(pts
				(xy -0.925 -0.47) (xy 0.925 -0.47) (xy 0.925 0.47) (xy -0.925 0.47)
			)
			(stroke
				(width 0.05)
				(type default)
			)
			(fill no)
			(layer "F.CrtYd")
		)
		(fp_poly
			(pts
				(xy -0.5 -0.25) (xy 0.5 -0.25) (xy 0.5 0.25) (xy -0.5 0.25)
			)
			(stroke
				(width 0.15)
				(type solid)
			)
			(fill no)
			(layer "F.Fab")
		)
		(pad "1" smd roundrect
			(at -0.48 0 135)
			(size 0.59 0.64)
			(layers "F.Cu" "F.Mask" "F.Paste")
			(roundrect_rratio 0.25)
			(net 21 "Net-(C33-Pad2)")
			(pintype "passive")
		)
		(pad "2" smd roundrect
			(at 0.48 0 135)
			(size 0.59 0.64)
			(layers "F.Cu" "F.Mask" "F.Paste")
			(roundrect_rratio 0.25)
			(net 1 "GND")
			(pintype "passive")
		)
	)
	(footprint "antmicro-footprints:SOT-23-5"
		(layer "F.Cu")
		(at 128.198 75.034 90)
		(property "Reference" "U3"
			(at -0.531 -1.96 90)
			(layer "F.SilkS")
			(effects
				(font
					(size 0.7 0.7)
					(thickness 0.15)
				)
				(justify right bottom)
			)
		)
		(property "Value" "LMR62014XMF"
			(at 0.002 2.799 90)
			(layer "F.Fab")
			(effects
				(font
					(size 0.7 0.7)
					(thickness 0.15)
				)
				(justify left bottom)
			)
		)
		(property "Datasheet" "https://www.ti.com/lit/ds/symlink/lmr62014.pdf?ts=1698148381034"
			(at 0 0 90)
			(layer "F.Fab")
			(hide yes)
			(effects
				(font
					(size 1.27 1.27)
					(thickness 0.15)
				)
			)
		)
		(property "Description" "Step-Up Regulator  2.7V to 14V, 1.4A"
			(at 0 0 90)
			(layer "F.Fab")
			(hide yes)
			(effects
				(font
					(size 1.27 1.27)
					(thickness 0.15)
				)
			)
		)
		(property "Author" "Antmicro"
			(at 203.232 -53.164 0)
			(layer "F.Fab")
			(hide yes)
			(effects
				(font
					(size 1 1)
					(thickness 0.15)
				)
			)
		)
		(property "License" "Apache-2.0"
			(at 203.232 -53.164 0)
			(layer "F.Fab")
			(hide yes)
			(effects
				(font
					(size 1 1)
					(thickness 0.15)
				)
			)
		)
		(property "MPN" "LMR62014XMF/NOPB"
			(at 203.232 -53.164 0)
			(layer "F.Fab")
			(hide yes)
			(effects
				(font
					(size 1 1)
					(thickness 0.15)
				)
			)
		)
		(property "Manufacturer" "Texas Instruments"
			(at 203.232 -53.164 0)
			(layer "F.Fab")
			(hide yes)
			(effects
				(font
					(size 1 1)
					(thickness 0.15)
				)
			)
		)
		(sheetname "/Power/")
		(sheetfile "power.kicad_sch")
		(attr smd)
		(fp_line
			(start 0.8 -1.6)
			(end 0.5 -1.6)
			(stroke
				(width 0.15)
				(type solid)
			)
			(layer "F.SilkS")
		)
		(fp_line
			(start -0.8 -1.6)
			(end -0.5 -1.6)
			(stroke
				(width 0.15)
				(type solid)
			)
			(layer "F.SilkS")
		)
		(fp_line
			(start -0.8 -1.6)
			(end -0.8 -1.3)
			(stroke
				(width 0.15)
				(type solid)
			)
			(layer "F.SilkS")
		)
		(fp_line
			(start 0.8 -1.3)
			(end 0.8 -1.6)
			(stroke
				(width 0.15)
				(type solid)
			)
			(layer "F.SilkS")
		)
		(fp_line
			(start 0.8 0.55)
			(end 0.8 -0.55)
			(stroke
				(width 0.15)
				(type solid)
			)
			(layer "F.SilkS")
		)
		(fp_line
			(start 0.8 1.3)
			(end 0.8 1.599)
			(stroke
				(width 0.15)
				(type solid)
			)
			(layer "F.SilkS")
		)
		(fp_line
			(start 0.8 1.599)
			(end 0.549 1.599)
			(stroke
				(width 0.15)
				(type solid)
			)
			(layer "F.SilkS")
		)
		(fp_line
			(start -0.55 1.6)
			(end -0.85 1.6)
			(stroke
				(width 0.15)
				(type solid)
			)
			(layer "F.SilkS")
		)
		(fp_line
			(start -0.85 1.6)
			(end -0.85 1.301)
			(stroke
				(width 0.15)
				(type solid)
			)
			(layer "F.SilkS")
		)
		(fp_circle
			(center -1.25 -1.5)
			(end -1.2 -1.5)
			(stroke
				(width 0.15)
				(type solid)
			)
			(fill yes)
			(layer "F.SilkS")
		)
		(fp_rect
			(start 1.9 -1.76)
			(end -1.9 1.75)
			(stroke
				(width 0.05)
				(type solid)
			)
			(fill no)
			(layer "F.CrtYd")
		)
		(fp_line
			(start -0.398 -1.526)
			(end -0.874 -1.05)
			(stroke
				(width 0.15)
				(type solid)
			)
			(layer "F.Fab")
		)
		(fp_rect
			(start 0.874 1.523)
			(end -0.873 -1.525)
			(stroke
				(width 0.15)
				(type solid)
			)
			(fill no)
			(layer "F.Fab")
		)
		(pad "1" smd rect
			(at -1.351 -0.951)
			(size 0.55 1)
			(layers "F.Cu" "F.Mask" "F.Paste")
			(net 124 "/Power/SW_12V")
			(pinfunction "SW")
			(pintype "power_out")
		)
		(pad "2" smd rect
			(at -1.351 0)
			(size 0.55 1)
			(layers "F.Cu" "F.Mask" "F.Paste")
			(net 1 "GND")
			(pinfunction "GND")
			(pintype "power_in")
		)
		(pad "3" smd rect
			(at -1.351 0.949)
			(size 0.55 1)
			(layers "F.Cu" "F.Mask" "F.Paste")
			(net 122 "/Power/FB_12V")
			(pinfunction "FB")
			(pintype "input")
		)
		(pad "4" smd rect
			(at 1.35 0.949)
			(size 0.55 1)
			(layers "F.Cu" "F.Mask" "F.Paste")
			(net 125 "/Power/EN_12V")
			(pinfunction "~{SHDN}")
			(pintype "input")
		)
		(pad "5" smd rect
			(at 1.35 -0.951)
			(size 0.55 1)
			(layers "F.Cu" "F.Mask" "F.Paste")
			(net 5 "+5V")
			(pinfunction "VIN")
			(pintype "power_in")
		)
	)
	(footprint "antmicro-footprints:LED_0603_1608Metric_G"
		(layer "F.Cu")
		(at 147.85 96.1 -90)
		(descr "LED SMD 0603 Green")
		(tags "LED SMD 0603 Green")
		(property "Reference" "D18"
			(at -4.488889 29.433333 0)
			(layer "F.SilkS")
			(effects
				(font
					(size 0.7 0.7)
					(thickness 0.15)
				)
				(justify right bottom)
			)
		)
		(property "Value" "LED_G_0603_LTST-C190GKT"
			(at -0.001 1.599 90)
			(layer "F.Fab")
			(effects
				(font
					(size 0.7 0.7)
					(thickness 0.15)
				)
				(justify right bottom)
			)
		)
		(property "Datasheet" "https://media.digikey.com/pdf/Data%20Sheets/Lite-On%20PDFs/LTST-C190GKT.pdf"
			(at 0 0 270)
			(layer "F.Fab")
			(hide yes)
			(effects
				(font
					(size 1.27 1.27)
					(thickness 0.15)
				)
			)
		)
		(property "Description" "LED, Green, SMD, 0603, 20 mA, 2.1 V, 569 nm"
			(at 0 0 270)
			(layer "F.Fab")
			(hide yes)
			(effects
				(font
					(size 1.27 1.27)
					(thickness 0.15)
				)
			)
		)
		(property "Author" "Antmicro"
			(at 51.75 243.95 0)
			(layer "F.Fab")
			(hide yes)
			(effects
				(font
					(size 1 1)
					(thickness 0.15)
				)
			)
		)
		(property "Color" "Green"
			(at 51.75 243.95 0)
			(layer "F.Fab")
			(hide yes)
			(effects
				(font
					(size 1 1)
					(thickness 0.15)
				)
			)
		)
		(property "License" "Apache-2.0"
			(at 51.75 243.95 0)
			(layer "F.Fab")
			(hide yes)
			(effects
				(font
					(size 1 1)
					(thickness 0.15)
				)
			)
		)
		(property "MPN" "LTST-C190GKT"
			(at 51.75 243.95 0)
			(layer "F.Fab")
			(hide yes)
			(effects
				(font
					(size 1 1)
					(thickness 0.15)
				)
			)
		)
		(property "Manufacturer" "Lite-On"
			(at 51.75 243.95 0)
			(layer "F.Fab")
			(hide yes)
			(effects
				(font
					(size 1 1)
					(thickness 0.15)
				)
			)
		)
		(property "VSD_class" "LED"
			(at 51.75 243.95 0)
			(layer "F.Fab")
			(hide yes)
			(effects
				(font
					(size 1 1)
					(thickness 0.15)
				)
			)
		)
		(sheetname "/Power/")
		(sheetfile "power.kicad_sch")
		(attr smd)
		(fp_line
			(start 0.22 0.35)
			(end -0.22 0.35)
			(stroke
				(width 0.15)
				(type solid)
			)
			(layer "F.SilkS")
		)
		(fp_line
			(start -0.094672 0.201008)
			(end -0.094672 -0.198992)
			(stroke
				(width 0.1)
				(type solid)
			)
			(layer "F.SilkS")
		)
		(fp_line
			(start 0.105328 0.201008)
			(end -0.094672 0.001008)
			(stroke
				(width 0.1)
				(type solid)
			)
			(layer "F.SilkS")
		)
		(fp_line
			(start 0.105328 0.201008)
			(end 0.105328 -0.198992)
			(stroke
				(width 0.1)
				(type solid)
			)
			(layer "F.SilkS")
		)
		(fp_line
			(start -0.094672 0.001008)
			(end -0.24 0.001008)
			(stroke
				(width 0.1)
				(type solid)
			)
			(layer "F.SilkS")
		)
		(fp_line
			(start -0.094672 0.001008)
			(end 0.105328 -0.198992)
			(stroke
				(width 0.1)
				(type solid)
			)
			(layer "F.SilkS")
		)
		(fp_line
			(start 0.105328 0.001008)
			(end 0.24 0.001)
			(stroke
				(width 0.1)
				(type solid)
			)
			(layer "F.SilkS")
		)
		(fp_line
			(start -1.18 -0.319)
			(end -1.18 0.321)
			(stroke
				(width 0.15)
				(type solid)
			)
			(layer "F.SilkS")
		)
		(fp_line
			(start 0.22 -0.35)
			(end -0.22 -0.35)
			(stroke
				(width 0.15)
				(type solid)
			)
			(layer "F.SilkS")
		)
		(fp_rect
			(start 1.25 0.65)
			(end -1.25 -0.65)
			(stroke
				(width 0.05)
				(type solid)
			)
			(fill no)
			(layer "F.CrtYd")
		)
		(fp_line
			(start -0.199 0.2)
			(end -0.199 0.1)
			(stroke
				(width 0.15)
				(type solid)
			)
			(layer "F.Fab")
		)
		(fp_line
			(start 0.201 0.2)
			(end 0.201 0)
			(stroke
				(width 0.15)
				(type solid)
			)
			(layer "F.Fab")
		)
		(fp_line
			(start -0.199 0)
			(end -0.597 0)
			(stroke
				(width 0.15)
				(type solid)
			)
			(layer "F.Fab")
		)
		(fp_line
			(start -0.101 0)
			(end 0.201 0.2)
			(stroke
				(width 0.15)
				(type solid)
			)
			(layer "F.Fab")
		)
		(fp_line
			(start 0.201 0)
			(end 0.201 -0.202)
			(stroke
				(width 0.15)
				(type solid)
			)
			(layer "F.Fab")
		)
		(fp_line
			(start 0.599 0)
			(end 0.201 0)
			(stroke
				(width 0.15)
				(type solid)
			)
			(layer "F.Fab")
		)
		(fp_line
			(start -0.199 -0.202)
			(end -0.199 0.1)
			(stroke
				(width 0.15)
				(type solid)
			)
			(layer "F.Fab")
		)
		(fp_line
			(start 0.201 -0.202)
			(end -0.101 0)
			(stroke
				(width 0.15)
				(type solid)
			)
			(layer "F.Fab")
		)
		(fp_rect
			(start 0.848 0.4)
			(end -0.85 -0.402)
			(stroke
				(width 0.15)
				(type solid)
			)
			(fill no)
			(layer "F.Fab")
		)
		(pad "1" smd roundrect
			(at -0.7 0 90)
			(size 0.8 1)
			(layers "F.Cu" "F.Mask" "F.Paste")
			(roundrect_rratio 0.2)
			(net 142 "Net-(D18-C)")
			(pinfunction "C")
			(pintype "passive")
		)
		(pad "2" smd roundrect
			(at 0.7 0 90)
			(size 0.8 1)
			(layers "F.Cu" "F.Mask" "F.Paste")
			(roundrect_rratio 0.2)
			(net 123 "/Power/OUT_12V")
			(pinfunction "A")
			(pintype "passive")
		)
	)
	(footprint "antmicro-footprints:C_0603_1608Metric"
		(layer "F.Cu")
		(at 129.448 78.844 -90)
		(descr "Capacitor SMD 0603")
		(tags "capacitor 0603")
		(property "Reference" "C16"
			(at -0.612 0.759 90)
			(layer "F.SilkS")
			(effects
				(font
					(size 0.7 0.7)
					(thickness 0.15)
				)
				(justify right bottom)
			)
		)
		(property "Value" "C_10u_25V_0603"
			(at -2.44357 2.792288 90)
			(layer "F.Fab")
			(effects
				(font
					(size 0.7 0.7)
					(thickness 0.15)
				)
				(justify right bottom)
			)
		)
		(property "Datasheet" "https://product.tdk.com/en/search/capacitor/ceramic/mlcc/info?part_no=C1608X5R1E106M080AC"
			(at 0 0 270)
			(layer "F.Fab")
			(hide yes)
			(effects
				(font
					(size 1.27 1.27)
					(thickness 0.15)
				)
			)
		)
		(property "Description" "SMD Multilayer Ceramic Capacitor, 10 µF, 25 V, 0603 [1608 Metric], ± 20%, X5R, C"
			(at 0 0 270)
			(layer "F.Fab")
			(hide yes)
			(effects
				(font
					(size 1.27 1.27)
					(thickness 0.15)
				)
			)
		)
		(property "Author" "Antmicro"
			(at 50.604 208.292 0)
			(layer "F.Fab")
			(hide yes)
			(effects
				(font
					(size 1 1)
					(thickness 0.15)
				)
			)
		)
		(property "Dielectric" ""
			(at 50.604 208.292 0)
			(layer "F.Fab")
			(hide yes)
			(effects
				(font
					(size 1 1)
					(thickness 0.15)
				)
			)
		)
		(property "License" "Apache-2.0"
			(at 50.604 208.292 0)
			(layer "F.Fab")
			(hide yes)
			(effects
				(font
					(size 1 1)
					(thickness 0.15)
				)
			)
		)
		(property "MPN" "C1608X5R1E106M080AC"
			(at 50.604 208.292 0)
			(layer "F.Fab")
			(hide yes)
			(effects
				(font
					(size 1 1)
					(thickness 0.15)
				)
			)
		)
		(property "Manufacturer" "TDK"
			(at 50.604 208.292 0)
			(layer "F.Fab")
			(hide yes)
			(effects
				(font
					(size 1 1)
					(thickness 0.15)
				)
			)
		)
		(property "Val" "10u"
			(at 50.604 208.292 0)
			(layer "F.Fab")
			(hide yes)
			(effects
				(font
					(size 1 1)
					(thickness 0.15)
				)
			)
		)
		(property "Voltage" "25V"
			(at 50.604 208.292 0)
			(layer "F.Fab")
			(hide yes)
			(effects
				(font
					(size 1 1)
					(thickness 0.15)
				)
			)
		)
		(sheetname "/Power/")
		(sheetfile "power.kicad_sch")
		(attr smd)
		(fp_line
			(start -0.15 0.4)
			(end 0.15 0.4)
			(stroke
				(width 0.15)
				(type solid)
			)
			(layer "F.SilkS")
		)
		(fp_line
			(start -0.15 -0.4)
			(end 0.15 -0.4)
			(stroke
				(width 0.15)
				(type solid)
			)
			(layer "F.SilkS")
		)
		(fp_rect
			(start -1.25 -0.65)
			(end 1.25 0.65)
			(stroke
				(width 0.05)
				(type solid)
			)
			(fill no)
			(layer "F.CrtYd")
		)
		(fp_rect
			(start -0.8 -0.4)
			(end 0.8 0.4)
			(stroke
				(width 0.15)
				(type solid)
			)
			(fill no)
			(layer "F.Fab")
		)
		(pad "1" smd roundrect
			(at -0.7 0 270)
			(size 0.8 1)
			(layers "F.Cu" "F.Mask" "F.Paste")
			(roundrect_rratio 0.2)
			(net 1 "GND")
			(pintype "passive")
		)
		(pad "2" smd roundrect
			(at 0.7 0 270)
			(size 0.8 1)
			(layers "F.Cu" "F.Mask" "F.Paste")
			(roundrect_rratio 0.2)
			(net 123 "/Power/OUT_12V")
			(pintype "passive")
		)
	)
	(footprint "antmicro-footprints:C_0402_1005Metric"
		(layer "F.Cu")
		(at 142.113 74.295 135)
		(descr "Capacitor SMD 0402")
		(tags "capacitor SMD 0402")
		(property "Reference" "C28"
			(at 6.272037 -0.486489 315)
			(unlocked yes)
			(layer "F.SilkS")
			(effects
				(font
					(size 0.7 0.7)
					(thickness 0.15)
				)
				(justify left bottom)
			)
		)
		(property "Value" "C_100n_0402"
			(at -1.022927 2.155213 135)
			(layer "F.Fab")
			(effects
				(font
					(size 0.7 0.7)
					(thickness 0.15)
				)
				(justify left bottom)
			)
		)
		(property "Datasheet" "https://www.murata.com/products/productdetail?partno=GRM155R61H104KE14%23"
			(at 0 0 135)
			(layer "F.Fab")
			(hide yes)
			(effects
				(font
					(size 1.27 1.27)
					(thickness 0.15)
				)
			)
		)
		(property "Description" "SMD Multilayer Ceramic Capacitor, 0.1 µF, 50 V, 0402 [1005 Metric], ± 10%, X5R, GRM Series"
			(at 0 0 135)
			(layer "F.Fab")
			(hide yes)
			(effects
				(font
					(size 1.27 1.27)
					(thickness 0.15)
				)
			)
		)
		(property "Author" "Antmicro"
			(at 295.136564 26.340432 0)
			(layer "F.Fab")
			(hide yes)
			(effects
				(font
					(size 1 1)
					(thickness 0.15)
				)
			)
		)
		(property "Dielectric" "X5R"
			(at 295.136564 26.340432 0)
			(layer "F.Fab")
			(hide yes)
			(effects
				(font
					(size 1 1)
					(thickness 0.15)
				)
			)
		)
		(property "License" "Apache-2.0"
			(at 295.136564 26.340432 0)
			(layer "F.Fab")
			(hide yes)
			(effects
				(font
					(size 1 1)
					(thickness 0.15)
				)
			)
		)
		(property "MPN" "GRM155R61H104KE14D"
			(at 295.136564 26.340432 0)
			(layer "F.Fab")
			(hide yes)
			(effects
				(font
					(size 1 1)
					(thickness 0.15)
				)
			)
		)
		(property "Manufacturer" "Murata"
			(at 295.136564 26.340432 0)
			(layer "F.Fab")
			(hide yes)
			(effects
				(font
					(size 1 1)
					(thickness 0.15)
				)
			)
		)
		(property "Val" "100n"
			(at 295.136564 26.340432 0)
			(layer "F.Fab")
			(hide yes)
			(effects
				(font
					(size 1 1)
					(thickness 0.15)
				)
			)
		)
		(property "Voltage" "50V"
			(at 295.136564 26.340432 0)
			(layer "F.Fab")
			(hide yes)
			(effects
				(font
					(size 1 1)
					(thickness 0.15)
				)
			)
		)
		(sheetname "/Deserializer/")
		(sheetfile "deserializer.kicad_sch")
		(attr smd)
		(fp_poly
			(pts
				(xy -0.925 -0.47) (xy 0.925 -0.47) (xy 0.925 0.47) (xy -0.925 0.47)
			)
			(stroke
				(width 0.05)
				(type default)
			)
			(fill no)
			(layer "F.CrtYd")
		)
		(fp_line
			(start 0.504 -0.25)
			(end 0.504 0.248)
			(stroke
				(width 0.15)
				(type solid)
			)
			(layer "F.Fab")
		)
		(fp_line
			(start 0.504 0.248)
			(end -0.494 0.248)
			(stroke
				(width 0.15)
				(type solid)
			)
			(layer "F.Fab")
		)
		(fp_line
			(start -0.494 -0.25)
			(end 0.504 -0.25)
			(stroke
				(width 0.15)
				(type solid)
			)
			(layer "F.Fab")
		)
		(fp_line
			(start -0.494 0.248)
			(end -0.494 -0.25)
			(stroke
				(width 0.15)
				(type solid)
			)
			(layer "F.Fab")
		)
		(pad "1" smd roundrect
			(at -0.48 0 135)
			(size 0.59 0.64)
			(layers "F.Cu" "F.Mask" "F.Paste")
			(roundrect_rratio 0.25)
			(net 14 "/Deserializer/SIOB_P")
			(pintype "passive")
		)
		(pad "2" smd roundrect
			(at 0.48 0 135)
			(size 0.59 0.64)
			(layers "F.Cu" "F.Mask" "F.Paste")
			(roundrect_rratio 0.25)
			(net 115 "/Connectors/PoCB")
			(pintype "passive")
		)
	)
	(footprint "antmicro-footprints:C_0402_1005Metric"
		(layer "F.Cu")
		(at 131.064 75.946)
		(descr "Capacitor SMD 0402")
		(tags "capacitor SMD 0402")
		(property "Reference" "C15"
			(at 0.937 0.277 0)
			(layer "F.SilkS")
			(effects
				(font
					(size 0.7 0.7)
					(thickness 0.15)
				)
				(justify left bottom)
			)
		)
		(property "Value" "C_220p_0402"
			(at -1.022927 2.155213 0)
			(layer "F.Fab")
			(effects
				(font
					(size 0.7 0.7)
					(thickness 0.15)
				)
				(justify left bottom)
			)
		)
		(property "Datasheet" "https://spicat.kyocera-avx.com/product/mlcc/chartview/04025C221JAT2A/"
			(at 0 0 0)
			(layer "F.Fab")
			(hide yes)
			(effects
				(font
					(size 1.27 1.27)
					(thickness 0.15)
				)
			)
		)
		(property "Description" "SMD Multilayer Ceramic Capacitor, 220 pF, 50 V, 0402 [1005 Metric], ± 10%, X7R, MC"
			(at 0 0 0)
			(layer "F.Fab")
			(hide yes)
			(effects
				(font
					(size 1.27 1.27)
					(thickness 0.15)
				)
			)
		)
		(property "Author" "Antmicro"
			(at 0 0 0)
			(layer "F.Fab")
			(hide yes)
			(effects
				(font
					(size 1 1)
					(thickness 0.15)
				)
			)
		)
		(property "Dielectric" ""
			(at 0 0 0)
			(layer "F.Fab")
			(hide yes)
			(effects
				(font
					(size 1 1)
					(thickness 0.15)
				)
			)
		)
		(property "License" "Apache-2.0"
			(at 0 0 0)
			(layer "F.Fab")
			(hide yes)
			(effects
				(font
					(size 1 1)
					(thickness 0.15)
				)
			)
		)
		(property "MPN" "04025C221JAT2A"
			(at 0 0 0)
			(layer "F.Fab")
			(hide yes)
			(effects
				(font
					(size 1 1)
					(thickness 0.15)
				)
			)
		)
		(property "Manufacturer" "KYOCERA AVX"
			(at 0 0 0)
			(layer "F.Fab")
			(hide yes)
			(effects
				(font
					(size 1 1)
					(thickness 0.15)
				)
			)
		)
		(property "Val" "220p"
			(at 0 0 0)
			(layer "F.Fab")
			(hide yes)
			(effects
				(font
					(size 1 1)
					(thickness 0.15)
				)
			)
		)
		(property "Voltage" ""
			(at 0 0 0)
			(layer "F.Fab")
			(hide yes)
			(effects
				(font
					(size 1 1)
					(thickness 0.15)
				)
			)
		)
		(sheetname "/Power/")
		(sheetfile "power.kicad_sch")
		(attr smd)
		(fp_rect
			(start -0.925 -0.47)
			(end 0.925 0.47)
			(stroke
				(width 0.05)
				(type default)
			)
			(fill no)
			(layer "F.CrtYd")
		)
		(fp_line
			(start -0.494 -0.25)
			(end 0.504 -0.25)
			(stroke
				(width 0.15)
				(type solid)
			)
			(layer "F.Fab")
		)
		(fp_line
			(start -0.494 0.248)
			(end -0.494 -0.25)
			(stroke
				(width 0.15)
				(type solid)
			)
			(layer "F.Fab")
		)
		(fp_line
			(start 0.504 -0.25)
			(end 0.504 0.248)
			(stroke
				(width 0.15)
				(type solid)
			)
			(layer "F.Fab")
		)
		(fp_line
			(start 0.504 0.248)
			(end -0.494 0.248)
			(stroke
				(width 0.15)
				(type solid)
			)
			(layer "F.Fab")
		)
		(pad "1" smd roundrect
			(at -0.48 0)
			(size 0.59 0.64)
			(layers "F.Cu" "F.Mask" "F.Paste")
			(roundrect_rratio 0.25)
			(net 122 "/Power/FB_12V")
			(pintype "passive")
		)
		(pad "2" smd roundrect
			(at 0.48 0)
			(size 0.59 0.64)
			(layers "F.Cu" "F.Mask" "F.Paste")
			(roundrect_rratio 0.25)
			(net 123 "/Power/OUT_12V")
			(pintype "passive")
		)
	)
	(footprint "antmicro-footprints:DFN-10_2.5x1mm"
		(layer "F.Cu")
		(at 142.598 77.076 -45)
		(property "Reference" "D4"
			(at 1.22881 -1.358635 225)
			(layer "F.SilkS")
			(effects
				(font
					(size 0.7 0.7)
					(thickness 0.15)
				)
				(justify left bottom)
			)
		)
		(property "Value" "PESD4USB5U-TTS"
			(at 2.032 1.524 135)
			(layer "F.Fab")
			(effects
				(font
					(size 0.7 0.7)
					(thickness 0.15)
				)
				(justify right bottom)
			)
		)
		(property "Datasheet" "https://assets.nexperia.com/documents/data-sheet/PESD4USB5U-TTS.pdf"
			(at 0 0 315)
			(layer "F.Fab")
			(hide yes)
			(effects
				(font
					(size 1.27 1.27)
					(thickness 0.15)
				)
			)
		)
		(property "Description" "TVS diode array, 15kV, DFN-10, 5 V, 0.5 pF"
			(at 0 0 315)
			(layer "F.Fab")
			(hide yes)
			(effects
				(font
					(size 1.27 1.27)
					(thickness 0.15)
				)
			)
		)
		(property "Author" "Antmicro"
			(at -12.790036 123.554121 0)
			(layer "F.Fab")
			(hide yes)
			(effects
				(font
					(size 1 1)
					(thickness 0.15)
				)
			)
		)
		(property "License" "Apache-2.0"
			(at -12.790036 123.554121 0)
			(layer "F.Fab")
			(hide yes)
			(effects
				(font
					(size 1 1)
					(thickness 0.15)
				)
			)
		)
		(property "MPN" "PESD4USB5U-TTS"
			(at -12.790036 123.554121 0)
			(layer "F.Fab")
			(hide yes)
			(effects
				(font
					(size 1 1)
					(thickness 0.15)
				)
			)
		)
		(property "Manufacturer" "Nexperia"
			(at -12.790036 123.554121 0)
			(layer "F.Fab")
			(hide yes)
			(effects
				(font
					(size 1 1)
					(thickness 0.15)
				)
			)
		)
		(sheetname "/Deserializer/")
		(sheetfile "deserializer.kicad_sch")
		(attr smd)
		(fp_line
			(start -0.4 1.4)
			(end 0.4 1.4)
			(stroke
				(width 0.15)
				(type solid)
			)
			(layer "F.SilkS")
		)
		(fp_line
			(start 0.4 -1.4)
			(end -0.4 -1.4)
			(stroke
				(width 0.15)
				(type solid)
			)
			(layer "F.SilkS")
		)
		(fp_circle
			(center -0.762 -1.27)
			(end -0.712 -1.270001)
			(stroke
				(width 0.15)
				(type solid)
			)
			(fill yes)
			(layer "F.SilkS")
		)
		(fp_poly
			(pts
				(xy -0.85 -1.6) (xy 0.85 -1.6) (xy 0.85 1.6) (xy -0.85 1.6)
			)
			(stroke
				(width 0.05)
				(type solid)
			)
			(fill no)
			(layer "F.CrtYd")
		)
		(fp_line
			(start -0.5 1.25)
			(end 0.5 1.25)
			(stroke
				(width 0.15)
				(type solid)
			)
			(layer "F.Fab")
		)
		(fp_line
			(start 0.5 1.25)
			(end 0.5 -1.25)
			(stroke
				(width 0.15)
				(type solid)
			)
			(layer "F.Fab")
		)
		(fp_line
			(start -0.499999 -0.9)
			(end -0.5 1.25)
			(stroke
				(width 0.15)
				(type solid)
			)
			(layer "F.Fab")
		)
		(fp_line
			(start -0.15 -1.249999)
			(end -0.499999 -0.9)
			(stroke
				(width 0.15)
				(type solid)
			)
			(layer "F.Fab")
		)
		(fp_line
			(start 0.5 -1.25)
			(end -0.15 -1.249999)
			(stroke
				(width 0.15)
				(type solid)
			)
			(layer "F.Fab")
		)
		(pad "1" smd roundrect
			(at -0.425 -1 225)
			(size 0.2 0.6)
			(layers "F.Cu" "F.Mask" "F.Paste")
			(roundrect_rratio 0.25)
			(net 14 "/Deserializer/SIOB_P")
			(pinfunction "1")
			(pintype "passive")
			(solder_mask_margin 0.05)
		)
		(pad "2" smd roundrect
			(at -0.425 -0.5 225)
			(size 0.2 0.6)
			(layers "F.Cu" "F.Mask" "F.Paste")
			(roundrect_rratio 0.25)
			(net 20 "/Deserializer/SIOB_N")
			(pinfunction "2")
			(pintype "passive")
			(solder_mask_margin 0.05)
		)
		(pad "3" smd roundrect
			(at -0.424999 0 225)
			(size 0.4 0.6)
			(layers "F.Cu" "F.Mask" "F.Paste")
			(roundrect_rratio 0.25)
			(net 1 "GND")
			(pinfunction "3")
			(pintype "passive")
			(solder_mask_margin 0.05)
		)
		(pad "4" smd roundrect
			(at -0.425 0.5 225)
			(size 0.2 0.6)
			(layers "F.Cu" "F.Mask" "F.Paste")
			(roundrect_rratio 0.25)
			(net 18 "/Deserializer/SIOA_N")
			(pinfunction "4")
			(pintype "passive")
			(solder_mask_margin 0.05)
		)
		(pad "5" smd roundrect
			(at -0.425 1 225)
			(size 0.2 0.6)
			(layers "F.Cu" "F.Mask" "F.Paste")
			(roundrect_rratio 0.25)
			(net 13 "/Deserializer/SIOA_P")
			(pinfunction "5")
			(pintype "passive")
			(solder_mask_margin 0.05)
		)
		(pad "6" smd roundrect
			(at 0.425 1 225)
			(size 0.2 0.6)
			(layers "F.Cu" "F.Mask" "F.Paste")
			(roundrect_rratio 0.25)
			(net 13 "/Deserializer/SIOA_P")
			(pinfunction "6")
			(pintype "passive")
			(solder_mask_margin 0.05)
		)
		(pad "7" smd roundrect
			(at 0.425 0.5 225)
			(size 0.2 0.6)
			(layers "F.Cu" "F.Mask" "F.Paste")
			(roundrect_rratio 0.25)
			(net 18 "/Deserializer/SIOA_N")
			(pinfunction "7")
			(pintype "passive")
			(solder_mask_margin 0.05)
		)
		(pad "8" smd roundrect
			(at 0.424999 0 225)
			(size 0.4 0.6)
			(layers "F.Cu" "F.Mask" "F.Paste")
			(roundrect_rratio 0.25)
			(net 1 "GND")
			(pinfunction "8")
			(pintype "passive")
			(solder_mask_margin 0.05)
		)
		(pad "9" smd roundrect
			(at 0.425 -0.5 225)
			(size 0.2 0.6)
			(layers "F.Cu" "F.Mask" "F.Paste")
			(roundrect_rratio 0.25)
			(net 20 "/Deserializer/SIOB_N")
			(pinfunction "9")
			(pintype "passive")
			(solder_mask_margin 0.05)
		)
		(pad "10" smd roundrect
			(at 0.425 -1 225)
			(size 0.2 0.6)
			(layers "F.Cu" "F.Mask" "F.Paste")
			(roundrect_rratio 0.25)
			(net 14 "/Deserializer/SIOB_P")
			(pinfunction "10")
			(pintype "passive")
			(solder_mask_margin 0.05)
		)
	)
	(footprint "antmicro-footprints:R_0402_1005Metric"
		(layer "F.Cu")
		(at 175.195 66.418 180)
		(descr "Resistor SMD 0402")
		(tags "resistor SMD 0402")
		(property "Reference" "R60"
			(at -1.320513 -1.324079 0)
			(layer "F.SilkS")
			(effects
				(font
					(size 0.7 0.7)
					(thickness 0.15)
				)
				(justify right bottom)
			)
		)
		(property "Value" "R_10k_0402"
			(at -1.011843 1.772047 0)
			(layer "F.Fab")
			(effects
				(font
					(size 0.7 0.7)
					(thickness 0.15)
				)
				(justify right bottom)
			)
		)
		(property "Datasheet" "https://www.bourns.com/docs/product-datasheets/cr.pdf"
			(at 0 0 180)
			(layer "F.Fab")
			(hide yes)
			(effects
				(font
					(size 1.27 1.27)
					(thickness 0.15)
				)
			)
		)
		(property "Description" "SMD Chip Resistor, 10 kohm, ± 1%, 62.5 mW, 0402 [1005 Metric], Thick Film, General Purpose"
			(at 0 0 180)
			(layer "F.Fab")
			(hide yes)
			(effects
				(font
					(size 1.27 1.27)
					(thickness 0.15)
				)
			)
		)
		(property "Author" "Antmicro"
			(at 350.39 132.836 0)
			(layer "F.Fab")
			(hide yes)
			(effects
				(font
					(size 1 1)
					(thickness 0.15)
				)
			)
		)
		(property "License" "Apache-2.0"
			(at 350.39 132.836 0)
			(layer "F.Fab")
			(hide yes)
			(effects
				(font
					(size 1 1)
					(thickness 0.15)
				)
			)
		)
		(property "MPN" "CR0402-FX-1002GLF"
			(at 350.39 132.836 0)
			(layer "F.Fab")
			(hide yes)
			(effects
				(font
					(size 1 1)
					(thickness 0.15)
				)
			)
		)
		(property "Manufacturer" "Bourns"
			(at 350.39 132.836 0)
			(layer "F.Fab")
			(hide yes)
			(effects
				(font
					(size 1 1)
					(thickness 0.15)
				)
			)
		)
		(property "Tolerance" "1%"
			(at 350.39 132.836 0)
			(layer "F.Fab")
			(hide yes)
			(effects
				(font
					(size 1 1)
					(thickness 0.15)
				)
			)
		)
		(property "Val" "10k"
			(at 350.39 132.836 0)
			(layer "F.Fab")
			(hide yes)
			(effects
				(font
					(size 1 1)
					(thickness 0.15)
				)
			)
		)
		(sheetname "/Connectors/")
		(sheetfile "connectors.kicad_sch")
		(attr smd)
		(fp_rect
			(start -0.925 -0.47)
			(end 0.925 0.47)
			(stroke
				(width 0.05)
				(type default)
			)
			(fill no)
			(layer "F.CrtYd")
		)
		(fp_rect
			(start -0.5 -0.25)
			(end 0.5 0.25)
			(stroke
				(width 0.15)
				(type solid)
			)
			(fill no)
			(layer "F.Fab")
		)
		(pad "1" smd roundrect
			(at -0.48 0 180)
			(size 0.59 0.64)
			(layers "F.Cu" "F.Mask" "F.Paste")
			(roundrect_rratio 0.25)
			(net 135 "Net-(U8-OE)")
			(pintype "passive")
		)
		(pad "2" smd roundrect
			(at 0.48 0 180)
			(size 0.59 0.64)
			(layers "F.Cu" "F.Mask" "F.Paste")
			(roundrect_rratio 0.25)
			(net 3 "+1V8")
			(pintype "passive")
		)
	)
	(footprint "antmicro-footprints:R_0402_1005Metric"
		(layer "F.Cu")
		(at 178.482 62.076 -90)
		(descr "Resistor SMD 0402")
		(tags "resistor SMD 0402")
		(property "Reference" "R61"
			(at 8.028 -0.588 90)
			(layer "F.SilkS")
			(effects
				(font
					(size 0.7 0.7)
					(thickness 0.15)
				)
				(justify right bottom)
			)
		)
		(property "Value" "R_2k2_0402"
			(at -1.011843 1.772047 90)
			(layer "F.Fab")
			(effects
				(font
					(size 0.7 0.7)
					(thickness 0.15)
				)
				(justify right bottom)
			)
		)
		(property "Datasheet" "https://www.bourns.com/docs/product-datasheets/cr.pdf"
			(at 0 0 270)
			(layer "F.Fab")
			(hide yes)
			(effects
				(font
					(size 1.27 1.27)
					(thickness 0.15)
				)
			)
		)
		(property "Description" "SMD Chip Resistor, 2.2 kohm, ± 1%, 62.5 mW, 0402 [1005 Metric], Thick Film, General Purpose"
			(at 0 0 270)
			(layer "F.Fab")
			(hide yes)
			(effects
				(font
					(size 1.27 1.27)
					(thickness 0.15)
				)
			)
		)
		(property "Author" "Antmicro"
			(at 116.406 240.558 0)
			(layer "F.Fab")
			(hide yes)
			(effects
				(font
					(size 1 1)
					(thickness 0.15)
				)
			)
		)
		(property "License" "Apache-2.0"
			(at 116.406 240.558 0)
			(layer "F.Fab")
			(hide yes)
			(effects
				(font
					(size 1 1)
					(thickness 0.15)
				)
			)
		)
		(property "MPN" "CR0402-FX-2201GLF"
			(at 116.406 240.558 0)
			(layer "F.Fab")
			(hide yes)
			(effects
				(font
					(size 1 1)
					(thickness 0.15)
				)
			)
		)
		(property "Manufacturer" "Bourns"
			(at 116.406 240.558 0)
			(layer "F.Fab")
			(hide yes)
			(effects
				(font
					(size 1 1)
					(thickness 0.15)
				)
			)
		)
		(property "Tolerance" "1%"
			(at 116.406 240.558 0)
			(layer "F.Fab")
			(hide yes)
			(effects
				(font
					(size 1 1)
					(thickness 0.15)
				)
			)
		)
		(property "Val" "2k2"
			(at 116.406 240.558 0)
			(layer "F.Fab")
			(hide yes)
			(effects
				(font
					(size 1 1)
					(thickness 0.15)
				)
			)
		)
		(sheetname "/Connectors/")
		(sheetfile "connectors.kicad_sch")
		(attr smd exclude_from_pos_files exclude_from_bom dnp)
		(fp_rect
			(start -0.925 -0.47)
			(end 0.925 0.47)
			(stroke
				(width 0.05)
				(type default)
			)
			(fill no)
			(layer "F.CrtYd")
		)
		(fp_rect
			(start -0.5 -0.25)
			(end 0.5 0.25)
			(stroke
				(width 0.15)
				(type solid)
			)
			(fill no)
			(layer "F.Fab")
		)
		(pad "1" smd roundrect
			(at -0.48 0 270)
			(size 0.59 0.64)
			(layers "F.Cu" "F.Mask" "F.Paste")
			(roundrect_rratio 0.25)
			(net 45 "/Connectors/SCL_CAM")
			(pintype "passive")
		)
		(pad "2" smd roundrect
			(at 0.48 0 270)
			(size 0.59 0.64)
			(layers "F.Cu" "F.Mask" "F.Paste")
			(roundrect_rratio 0.25)
			(net 50 "/Connectors/FFC_3V3")
			(pintype "passive")
		)
	)
	(footprint "antmicro-footprints:TP_SMD_0.75mm"
		(layer "F.Cu")
		(at 146.304 97.89)
		(property "Reference" "TP14"
			(at 0 -0.6 0)
			(layer "F.SilkS")
			(hide yes)
			(effects
				(font
					(size 0.7 0.7)
					(thickness 0.15)
				)
				(justify left bottom)
			)
		)
		(property "Value" "TP_0.75mm_SMD"
			(at 0 1.2 0)
			(layer "F.Fab")
			(effects
				(font
					(size 0.7 0.7)
					(thickness 0.15)
				)
				(justify left bottom)
			)
		)
		(property "Description" "SMT test point"
			(at 0 0 0)
			(layer "F.Fab")
			(hide yes)
			(effects
				(font
					(size 1.27 1.27)
					(thickness 0.15)
				)
			)
		)
		(property "Author" "Antmicro"
			(at 0 0 0)
			(layer "F.Fab")
			(hide yes)
			(effects
				(font
					(size 1 1)
					(thickness 0.15)
				)
			)
		)
		(property "License" "Apache-2.0"
			(at 0 0 0)
			(layer "F.Fab")
			(hide yes)
			(effects
				(font
					(size 1 1)
					(thickness 0.15)
				)
			)
		)
		(property "MPN" ""
			(at 0 0 0)
			(layer "F.Fab")
			(hide yes)
			(effects
				(font
					(size 1 1)
					(thickness 0.15)
				)
			)
		)
		(property "Manufacturer" ""
			(at 0 0 0)
			(layer "F.Fab")
			(hide yes)
			(effects
				(font
					(size 1 1)
					(thickness 0.15)
				)
			)
		)
		(sheetname "/Power/")
		(sheetfile "power.kicad_sch")
		(fp_circle
			(center 0 0)
			(end 0.475 0)
			(stroke
				(width 0.05)
				(type default)
			)
			(fill no)
			(layer "F.CrtYd")
		)
		(pad "1" smd circle
			(at 0 0)
			(size 0.75 0.75)
			(layers "F.Cu" "F.Mask")
			(net 11 "/Power/OUT_1V2")
			(pinfunction "1")
			(pintype "passive")
		)
	)
	(footprint "antmicro-footprints:R_0402_1005Metric"
		(layer "F.Cu")
		(at 121.087 81.638 -90)
		(descr "Resistor SMD 0402")
		(tags "resistor SMD 0402")
		(property "Reference" "R38"
			(at -1.12 0.564 90)
			(layer "F.SilkS")
			(effects
				(font
					(size 0.7 0.7)
					(thickness 0.15)
				)
				(justify right bottom)
			)
		)
		(property "Value" "R_10k_0402"
			(at -1.011843 1.772047 90)
			(layer "F.Fab")
			(effects
				(font
					(size 0.7 0.7)
					(thickness 0.15)
				)
				(justify right bottom)
			)
		)
		(property "Datasheet" "https://www.bourns.com/docs/product-datasheets/cr.pdf"
			(at 0 0 270)
			(layer "F.Fab")
			(hide yes)
			(effects
				(font
					(size 1.27 1.27)
					(thickness 0.15)
				)
			)
		)
		(property "Description" "SMD Chip Resistor, 10 kohm, ± 1%, 62.5 mW, 0402 [1005 Metric], Thick Film, General Purpose"
			(at 0 0 270)
			(layer "F.Fab")
			(hide yes)
			(effects
				(font
					(size 1.27 1.27)
					(thickness 0.15)
				)
			)
		)
		(property "Author" "Antmicro"
			(at 39.449 202.725 0)
			(layer "F.Fab")
			(hide yes)
			(effects
				(font
					(size 1 1)
					(thickness 0.15)
				)
			)
		)
		(property "License" "Apache-2.0"
			(at 39.449 202.725 0)
			(layer "F.Fab")
			(hide yes)
			(effects
				(font
					(size 1 1)
					(thickness 0.15)
				)
			)
		)
		(property "MPN" "CR0402-FX-1002GLF"
			(at 39.449 202.725 0)
			(layer "F.Fab")
			(hide yes)
			(effects
				(font
					(size 1 1)
					(thickness 0.15)
				)
			)
		)
		(property "Manufacturer" "Bourns"
			(at 39.449 202.725 0)
			(layer "F.Fab")
			(hide yes)
			(effects
				(font
					(size 1 1)
					(thickness 0.15)
				)
			)
		)
		(property "Tolerance" "1%"
			(at 39.449 202.725 0)
			(layer "F.Fab")
			(hide yes)
			(effects
				(font
					(size 1 1)
					(thickness 0.15)
				)
			)
		)
		(property "Val" "10k"
			(at 39.449 202.725 0)
			(layer "F.Fab")
			(hide yes)
			(effects
				(font
					(size 1 1)
					(thickness 0.15)
				)
			)
		)
		(sheetname "/Power/")
		(sheetfile "power.kicad_sch")
		(attr smd)
		(fp_rect
			(start -0.925 -0.47)
			(end 0.925 0.47)
			(stroke
				(width 0.05)
				(type default)
			)
			(fill no)
			(layer "F.CrtYd")
		)
		(fp_rect
			(start -0.5 -0.25)
			(end 0.5 0.25)
			(stroke
				(width 0.15)
				(type solid)
			)
			(fill no)
			(layer "F.Fab")
		)
		(pad "1" smd roundrect
			(at -0.48 0 270)
			(size 0.59 0.64)
			(layers "F.Cu" "F.Mask" "F.Paste")
			(roundrect_rratio 0.25)
			(net 1 "GND")
			(pintype "passive")
		)
		(pad "2" smd roundrect
			(at 0.48 0 270)
			(size 0.59 0.64)
			(layers "F.Cu" "F.Mask" "F.Paste")
			(roundrect_rratio 0.25)
			(net 71 "/Power/FB_1V2")
			(pintype "passive")
		)
	)
	(footprint "antmicro-footprints:R_0402_1005Metric"
		(layer "F.Cu")
		(at 139.192 61.976 90)
		(descr "Resistor SMD 0402")
		(tags "resistor SMD 0402")
		(property "Reference" "R20"
			(at -1.1405 1.27 90)
			(layer "F.SilkS")
			(effects
				(font
					(size 0.7 0.7)
					(thickness 0.15)
				)
				(justify left bottom)
			)
		)
		(property "Value" "R_5k1_0402"
			(at -1.011843 1.772047 90)
			(layer "F.Fab")
			(effects
				(font
					(size 0.7 0.7)
					(thickness 0.15)
				)
				(justify left bottom)
			)
		)
		(property "Datasheet" "https://www.bourns.com/docs/product-datasheets/cr.pdf"
			(at 0 0 90)
			(layer "F.Fab")
			(hide yes)
			(effects
				(font
					(size 1.27 1.27)
					(thickness 0.15)
				)
			)
		)
		(property "Description" "SMD Chip Resistor, 5.1 kohm, ± 1%, 63 mW, 0402 [1005 Metric], Thick Film, General Purpose"
			(at 0 0 90)
			(layer "F.Fab")
			(hide yes)
			(effects
				(font
					(size 1.27 1.27)
					(thickness 0.15)
				)
			)
		)
		(property "Author" "Antmicro"
			(at 201.168 -77.216 0)
			(layer "F.Fab")
			(hide yes)
			(effects
				(font
					(size 1 1)
					(thickness 0.15)
				)
			)
		)
		(property "License" "Apache-2.0"
			(at 201.168 -77.216 0)
			(layer "F.Fab")
			(hide yes)
			(effects
				(font
					(size 1 1)
					(thickness 0.15)
				)
			)
		)
		(property "MPN" "CR0402-FX-5101GLF"
			(at 201.168 -77.216 0)
			(layer "F.Fab")
			(hide yes)
			(effects
				(font
					(size 1 1)
					(thickness 0.15)
				)
			)
		)
		(property "Manufacturer" "Bourns"
			(at 201.168 -77.216 0)
			(layer "F.Fab")
			(hide yes)
			(effects
				(font
					(size 1 1)
					(thickness 0.15)
				)
			)
		)
		(property "Tolerance" "1%"
			(at 201.168 -77.216 0)
			(layer "F.Fab")
			(hide yes)
			(effects
				(font
					(size 1 1)
					(thickness 0.15)
				)
			)
		)
		(property "Val" "5k1"
			(at 201.168 -77.216 0)
			(layer "F.Fab")
			(hide yes)
			(effects
				(font
					(size 1 1)
					(thickness 0.15)
				)
			)
		)
		(sheetname "/Power/")
		(sheetfile "power.kicad_sch")
		(attr smd)
		(fp_rect
			(start -0.925 -0.47)
			(end 0.925 0.47)
			(stroke
				(width 0.05)
				(type default)
			)
			(fill no)
			(layer "F.CrtYd")
		)
		(fp_rect
			(start -0.5 -0.25)
			(end 0.5 0.25)
			(stroke
				(width 0.15)
				(type solid)
			)
			(fill no)
			(layer "F.Fab")
		)
		(pad "1" smd roundrect
			(at -0.48 0 90)
			(size 0.59 0.64)
			(layers "F.Cu" "F.Mask" "F.Paste")
			(roundrect_rratio 0.25)
			(net 4 "+12V")
			(pintype "passive")
		)
		(pad "2" smd roundrect
			(at 0.48 0 90)
			(size 0.59 0.64)
			(layers "F.Cu" "F.Mask" "F.Paste")
			(roundrect_rratio 0.25)
			(net 52 "Net-(L2-Pad2)")
			(pintype "passive")
		)
	)
	(footprint "antmicro-footprints:SOT-363"
		(layer "F.Cu")
		(at 178.308 56.642)
		(property "Reference" "Q3"
			(at 1.321273 0.068518 0)
			(layer "F.SilkS")
			(effects
				(font
					(size 0.7 0.7)
					(thickness 0.15)
				)
				(justify left bottom)
			)
		)
		(property "Value" "DZDH0401DW"
			(at 0 2.2 0)
			(layer "F.Fab")
			(effects
				(font
					(size 0.7 0.7)
					(thickness 0.15)
				)
				(justify left bottom)
			)
		)
		(property "Datasheet" "https://www.mouser.com/datasheet/2/115/DIOD_S_A0011803041_1-2543705.pdf"
			(at 0 0 0)
			(layer "F.Fab")
			(hide yes)
			(effects
				(font
					(size 1.27 1.27)
					(thickness 0.15)
				)
			)
		)
		(property "Description" "OR Controller N+1 ORing Controller P-Channel 1:1 SOT-363"
			(at 0 0 0)
			(layer "F.Fab")
			(hide yes)
			(effects
				(font
					(size 1.27 1.27)
					(thickness 0.15)
				)
			)
		)
		(property "Author" "Antmicro"
			(at 0 0 0)
			(layer "F.Fab")
			(hide yes)
			(effects
				(font
					(size 1 1)
					(thickness 0.15)
				)
			)
		)
		(property "License" "Apache-2.0"
			(at 0 0 0)
			(layer "F.Fab")
			(hide yes)
			(effects
				(font
					(size 1 1)
					(thickness 0.15)
				)
			)
		)
		(property "MPN" "DZDH0401DW"
			(at 0 0 0)
			(layer "F.Fab")
			(hide yes)
			(effects
				(font
					(size 1 1)
					(thickness 0.15)
				)
			)
		)
		(property "Manufacturer" "Diodes Incorporated"
			(at 0 0 0)
			(layer "F.Fab")
			(hide yes)
			(effects
				(font
					(size 1 1)
					(thickness 0.15)
				)
			)
		)
		(sheetname "/Power/")
		(sheetfile "power.kicad_sch")
		(attr smd)
		(fp_line
			(start -0.8 1.146)
			(end -0.8 1.223)
			(stroke
				(width 0.15)
				(type solid)
			)
			(layer "F.SilkS")
		)
		(fp_line
			(start -0.8 1.223)
			(end 0.803 1.223)
			(stroke
				(width 0.15)
				(type solid)
			)
			(layer "F.SilkS")
		)
		(fp_line
			(start -0.72 -1.153)
			(end -0.72 -1.228)
			(stroke
				(width 0.15)
				(type solid)
			)
			(layer "F.SilkS")
		)
		(fp_line
			(start 0.803 -1.228)
			(end -0.72 -1.228)
			(stroke
				(width 0.15)
				(type solid)
			)
			(layer "F.SilkS")
		)
		(fp_line
			(start 0.803 -1.153)
			(end 0.803 -1.228)
			(stroke
				(width 0.15)
				(type solid)
			)
			(layer "F.SilkS")
		)
		(fp_line
			(start 0.803 1.146)
			(end 0.803 1.223)
			(stroke
				(width 0.15)
				(type solid)
			)
			(layer "F.SilkS")
		)
		(fp_circle
			(center -0.978102 -1.2)
			(end -0.928102 -1.2)
			(stroke
				(width 0.15)
				(type solid)
			)
			(fill yes)
			(layer "F.SilkS")
		)
		(fp_rect
			(start 1.3 -1.3)
			(end -1.3 1.3)
			(stroke
				(width 0.05)
				(type solid)
			)
			(fill no)
			(layer "F.CrtYd")
		)
		(fp_line
			(start -0.1 -1.1)
			(end -0.68 -0.52)
			(stroke
				(width 0.15)
				(type solid)
			)
			(layer "F.Fab")
		)
		(fp_rect
			(start 0.68 1.1)
			(end -0.68 -1.1)
			(stroke
				(width 0.15)
				(type solid)
			)
			(fill no)
			(layer "F.Fab")
		)
		(pad "1" smd custom
			(at -0.948 -0.752 270)
			(size 0.6 0.6)
			(layers "F.Cu" "F.Mask" "F.Paste")
			(net 149 "unconnected-(Q3-NC-Pad1)")
			(pinfunction "NC")
			(pintype "no_connect")
			(options
				(clearance outline)
				(anchor rect)
			)
			(primitives)
		)
		(pad "2" smd rect
			(at -0.948 -0.002 270)
			(size 0.4 0.6)
			(layers "F.Cu" "F.Mask" "F.Paste")
			(net 128 "Net-(Q3-REF)")
			(pinfunction "REF")
			(pintype "input")
		)
		(pad "3" smd custom
			(at -0.948 0.745 270)
			(size 0.6 0.6)
			(layers "F.Cu" "F.Mask" "F.Paste")
			(net 127 "Net-(Q2-G)")
			(pinfunction "BIAS")
			(pintype "output")
			(options
				(clearance outline)
				(anchor rect)
			)
			(primitives)
		)
		(pad "4" smd custom
			(at 0.951 0.745 270)
			(size 0.6 0.6)
			(layers "F.Cu" "F.Mask" "F.Paste")
			(net 4 "+12V")
			(pinfunction "S")
			(pintype "power_in")
			(options
				(clearance outline)
				(anchor rect)
			)
			(primitives)
		)
		(pad "5" smd rect
			(at 0.951 -0.002 270)
			(size 0.4 0.6)
			(layers "F.Cu" "F.Mask" "F.Paste")
			(net 148 "unconnected-(Q3-NC-Pad5)")
			(pinfunction "NC")
			(pintype "no_connect")
		)
		(pad "6" smd custom
			(at 0.951 -0.752 270)
			(size 0.6 0.6)
			(layers "F.Cu" "F.Mask" "F.Paste")
			(net 118 "/Connectors/DC_IN")
			(pinfunction "D")
			(pintype "power_in")
			(options
				(clearance outline)
				(anchor rect)
			)
			(primitives)
		)
	)
	(footprint "antmicro-footprints:SOT-23-5"
		(layer "F.Cu")
		(at 169.926 61.087 -90)
		(property "Reference" "U1"
			(at 2.413 1.778 90)
			(layer "F.SilkS")
			(effects
				(font
					(size 0.7 0.7)
					(thickness 0.15)
				)
				(justify left bottom)
			)
		)
		(property "Value" "SN74LV1T125DBVR"
			(at 0.002 2.799 90)
			(layer "F.Fab")
			(effects
				(font
					(size 0.7 0.7)
					(thickness 0.15)
				)
				(justify right bottom)
			)
		)
		(property "Datasheet" "https://www.ti.com/lit/ds/symlink/sn74lv1t125.pdf?HQS=dis-mous-null-mousermode-dsf-pf-null-wwe&ts=1627648952184&ref_url=https%253A%252F%252Fmouser.com%252F"
			(at 0 0 270)
			(layer "F.Fab")
			(hide yes)
			(effects
				(font
					(size 1.27 1.27)
					(thickness 0.15)
				)
			)
		)
		(property "Description" "Buffer, 74LV1T125, 1.6 V to 5.5 V, SOT-23-5"
			(at 0 0 270)
			(layer "F.Fab")
			(hide yes)
			(effects
				(font
					(size 1.27 1.27)
					(thickness 0.15)
				)
			)
		)
		(property "Author" "Antmicro"
			(at 108.839 231.013 0)
			(layer "F.Fab")
			(hide yes)
			(effects
				(font
					(size 1 1)
					(thickness 0.15)
				)
			)
		)
		(property "License" "Apache-2.0"
			(at 108.839 231.013 0)
			(layer "F.Fab")
			(hide yes)
			(effects
				(font
					(size 1 1)
					(thickness 0.15)
				)
			)
		)
		(property "MPN" "SN74LV1T125DBVR"
			(at 108.839 231.013 0)
			(layer "F.Fab")
			(hide yes)
			(effects
				(font
					(size 1 1)
					(thickness 0.15)
				)
			)
		)
		(property "Manufacturer" "Texas Instruments"
			(at 108.839 231.013 0)
			(layer "F.Fab")
			(hide yes)
			(effects
				(font
					(size 1 1)
					(thickness 0.15)
				)
			)
		)
		(sheetname "/Connectors/")
		(sheetfile "connectors.kicad_sch")
		(attr smd)
		(fp_line
			(start -0.85 1.6)
			(end -0.85 1.301)
			(stroke
				(width 0.15)
				(type solid)
			)
			(layer "F.SilkS")
		)
		(fp_line
			(start -0.55 1.6)
			(end -0.85 1.6)
			(stroke
				(width 0.15)
				(type solid)
			)
			(layer "F.SilkS")
		)
		(fp_line
			(start 0.8 1.599)
			(end 0.549 1.599)
			(stroke
				(width 0.15)
				(type solid)
			)
			(layer "F.SilkS")
		)
		(fp_line
			(start 0.8 1.3)
			(end 0.8 1.599)
			(stroke
				(width 0.15)
				(type solid)
			)
			(layer "F.SilkS")
		)
		(fp_line
			(start 0.8 0.55)
			(end 0.8 -0.55)
			(stroke
				(width 0.15)
				(type solid)
			)
			(layer "F.SilkS")
		)
		(fp_line
			(start 0.8 -1.3)
			(end 0.8 -1.6)
			(stroke
				(width 0.15)
				(type solid)
			)
			(layer "F.SilkS")
		)
		(fp_line
			(start -0.8 -1.6)
			(end -0.8 -1.3)
			(stroke
				(width 0.15)
				(type solid)
			)
			(layer "F.SilkS")
		)
		(fp_line
			(start -0.8 -1.6)
			(end -0.5 -1.6)
			(stroke
				(width 0.15)
				(type solid)
			)
			(layer "F.SilkS")
		)
		(fp_line
			(start 0.8 -1.6)
			(end 0.5 -1.6)
			(stroke
				(width 0.15)
				(type solid)
			)
			(layer "F.SilkS")
		)
		(fp_circle
			(center -1.25 -1.5)
			(end -1.2 -1.5)
			(stroke
				(width 0.15)
				(type solid)
			)
			(fill yes)
			(layer "F.SilkS")
		)
		(fp_rect
			(start 1.9 -1.76)
			(end -1.9 1.75)
			(stroke
				(width 0.05)
				(type solid)
			)
			(fill no)
			(layer "F.CrtYd")
		)
		(fp_line
			(start -0.398 -1.526)
			(end -0.874 -1.05)
			(stroke
				(width 0.15)
				(type solid)
			)
			(layer "F.Fab")
		)
		(fp_rect
			(start 0.874 1.523)
			(end -0.873 -1.525)
			(stroke
				(width 0.15)
				(type solid)
			)
			(fill no)
			(layer "F.Fab")
		)
		(pad "1" smd rect
			(at -1.351 -0.951 180)
			(size 0.55 1)
			(layers "F.Cu" "F.Mask" "F.Paste")
			(net 129 "Net-(U1-~{OE})")
			(pinfunction "~{OE}")
			(pintype "input")
		)
		(pad "2" smd rect
			(at -1.351 0 180)
			(size 0.55 1)
			(layers "F.Cu" "F.Mask" "F.Paste")
			(net 67 "/Connectors/VSYNC_CAM0")
			(pinfunction "A")
			(pintype "input")
		)
		(pad "3" smd rect
			(at -1.351 0.949 180)
			(size 0.55 1)
			(layers "F.Cu" "F.Mask" "F.Paste")
			(net 1 "GND")
			(pinfunction "GND")
			(pintype "power_in")
		)
		(pad "4" smd rect
			(at 1.35 0.949 180)
			(size 0.55 1)
			(layers "F.Cu" "F.Mask" "F.Paste")
			(net 130 "Net-(U1-Y)")
			(pinfunction "Y")
			(pintype "output")
		)
		(pad "5" smd rect
			(at 1.35 -0.951 180)
			(size 0.55 1)
			(layers "F.Cu" "F.Mask" "F.Paste")
			(net 3 "+1V8")
			(pinfunction "VCC")
			(pintype "power_in")
		)
	)
	(footprint "antmicro-footprints:R_0402_1005Metric"
		(layer "F.Cu")
		(at 144.708 73.66 -90)
		(descr "Resistor SMD 0402")
		(tags "resistor SMD 0402")
		(property "Reference" "R47"
			(at -3.0226 1.325 90)
			(layer "F.SilkS")
			(effects
				(font
					(size 0.7 0.7)
					(thickness 0.15)
				)
				(justify right bottom)
			)
		)
		(property "Value" "R_0R_0402"
			(at -1.011843 1.772047 90)
			(layer "F.Fab")
			(effects
				(font
					(size 0.7 0.7)
					(thickness 0.15)
				)
				(justify right bottom)
			)
		)
		(property "Datasheet" "https://industrial.panasonic.com/cdbs/www-data/pdf/RDA0000/AOA0000C301.pdf"
			(at 0 0 270)
			(layer "F.Fab")
			(hide yes)
			(effects
				(font
					(size 1.27 1.27)
					(thickness 0.15)
				)
			)
		)
		(property "Description" "SMD Chip Resistor, Jumper, 0 ohm, 100 mW, 0402 [1005 Metric], Thick Film, General Purpose"
			(at 0 0 270)
			(layer "F.Fab")
			(hide yes)
			(effects
				(font
					(size 1.27 1.27)
					(thickness 0.15)
				)
			)
		)
		(property "Author" "Antmicro"
			(at 71.048 218.368 0)
			(layer "F.Fab")
			(hide yes)
			(effects
				(font
					(size 1 1)
					(thickness 0.15)
				)
			)
		)
		(property "Current" "1A"
			(at 71.048 218.368 0)
			(layer "F.Fab")
			(hide yes)
			(effects
				(font
					(size 1 1)
					(thickness 0.15)
				)
			)
		)
		(property "License" "Apache-2.0"
			(at 71.048 218.368 0)
			(layer "F.Fab")
			(hide yes)
			(effects
				(font
					(size 1 1)
					(thickness 0.15)
				)
			)
		)
		(property "MPN" "ERJ2GE0R00X"
			(at 71.048 218.368 0)
			(layer "F.Fab")
			(hide yes)
			(effects
				(font
					(size 1 1)
					(thickness 0.15)
				)
			)
		)
		(property "Manufacturer" "Panasonic"
			(at 71.048 218.368 0)
			(layer "F.Fab")
			(hide yes)
			(effects
				(font
					(size 1 1)
					(thickness 0.15)
				)
			)
		)
		(property "Tolerance" ""
			(at 71.048 218.368 0)
			(layer "F.Fab")
			(hide yes)
			(effects
				(font
					(size 1 1)
					(thickness 0.15)
				)
			)
		)
		(property "Val" "0R"
			(at 71.048 218.368 0)
			(layer "F.Fab")
			(hide yes)
			(effects
				(font
					(size 1 1)
					(thickness 0.15)
				)
			)
		)
		(sheetname "/Deserializer/")
		(sheetfile "deserializer.kicad_sch")
		(attr smd)
		(fp_rect
			(start -0.925 -0.47)
			(end 0.925 0.47)
			(stroke
				(width 0.05)
				(type default)
			)
			(fill no)
			(layer "F.CrtYd")
		)
		(fp_rect
			(start -0.5 -0.25)
			(end 0.5 0.25)
			(stroke
				(width 0.15)
				(type solid)
			)
			(fill no)
			(layer "F.Fab")
		)
		(pad "1" smd roundrect
			(at -0.48 0 270)
			(size 0.59 0.64)
			(layers "F.Cu" "F.Mask" "F.Paste")
			(roundrect_rratio 0.25)
			(net 17 "/Deserializer/X2_R")
			(pintype "passive")
		)
		(pad "2" smd roundrect
			(at 0.48 0 270)
			(size 0.59 0.64)
			(layers "F.Cu" "F.Mask" "F.Paste")
			(roundrect_rratio 0.25)
			(net 75 "/Deserializer/X2")
			(pintype "passive")
		)
	)
	(footprint "antmicro-footprints:L_Coilcraft-MSS6132T"
		(layer "F.Cu")
		(at 123.19 61.976 90)
		(property "Reference" "L1"
			(at -0.635 -3.556 90)
			(layer "F.SilkS")
			(effects
				(font
					(size 0.7 0.7)
					(thickness 0.15)
				)
				(justify left bottom)
			)
		)
		(property "Value" "L_22u_1.12A_Coilcraft-MSS6132T"
			(at -0.508 4.826 90)
			(layer "F.Fab")
			(effects
				(font
					(size 0.7 0.7)
					(thickness 0.15)
				)
				(justify left bottom)
			)
		)
		(property "Datasheet" "https://www.coilcraft.com/getmedia/d035c9b3-191d-46aa-ab3f-5c1a849157c1/mss6132t.pdf"
			(at 0 0 90)
			(layer "F.Fab")
			(hide yes)
			(effects
				(font
					(size 1.27 1.27)
					(thickness 0.15)
				)
			)
		)
		(property "Description" "Power Inductor (SMT), 22 µH, 1.85 A, Shielded, 2.45 A, WE-MAPI"
			(at 0 0 90)
			(layer "F.Fab")
			(hide yes)
			(effects
				(font
					(size 1.27 1.27)
					(thickness 0.15)
				)
			)
		)
		(property "Author" "Antmicro"
			(at 185.166 -61.214 0)
			(layer "F.Fab")
			(hide yes)
			(effects
				(font
					(size 1 1)
					(thickness 0.15)
				)
			)
		)
		(property "IMax" "1.45A"
			(at 185.166 -61.214 0)
			(layer "F.Fab")
			(hide yes)
			(effects
				(font
					(size 1 1)
					(thickness 0.15)
				)
			)
		)
		(property "ISat" "1.12A"
			(at 185.166 -61.214 0)
			(layer "F.Fab")
			(hide yes)
			(effects
				(font
					(size 1 1)
					(thickness 0.15)
				)
			)
		)
		(property "License" "Apache-2.0"
			(at 185.166 -61.214 0)
			(layer "F.Fab")
			(hide yes)
			(effects
				(font
					(size 1 1)
					(thickness 0.15)
				)
			)
		)
		(property "MPN" "MSS6132T-223"
			(at 185.166 -61.214 0)
			(layer "F.Fab")
			(hide yes)
			(effects
				(font
					(size 1 1)
					(thickness 0.15)
				)
			)
		)
		(property "Manufacturer" "Coilcraft"
			(at 185.166 -61.214 0)
			(layer "F.Fab")
			(hide yes)
			(effects
				(font
					(size 1 1)
					(thickness 0.15)
				)
			)
		)
		(property "Size" "6.1x6.1"
			(at 185.166 -61.214 0)
			(layer "F.Fab")
			(hide yes)
			(effects
				(font
					(size 1 1)
					(thickness 0.15)
				)
			)
		)
		(property "Val" "22u/1.12A"
			(at 185.166 -61.214 0)
			(layer "F.Fab")
			(hide yes)
			(effects
				(font
					(size 1 1)
					(thickness 0.15)
				)
			)
		)
		(sheetname "/Power/")
		(sheetfile "power.kicad_sch")
		(attr smd)
		(fp_line
			(start -0.8 -3.05)
			(end 0.8 -3.05)
			(stroke
				(width 0.15)
				(type solid)
			)
			(layer "F.SilkS")
		)
		(fp_line
			(start -0.8 3.05)
			(end 0.8 3.05)
			(stroke
				(width 0.15)
				(type solid)
			)
			(layer "F.SilkS")
		)
		(fp_rect
			(start -3.35 -3.35)
			(end 3.35 3.35)
			(stroke
				(width 0.05)
				(type solid)
			)
			(fill no)
			(layer "F.CrtYd")
		)
		(fp_rect
			(start -3.1 -3.1)
			(end 3.1 3.1)
			(stroke
				(width 0.15)
				(type solid)
			)
			(fill no)
			(layer "F.Fab")
		)
		(pad "1" smd custom
			(at -2.71 0 180)
			(size 6 0.575)
			(layers "F.Cu" "F.Mask" "F.Paste")
			(net 4 "+12V")
			(pintype "passive")
			(options
				(clearance outline)
				(anchor rect)
			)
			(primitives
				(gr_poly
					(pts
						(xy 2.4 1.71) (xy 2.117646 1.21) (xy 1.9 0.96) (xy 1.65 0.71) (xy 1.2 0.41) (xy 0.4 0.11) (xy 0.4 0.01)
						(xy 2.9 0) (xy 2.9 1.71)
					)
					(width 0.2)
					(fill yes)
				)
				(gr_poly
					(pts
						(xy -2.4 1.731128) (xy -2.117646 1.231128) (xy -1.9 0.981128) (xy -1.65 0.731128) (xy -1.2 0.431128)
						(xy -0.4 0.131128) (xy -0.4 0.031128) (xy -2.9 0.021128) (xy -2.9 1.731128)
					)
					(width 0.2)
					(fill yes)
				)
			)
		)
		(pad "2" smd custom
			(at 2.71 0)
			(size 6 0.575)
			(layers "F.Cu" "F.Mask" "F.Paste")
			(net 51 "Net-(L1-Pad2)")
			(pintype "passive")
			(options
				(clearance outline)
				(anchor rect)
			)
			(primitives
				(gr_poly
					(pts
						(xy -2.4 1.731128) (xy -2.117646 1.231128) (xy -1.9 0.981128) (xy -1.65 0.731128) (xy -1.2 0.431128)
						(xy -0.4 0.131128) (xy -0.4 0.031128) (xy -2.9 0.021128) (xy -2.9 1.731128)
					)
					(width 0.2)
					(fill yes)
				)
				(gr_poly
					(pts
						(xy 2.4 1.71) (xy 2.117646 1.21) (xy 1.9 0.96) (xy 1.65 0.71) (xy 1.2 0.41) (xy 0.4 0.11) (xy 0.4 0.01)
						(xy 2.9 0) (xy 2.9 1.71)
					)
					(width 0.2)
					(fill yes)
				)
			)
		)
	)
	(footprint "antmicro-footprints:LED_0603_1608Metric_G"
		(layer "F.Cu")
		(at 153.924 96.11 -90)
		(descr "LED SMD 0603 Green")
		(tags "LED SMD 0603 Green")
		(property "Reference" "D15"
			(at -0.86 35.507333 0)
			(layer "F.SilkS")
			(effects
				(font
					(size 0.7 0.7)
					(thickness 0.15)
				)
				(justify right bottom)
			)
		)
		(property "Value" "LED_G_0603_LTST-C190GKT"
			(at -0.001 1.599 90)
			(layer "F.Fab")
			(effects
				(font
					(size 0.7 0.7)
					(thickness 0.15)
				)
				(justify right bottom)
			)
		)
		(property "Datasheet" "https://media.digikey.com/pdf/Data%20Sheets/Lite-On%20PDFs/LTST-C190GKT.pdf"
			(at 0 0 270)
			(layer "F.Fab")
			(hide yes)
			(effects
				(font
					(size 1.27 1.27)
					(thickness 0.15)
				)
			)
		)
		(property "Description" "LED, Green, SMD, 0603, 20 mA, 2.1 V, 569 nm"
			(at 0 0 270)
			(layer "F.Fab")
			(hide yes)
			(effects
				(font
					(size 1.27 1.27)
					(thickness 0.15)
				)
			)
		)
		(property "Author" "Antmicro"
			(at 57.814 250.034 0)
			(layer "F.Fab")
			(hide yes)
			(effects
				(font
					(size 1 1)
					(thickness 0.15)
				)
			)
		)
		(property "Color" "Green"
			(at 57.814 250.034 0)
			(layer "F.Fab")
			(hide yes)
			(effects
				(font
					(size 1 1)
					(thickness 0.15)
				)
			)
		)
		(property "License" "Apache-2.0"
			(at 57.814 250.034 0)
			(layer "F.Fab")
			(hide yes)
			(effects
				(font
					(size 1 1)
					(thickness 0.15)
				)
			)
		)
		(property "MPN" "LTST-C190GKT"
			(at 57.814 250.034 0)
			(layer "F.Fab")
			(hide yes)
			(effects
				(font
					(size 1 1)
					(thickness 0.15)
				)
			)
		)
		(property "Manufacturer" "Lite-On"
			(at 57.814 250.034 0)
			(layer "F.Fab")
			(hide yes)
			(effects
				(font
					(size 1 1)
					(thickness 0.15)
				)
			)
		)
		(property "VSD_class" "LED"
			(at 57.814 250.034 0)
			(layer "F.Fab")
			(hide yes)
			(effects
				(font
					(size 1 1)
					(thickness 0.15)
				)
			)
		)
		(sheetname "/Power/")
		(sheetfile "power.kicad_sch")
		(attr smd)
		(fp_line
			(start 0.22 0.35)
			(end -0.22 0.35)
			(stroke
				(width 0.15)
				(type solid)
			)
			(layer "F.SilkS")
		)
		(fp_line
			(start -0.094672 0.201008)
			(end -0.094672 -0.198992)
			(stroke
				(width 0.1)
				(type solid)
			)
			(layer "F.SilkS")
		)
		(fp_line
			(start 0.105328 0.201008)
			(end -0.094672 0.001008)
			(stroke
				(width 0.1)
				(type solid)
			)
			(layer "F.SilkS")
		)
		(fp_line
			(start 0.105328 0.201008)
			(end 0.105328 -0.198992)
			(stroke
				(width 0.1)
				(type solid)
			)
			(layer "F.SilkS")
		)
		(fp_line
			(start -0.094672 0.001008)
			(end -0.24 0.001008)
			(stroke
				(width 0.1)
				(type solid)
			)
			(layer "F.SilkS")
		)
		(fp_line
			(start -0.094672 0.001008)
			(end 0.105328 -0.198992)
			(stroke
				(width 0.1)
				(type solid)
			)
			(layer "F.SilkS")
		)
		(fp_line
			(start 0.105328 0.001008)
			(end 0.24 0.001)
			(stroke
				(width 0.1)
				(type solid)
			)
			(layer "F.SilkS")
		)
		(fp_line
			(start -1.18 -0.319)
			(end -1.18 0.321)
			(stroke
				(width 0.15)
				(type solid)
			)
			(layer "F.SilkS")
		)
		(fp_line
			(start 0.22 -0.35)
			(end -0.22 -0.35)
			(stroke
				(width 0.15)
				(type solid)
			)
			(layer "F.SilkS")
		)
		(fp_rect
			(start 1.25 0.65)
			(end -1.25 -0.65)
			(stroke
				(width 0.05)
				(type solid)
			)
			(fill no)
			(layer "F.CrtYd")
		)
		(fp_line
			(start -0.199 0.2)
			(end -0.199 0.1)
			(stroke
				(width 0.15)
				(type solid)
			)
			(layer "F.Fab")
		)
		(fp_line
			(start 0.201 0.2)
			(end 0.201 0)
			(stroke
				(width 0.15)
				(type solid)
			)
			(layer "F.Fab")
		)
		(fp_line
			(start -0.199 0)
			(end -0.597 0)
			(stroke
				(width 0.15)
				(type solid)
			)
			(layer "F.Fab")
		)
		(fp_line
			(start -0.101 0)
			(end 0.201 0.2)
			(stroke
				(width 0.15)
				(type solid)
			)
			(layer "F.Fab")
		)
		(fp_line
			(start 0.201 0)
			(end 0.201 -0.202)
			(stroke
				(width 0.15)
				(type solid)
			)
			(layer "F.Fab")
		)
		(fp_line
			(start 0.599 0)
			(end 0.201 0)
			(stroke
				(width 0.15)
				(type solid)
			)
			(layer "F.Fab")
		)
		(fp_line
			(start -0.199 -0.202)
			(end -0.199 0.1)
			(stroke
				(width 0.15)
				(type solid)
			)
			(layer "F.Fab")
		)
		(fp_line
			(start 0.201 -0.202)
			(end -0.101 0)
			(stroke
				(width 0.15)
				(type solid)
			)
			(layer "F.Fab")
		)
		(fp_rect
			(start 0.848 0.4)
			(end -0.85 -0.402)
			(stroke
				(width 0.15)
				(type solid)
			)
			(fill no)
			(layer "F.Fab")
		)
		(pad "1" smd roundrect
			(at -0.7 0 90)
			(size 0.8 1)
			(layers "F.Cu" "F.Mask" "F.Paste")
			(roundrect_rratio 0.2)
			(net 112 "Net-(D15-C)")
			(pinfunction "C")
			(pintype "passive")
		)
		(pad "2" smd roundrect
			(at 0.7 0 90)
			(size 0.8 1)
			(layers "F.Cu" "F.Mask" "F.Paste")
			(roundrect_rratio 0.2)
			(net 118 "/Connectors/DC_IN")
			(pinfunction "A")
			(pintype "passive")
		)
	)
	(footprint "antmicro-footprints:R_0402_1005Metric"
		(layer "F.Cu")
		(at 177.804 54.609 180)
		(descr "Resistor SMD 0402")
		(tags "resistor SMD 0402")
		(property "Reference" "R15"
			(at -2.846 -0.741 0)
			(layer "F.SilkS")
			(effects
				(font
					(size 0.7 0.7)
					(thickness 0.15)
				)
				(justify right bottom)
			)
		)
		(property "Value" "R_100R_0402"
			(at -1.011843 1.772047 0)
			(layer "F.Fab")
			(effects
				(font
					(size 0.7 0.7)
					(thickness 0.15)
				)
				(justify right bottom)
			)
		)
		(property "Datasheet" "https://www.bourns.com/docs/product-datasheets/cr.pdf"
			(at 0 0 180)
			(layer "F.Fab")
			(hide yes)
			(effects
				(font
					(size 1.27 1.27)
					(thickness 0.15)
				)
			)
		)
		(property "Description" "SMD Chip Resistor, 100 ohm, ± 1%, 62.5 mW, 0402 [1005 Metric], Thick Film, General Purpose"
			(at 0 0 180)
			(layer "F.Fab")
			(hide yes)
			(effects
				(font
					(size 1.27 1.27)
					(thickness 0.15)
				)
			)
		)
		(property "Author" "Antmicro"
			(at 355.608 109.218 0)
			(layer "F.Fab")
			(hide yes)
			(effects
				(font
					(size 1 1)
					(thickness 0.15)
				)
			)
		)
		(property "License" "Apache-2.0"
			(at 355.608 109.218 0)
			(layer "F.Fab")
			(hide yes)
			(effects
				(font
					(size 1 1)
					(thickness 0.15)
				)
			)
		)
		(property "MPN" "CR0402-FX-1000GLF"
			(at 355.608 109.218 0)
			(layer "F.Fab")
			(hide yes)
			(effects
				(font
					(size 1 1)
					(thickness 0.15)
				)
			)
		)
		(property "Manufacturer" "Bourns"
			(at 355.608 109.218 0)
			(layer "F.Fab")
			(hide yes)
			(effects
				(font
					(size 1 1)
					(thickness 0.15)
				)
			)
		)
		(property "Tolerance" "1%"
			(at 355.608 109.218 0)
			(layer "F.Fab")
			(hide yes)
			(effects
				(font
					(size 1 1)
					(thickness 0.15)
				)
			)
		)
		(property "Val" "100R"
			(at 355.608 109.218 0)
			(layer "F.Fab")
			(hide yes)
			(effects
				(font
					(size 1 1)
					(thickness 0.15)
				)
			)
		)
		(sheetname "/Power/")
		(sheetfile "power.kicad_sch")
		(attr smd)
		(fp_rect
			(start -0.925 -0.47)
			(end 0.925 0.47)
			(stroke
				(width 0.05)
				(type default)
			)
			(fill no)
			(layer "F.CrtYd")
		)
		(fp_rect
			(start -0.5 -0.25)
			(end 0.5 0.25)
			(stroke
				(width 0.15)
				(type solid)
			)
			(fill no)
			(layer "F.Fab")
		)
		(pad "1" smd roundrect
			(at -0.48 0 180)
			(size 0.59 0.64)
			(layers "F.Cu" "F.Mask" "F.Paste")
			(roundrect_rratio 0.25)
			(net 126 "Net-(Q1-G)")
			(pintype "passive")
		)
		(pad "2" smd roundrect
			(at 0.48 0 180)
			(size 0.59 0.64)
			(layers "F.Cu" "F.Mask" "F.Paste")
			(roundrect_rratio 0.25)
			(net 118 "/Connectors/DC_IN")
			(pintype "passive")
		)
	)
	(footprint "antmicro-footprints:TP_SMD_0.75mm"
		(layer "F.Cu")
		(at 144.78 97.89)
		(property "Reference" "TP13"
			(at 0 -0.6 0)
			(layer "F.SilkS")
			(hide yes)
			(effects
				(font
					(size 0.7 0.7)
					(thickness 0.15)
				)
				(justify left bottom)
			)
		)
		(property "Value" "TP_0.75mm_SMD"
			(at 0 1.2 0)
			(layer "F.Fab")
			(effects
				(font
					(size 0.7 0.7)
					(thickness 0.15)
				)
				(justify left bottom)
			)
		)
		(property "Description" "SMT test point"
			(at 0 0 0)
			(layer "F.Fab")
			(hide yes)
			(effects
				(font
					(size 1.27 1.27)
					(thickness 0.15)
				)
			)
		)
		(property "Author" "Antmicro"
			(at 0 0 0)
			(layer "F.Fab")
			(hide yes)
			(effects
				(font
					(size 1 1)
					(thickness 0.15)
				)
			)
		)
		(property "License" "Apache-2.0"
			(at 0 0 0)
			(layer "F.Fab")
			(hide yes)
			(effects
				(font
					(size 1 1)
					(thickness 0.15)
				)
			)
		)
		(property "MPN" ""
			(at 0 0 0)
			(layer "F.Fab")
			(hide yes)
			(effects
				(font
					(size 1 1)
					(thickness 0.15)
				)
			)
		)
		(property "Manufacturer" ""
			(at 0 0 0)
			(layer "F.Fab")
			(hide yes)
			(effects
				(font
					(size 1 1)
					(thickness 0.15)
				)
			)
		)
		(sheetname "/Power/")
		(sheetfile "power.kicad_sch")
		(fp_circle
			(center 0 0)
			(end 0.475 0)
			(stroke
				(width 0.05)
				(type default)
			)
			(fill no)
			(layer "F.CrtYd")
		)
		(pad "1" smd circle
			(at 0 0)
			(size 0.75 0.75)
			(layers "F.Cu" "F.Mask")
			(net 10 "/Power/OUT_1V8")
			(pinfunction "1")
			(pintype "passive")
		)
	)
	(footprint "antmicro-footprints:TP_SMD_0.75mm"
		(layer "B.Cu")
		(at 157.25 76.05 180)
		(property "Reference" "TP25"
			(at 0 0.6 0)
			(layer "B.SilkS")
			(hide yes)
			(effects
				(font
					(size 0.7 0.7)
					(thickness 0.15)
				)
				(justify left bottom mirror)
			)
		)
		(property "Value" "TP_0.75mm_SMD"
			(at 0 -1.2 0)
			(layer "B.Fab")
			(effects
				(font
					(size 0.7 0.7)
					(thickness 0.15)
				)
				(justify left bottom mirror)
			)
		)
		(property "Description" "SMT test point"
			(at 0 0 0)
			(layer "B.Fab")
			(hide yes)
			(effects
				(font
					(size 1.27 1.27)
					(thickness 0.15)
				)
				(justify mirror)
			)
		)
		(property "MPN" ""
			(at 0 0 0)
			(unlocked yes)
			(layer "B.Fab")
			(hide yes)
			(effects
				(font
					(size 1 1)
					(thickness 0.15)
				)
				(justify mirror)
			)
		)
		(property "Manufacturer" ""
			(at 0 0 0)
			(unlocked yes)
			(layer "B.Fab")
			(hide yes)
			(effects
				(font
					(size 1 1)
					(thickness 0.15)
				)
				(justify mirror)
			)
		)
		(property "Author" "Antmicro"
			(at 0 0 0)
			(unlocked yes)
			(layer "B.Fab")
			(hide yes)
			(effects
				(font
					(size 1 1)
					(thickness 0.15)
				)
				(justify mirror)
			)
		)
		(property "License" "Apache-2.0"
			(at 0 0 0)
			(unlocked yes)
			(layer "B.Fab")
			(hide yes)
			(effects
				(font
					(size 1 1)
					(thickness 0.15)
				)
				(justify mirror)
			)
		)
		(sheetname "/Connectors/")
		(sheetfile "connectors.kicad_sch")
		(attr exclude_from_pos_files)
		(fp_circle
			(center 0 0)
			(end 0.475 0)
			(stroke
				(width 0.05)
				(type default)
			)
			(fill no)
			(layer "B.CrtYd")
		)
		(fp_text user "Author: Antmicro"
			(at -0.4 -3.901 0)
			(layer "B.Fab")
			(effects
				(font
					(size 0.7 0.7)
					(thickness 0.15)
				)
				(justify left bottom mirror)
			)
		)
		(fp_text user "${REFERENCE}"
			(at -0.4 -2.7 0)
			(layer "B.Fab")
			(effects
				(font
					(size 0.7 0.7)
					(thickness 0.15)
				)
				(justify left bottom mirror)
			)
		)
		(fp_text user "License: Apache-2.0"
			(at -0.4 -5.101 0)
			(layer "B.Fab")
			(effects
				(font
					(size 0.7 0.7)
					(thickness 0.15)
				)
				(justify left bottom mirror)
			)
		)
		(pad "1" smd circle
			(at 0 0 180)
			(size 0.75 0.75)
			(layers "B.Cu" "B.Mask")
			(net 121 "/Connectors/SCL")
			(pinfunction "1")
			(pintype "passive")
		)
	)
	(footprint "antmicro-footprints:C_0402_1005Metric"
		(layer "B.Cu")
		(at 142.588 77.056 -45)
		(descr "Capacitor SMD 0402")
		(tags "capacitor SMD 0402")
		(property "Reference" "C39"
			(at -1.52271 0.22729 315)
			(unlocked yes)
			(layer "B.SilkS")
			(effects
				(font
					(size 0.7 0.7)
					(thickness 0.15)
				)
				(justify left bottom mirror)
			)
		)
		(property "Value" "C_100n_0402"
			(at -1.022927 -2.155213 135)
			(layer "B.Fab")
			(effects
				(font
					(size 0.7 0.7)
					(thickness 0.15)
				)
				(justify left bottom mirror)
			)
		)
		(property "Datasheet" "https://www.murata.com/products/productdetail?partno=GRM155R61H104KE14%23"
			(at 0 0 315)
			(layer "F.Fab")
			(hide yes)
			(effects
				(font
					(size 1.27 1.27)
					(thickness 0.15)
				)
			)
		)
		(property "Description" "SMD Multilayer Ceramic Capacitor, 0.1 µF, 50 V, 0402 [1005 Metric], ± 10%, X5R, GRM Series"
			(at 0 0 315)
			(layer "F.Fab")
			(hide yes)
			(effects
				(font
					(size 1.27 1.27)
					(thickness 0.15)
				)
			)
		)
		(property "Author" "Antmicro"
			(at -12.790036 123.554121 0)
			(layer "B.Fab")
			(hide yes)
			(effects
				(font
					(size 1 1)
					(thickness 0.15)
				)
				(justify mirror)
			)
		)
		(property "Dielectric" "X5R"
			(at -12.790036 123.554121 0)
			(layer "B.Fab")
			(hide yes)
			(effects
				(font
					(size 1 1)
					(thickness 0.15)
				)
				(justify mirror)
			)
		)
		(property "License" "Apache-2.0"
			(at -12.790036 123.554121 0)
			(layer "B.Fab")
			(hide yes)
			(effects
				(font
					(size 1 1)
					(thickness 0.15)
				)
				(justify mirror)
			)
		)
		(property "MPN" "GRM155R61H104KE14D"
			(at -12.790036 123.554121 0)
			(layer "B.Fab")
			(hide yes)
			(effects
				(font
					(size 1 1)
					(thickness 0.15)
				)
				(justify mirror)
			)
		)
		(property "Manufacturer" "Murata"
			(at -12.790036 123.554121 0)
			(layer "B.Fab")
			(hide yes)
			(effects
				(font
					(size 1 1)
					(thickness 0.15)
				)
				(justify mirror)
			)
		)
		(property "Val" "100n"
			(at -12.790036 123.554121 0)
			(layer "B.Fab")
			(hide yes)
			(effects
				(font
					(size 1 1)
					(thickness 0.15)
				)
				(justify mirror)
			)
		)
		(property "Voltage" "50V"
			(at -12.790036 123.554121 0)
			(layer "B.Fab")
			(hide yes)
			(effects
				(font
					(size 1 1)
					(thickness 0.15)
				)
				(justify mirror)
			)
		)
		(sheetname "/Deserializer/")
		(sheetfile "deserializer.kicad_sch")
		(attr smd)
		(fp_poly
			(pts
				(xy -0.925 0.47) (xy 0.925 0.47) (xy 0.925 -0.47) (xy -0.925 -0.47)
			)
			(stroke
				(width 0.05)
				(type default)
			)
			(fill no)
			(layer "B.CrtYd")
		)
		(fp_line
			(start -0.494 0.25)
			(end -0.494 -0.248)
			(stroke
				(width 0.15)
				(type solid)
			)
			(layer "B.Fab")
		)
		(fp_line
			(start -0.494 -0.248)
			(end 0.504 -0.248)
			(stroke
				(width 0.15)
				(type solid)
			)
			(layer "B.Fab")
		)
		(fp_line
			(start 0.504 0.25)
			(end -0.494 0.25)
			(stroke
				(width 0.15)
				(type solid)
			)
			(layer "B.Fab")
		)
		(fp_line
			(start 0.504 -0.248)
			(end 0.504 0.25)
			(stroke
				(width 0.15)
				(type solid)
			)
			(layer "B.Fab")
		)
		(pad "1" smd roundrect
			(at -0.48 0 315)
			(size 0.59 0.64)
			(layers "B.Cu" "B.Mask" "B.Paste")
			(roundrect_rratio 0.25)
			(net 1 "GND")
			(pintype "passive")
		)
		(pad "2" smd roundrect
			(at 0.48 0 315)
			(size 0.59 0.64)
			(layers "B.Cu" "B.Mask" "B.Paste")
			(roundrect_rratio 0.25)
			(net 26 "/Deserializer/VDD_1.8V")
			(pintype "passive")
		)
	)
	(footprint "antmicro-footprints:R_0402_1005Metric"
		(layer "B.Cu")
		(at 146.321605 96.355897 -90)
		(descr "Resistor SMD 0402")
		(tags "resistor SMD 0402")
		(property "Reference" "R80"
			(at -5.724873 -0.425736 90)
			(layer "B.SilkS")
			(effects
				(font
					(size 0.7 0.7)
					(thickness 0.15)
				)
				(justify right bottom mirror)
			)
		)
		(property "Value" "R_470R_0402"
			(at -1.011843 -1.772046 90)
			(layer "B.Fab")
			(effects
				(font
					(size 0.7 0.7)
					(thickness 0.15)
				)
				(justify left bottom mirror)
			)
		)
		(property "Datasheet" "https://www.bourns.com/docs/product-datasheets/cr.pdf"
			(at 0 0 90)
			(layer "F.Fab")
			(hide yes)
			(effects
				(font
					(size 1.27 1.27)
					(thickness 0.15)
				)
			)
		)
		(property "Description" "SMD Chip Resistor, 470 ohm, ± 1%, 62.5 mW, 0402 [1005 Metric], Thick Film, General Purpose"
			(at 0 0 90)
			(layer "F.Fab")
			(hide yes)
			(effects
				(font
					(size 1.27 1.27)
					(thickness 0.15)
				)
			)
		)
		(property "Author" "Antmicro"
			(at -24.712942 131.716501 135)
			(layer "B.Fab")
			(hide yes)
			(effects
				(font
					(size 1 1)
					(thickness 0.15)
				)
				(justify mirror)
			)
		)
		(property "License" "Apache-2.0"
			(at -24.712942 131.716501 135)
			(layer "B.Fab")
			(hide yes)
			(effects
				(font
					(size 1 1)
					(thickness 0.15)
				)
				(justify mirror)
			)
		)
		(property "MPN" "CR0402-FX-4700GLF"
			(at -24.712942 131.716501 135)
			(layer "B.Fab")
			(hide yes)
			(effects
				(font
					(size 1 1)
					(thickness 0.15)
				)
				(justify mirror)
			)
		)
		(property "Manufacturer" "Bourns"
			(at -24.712942 131.716501 135)
			(layer "B.Fab")
			(hide yes)
			(effects
				(font
					(size 1 1)
					(thickness 0.15)
				)
				(justify mirror)
			)
		)
		(property "Tolerance" "1%"
			(at -24.712942 131.716501 135)
			(layer "B.Fab")
			(hide yes)
			(effects
				(font
					(size 1 1)
					(thickness 0.15)
				)
				(justify mirror)
			)
		)
		(property "Val" "470R"
			(at -24.712942 131.716501 135)
			(layer "B.Fab")
			(hide yes)
			(effects
				(font
					(size 1 1)
					(thickness 0.15)
				)
				(justify mirror)
			)
		)
		(sheetname "/Power/")
		(sheetfile "power.kicad_sch")
		(attr smd)
		(fp_poly
			(pts
				(xy -0.925 0.47) (xy 0.925 0.47) (xy 0.925 -0.47) (xy -0.925 -0.47)
			)
			(stroke
				(width 0.05)
				(type default)
			)
			(fill no)
			(layer "B.CrtYd")
		)
		(fp_poly
			(pts
				(xy -0.5 0.25) (xy 0.5 0.25) (xy 0.5 -0.25) (xy -0.5 -0.25)
			)
			(stroke
				(width 0.15)
				(type solid)
			)
			(fill no)
			(layer "B.Fab")
		)
		(pad "1" smd roundrect
			(at -0.48 0 270)
			(size 0.59 0.64)
			(layers "B.Cu" "B.Mask" "B.Paste")
			(roundrect_rratio 0.25)
			(net 144 "Net-(D19-A)")
			(pintype "passive")
		)
		(pad "2" smd roundrect
			(at 0.48 0 270)
			(size 0.59 0.64)
			(layers "B.Cu" "B.Mask" "B.Paste")
			(roundrect_rratio 0.25)
			(net 5 "+5V")
			(pintype "passive")
		)
	)
	(footprint "antmicro-footprints:C_0402_1005Metric"
		(layer "B.Cu")
		(at 153.67 82.55 135)
		(descr "Capacitor SMD 0402")
		(tags "capacitor SMD 0402")
		(property "Reference" "C46"
			(at -1.271377 0.032325 315)
			(unlocked yes)
			(layer "B.SilkS")
			(effects
				(font
					(size 0.7 0.7)
					(thickness 0.15)
				)
				(justify right bottom mirror)
			)
		)
		(property "Value" "C_100n_0402"
			(at -1.022927 -2.155213 135)
			(layer "B.Fab")
			(effects
				(font
					(size 0.7 0.7)
					(thickness 0.15)
				)
				(justify right bottom mirror)
			)
		)
		(property "Datasheet" "https://www.murata.com/products/productdetail?partno=GRM155R61H104KE14%23"
			(at 0 0 135)
			(layer "F.Fab")
			(hide yes)
			(effects
				(font
					(size 1.27 1.27)
					(thickness 0.15)
				)
			)
		)
		(property "Description" "SMD Multilayer Ceramic Capacitor, 0.1 µF, 50 V, 0402 [1005 Metric], ± 10%, X5R, GRM Series"
			(at 0 0 135)
			(layer "F.Fab")
			(hide yes)
			(effects
				(font
					(size 1.27 1.27)
					(thickness 0.15)
				)
			)
		)
		(property "Author" "Antmicro"
			(at 320.702764 32.260566 0)
			(layer "B.Fab")
			(hide yes)
			(effects
				(font
					(size 1 1)
					(thickness 0.15)
				)
				(justify mirror)
			)
		)
		(property "Dielectric" "X5R"
			(at 320.702764 32.260566 0)
			(layer "B.Fab")
			(hide yes)
			(effects
				(font
					(size 1 1)
					(thickness 0.15)
				)
				(justify mirror)
			)
		)
		(property "License" "Apache-2.0"
			(at 320.702764 32.260566 0)
			(layer "B.Fab")
			(hide yes)
			(effects
				(font
					(size 1 1)
					(thickness 0.15)
				)
				(justify mirror)
			)
		)
		(property "MPN" "GRM155R61H104KE14D"
			(at 320.702764 32.260566 0)
			(layer "B.Fab")
			(hide yes)
			(effects
				(font
					(size 1 1)
					(thickness 0.15)
				)
				(justify mirror)
			)
		)
		(property "Manufacturer" "Murata"
			(at 320.702764 32.260566 0)
			(layer "B.Fab")
			(hide yes)
			(effects
				(font
					(size 1 1)
					(thickness 0.15)
				)
				(justify mirror)
			)
		)
		(property "Val" "100n"
			(at 320.702764 32.260566 0)
			(layer "B.Fab")
			(hide yes)
			(effects
				(font
					(size 1 1)
					(thickness 0.15)
				)
				(justify mirror)
			)
		)
		(property "Voltage" "50V"
			(at 320.702764 32.260566 0)
			(layer "B.Fab")
			(hide yes)
			(effects
				(font
					(size 1 1)
					(thickness 0.15)
				)
				(justify mirror)
			)
		)
		(sheetname "/Deserializer/")
		(sheetfile "deserializer.kicad_sch")
		(attr smd)
		(fp_poly
			(pts
				(xy -0.925 0.47) (xy 0.925 0.47) (xy 0.925 -0.47) (xy -0.925 -0.47)
			)
			(stroke
				(width 0.05)
				(type default)
			)
			(fill no)
			(layer "B.CrtYd")
		)
		(fp_line
			(start 0.504 -0.248)
			(end 0.504 0.25)
			(stroke
				(width 0.15)
				(type solid)
			)
			(layer "B.Fab")
		)
		(fp_line
			(start 0.504 0.25)
			(end -0.494 0.25)
			(stroke
				(width 0.15)
				(type solid)
			)
			(layer "B.Fab")
		)
		(fp_line
			(start -0.494 -0.248)
			(end 0.504 -0.248)
			(stroke
				(width 0.15)
				(type solid)
			)
			(layer "B.Fab")
		)
		(fp_line
			(start -0.494 0.25)
			(end -0.494 -0.248)
			(stroke
				(width 0.15)
				(type solid)
			)
			(layer "B.Fab")
		)
		(pad "1" smd roundrect
			(at -0.48 0 135)
			(size 0.59 0.64)
			(layers "B.Cu" "B.Mask" "B.Paste")
			(roundrect_rratio 0.25)
			(net 1 "GND")
			(pintype "passive")
		)
		(pad "2" smd roundrect
			(at 0.48 0 135)
			(size 0.59 0.64)
			(layers "B.Cu" "B.Mask" "B.Paste")
			(roundrect_rratio 0.25)
			(net 27 "/Deserializer/VDD")
			(pintype "passive")
		)
	)
	(footprint "antmicro-footprints:C_0402_1005Metric"
		(layer "B.Cu")
		(at 144.272 75.692 -45)
		(descr "Capacitor SMD 0402")
		(tags "capacitor SMD 0402")
		(property "Reference" "C38"
			(at -1.51371 0.22729 315)
			(unlocked yes)
			(layer "B.SilkS")
			(effects
				(font
					(size 0.7 0.7)
					(thickness 0.15)
				)
				(justify left bottom mirror)
			)
		)
		(property "Value" "C_10u_0402"
			(at -1.022927 -2.155213 135)
			(layer "B.Fab")
			(effects
				(font
					(size 0.7 0.7)
					(thickness 0.15)
				)
				(justify left bottom mirror)
			)
		)
		(property "Datasheet" "https://www.yageo.com/en/Chart/Download/pdf/CC0402MRX5R5BB106"
			(at 0 0 315)
			(layer "F.Fab")
			(hide yes)
			(effects
				(font
					(size 1.27 1.27)
					(thickness 0.15)
				)
			)
		)
		(property "Description" "SMD Multilayer Ceramic Capacitor, 10 µF, 6.3 V, 0402 [1005 Metric], ± 20%, X5R, CC Series"
			(at 0 0 315)
			(layer "F.Fab")
			(hide yes)
			(effects
				(font
					(size 1.27 1.27)
					(thickness 0.15)
				)
			)
		)
		(property "Author" "Antmicro"
			(at -11.266036 124.185383 0)
			(layer "B.Fab")
			(hide yes)
			(effects
				(font
					(size 1 1)
					(thickness 0.15)
				)
				(justify mirror)
			)
		)
		(property "Dielectric" ""
			(at -11.266036 124.185383 0)
			(layer "B.Fab")
			(hide yes)
			(effects
				(font
					(size 1 1)
					(thickness 0.15)
				)
				(justify mirror)
			)
		)
		(property "License" "Apache-2.0"
			(at -11.266036 124.185383 0)
			(layer "B.Fab")
			(hide yes)
			(effects
				(font
					(size 1 1)
					(thickness 0.15)
				)
				(justify mirror)
			)
		)
		(property "MPN" "CC0402MRX5R5BB106"
			(at -11.266036 124.185383 0)
			(layer "B.Fab")
			(hide yes)
			(effects
				(font
					(size 1 1)
					(thickness 0.15)
				)
				(justify mirror)
			)
		)
		(property "Manufacturer" "YAGEO"
			(at -11.266036 124.185383 0)
			(layer "B.Fab")
			(hide yes)
			(effects
				(font
					(size 1 1)
					(thickness 0.15)
				)
				(justify mirror)
			)
		)
		(property "Val" "10u"
			(at -11.266036 124.185383 0)
			(layer "B.Fab")
			(hide yes)
			(effects
				(font
					(size 1 1)
					(thickness 0.15)
				)
				(justify mirror)
			)
		)
		(property "Voltage" ""
			(at -11.266036 124.185383 0)
			(layer "B.Fab")
			(hide yes)
			(effects
				(font
					(size 1 1)
					(thickness 0.15)
				)
				(justify mirror)
			)
		)
		(sheetname "/Deserializer/")
		(sheetfile "deserializer.kicad_sch")
		(attr smd)
		(fp_poly
			(pts
				(xy -0.925 0.47) (xy 0.925 0.47) (xy 0.925 -0.47) (xy -0.925 -0.47)
			)
			(stroke
				(width 0.05)
				(type default)
			)
			(fill no)
			(layer "B.CrtYd")
		)
		(fp_line
			(start -0.494 0.25)
			(end -0.494 -0.248)
			(stroke
				(width 0.15)
				(type solid)
			)
			(layer "B.Fab")
		)
		(fp_line
			(start -0.494 -0.248)
			(end 0.504 -0.248)
			(stroke
				(width 0.15)
				(type solid)
			)
			(layer "B.Fab")
		)
		(fp_line
			(start 0.504 0.25)
			(end -0.494 0.25)
			(stroke
				(width 0.15)
				(type solid)
			)
			(layer "B.Fab")
		)
		(fp_line
			(start 0.504 -0.248)
			(end 0.504 0.25)
			(stroke
				(width 0.15)
				(type solid)
			)
			(layer "B.Fab")
		)
		(pad "1" smd roundrect
			(at -0.48 0 315)
			(size 0.59 0.64)
			(layers "B.Cu" "B.Mask" "B.Paste")
			(roundrect_rratio 0.25)
			(net 1 "GND")
			(pintype "passive")
		)
		(pad "2" smd roundrect
			(at 0.48 0 315)
			(size 0.59 0.64)
			(layers "B.Cu" "B.Mask" "B.Paste")
			(roundrect_rratio 0.25)
			(net 28 "/Deserializer/CAP_VDD")
			(pintype "passive")
		)
	)
	(footprint "antmicro-footprints:C_0402_1005Metric"
		(layer "B.Cu")
		(at 152.908 83.312 135)
		(descr "Capacitor SMD 0402")
		(tags "capacitor SMD 0402")
		(property "Reference" "C43"
			(at -0.97797 -1.314712 315)
			(unlocked yes)
			(layer "B.SilkS")
			(effects
				(font
					(size 0.7 0.7)
					(thickness 0.15)
				)
				(justify right bottom mirror)
			)
		)
		(property "Value" "C_10n_0402"
			(at -1.022927 -2.155213 135)
			(layer "B.Fab")
			(effects
				(font
					(size 0.7 0.7)
					(thickness 0.15)
				)
				(justify right bottom mirror)
			)
		)
		(property "Datasheet" "https://www.murata.com/products/productdetail?partno=GRM155R71H103KA88%23"
			(at 0 0 135)
			(layer "F.Fab")
			(hide yes)
			(effects
				(font
					(size 1.27 1.27)
					(thickness 0.15)
				)
			)
		)
		(property "Description" "SMD Multilayer Ceramic Capacitor, 10000 pF, 50 V, 0402 [1005 Metric], ± 10%, X7R, GRM Series"
			(at 0 0 135)
			(layer "F.Fab")
			(hide yes)
			(effects
				(font
					(size 1.27 1.27)
					(thickness 0.15)
				)
			)
		)
		(property "Author" "Antmicro"
			(at 319.940764 34.100196 0)
			(layer "B.Fab")
			(hide yes)
			(effects
				(font
					(size 1 1)
					(thickness 0.15)
				)
				(justify mirror)
			)
		)
		(property "Dielectric" "X7R"
			(at 319.940764 34.100196 0)
			(layer "B.Fab")
			(hide yes)
			(effects
				(font
					(size 1 1)
					(thickness 0.15)
				)
				(justify mirror)
			)
		)
		(property "License" "Apache-2.0"
			(at 319.940764 34.100196 0)
			(layer "B.Fab")
			(hide yes)
			(effects
				(font
					(size 1 1)
					(thickness 0.15)
				)
				(justify mirror)
			)
		)
		(property "MPN" "GRM155R71H103KA88D"
			(at 319.940764 34.100196 0)
			(layer "B.Fab")
			(hide yes)
			(effects
				(font
					(size 1 1)
					(thickness 0.15)
				)
				(justify mirror)
			)
		)
		(property "Manufacturer" "Murata"
			(at 319.940764 34.100196 0)
			(layer "B.Fab")
			(hide yes)
			(effects
				(font
					(size 1 1)
					(thickness 0.15)
				)
				(justify mirror)
			)
		)
		(property "Val" "10n"
			(at 319.940764 34.100196 0)
			(layer "B.Fab")
			(hide yes)
			(effects
				(font
					(size 1 1)
					(thickness 0.15)
				)
				(justify mirror)
			)
		)
		(property "Voltage" "50V"
			(at 319.940764 34.100196 0)
			(layer "B.Fab")
			(hide yes)
			(effects
				(font
					(size 1 1)
					(thickness 0.15)
				)
				(justify mirror)
			)
		)
		(sheetname "/Deserializer/")
		(sheetfile "deserializer.kicad_sch")
		(attr smd)
		(fp_poly
			(pts
				(xy -0.925 0.47) (xy 0.925 0.47) (xy 0.925 -0.47) (xy -0.925 -0.47)
			)
			(stroke
				(width 0.05)
				(type default)
			)
			(fill no)
			(layer "B.CrtYd")
		)
		(fp_line
			(start 0.504 -0.248)
			(end 0.504 0.25)
			(stroke
				(width 0.15)
				(type solid)
			)
			(layer "B.Fab")
		)
		(fp_line
			(start 0.504 0.25)
			(end -0.494 0.25)
			(stroke
				(width 0.15)
				(type solid)
			)
			(layer "B.Fab")
		)
		(fp_line
			(start -0.494 -0.248)
			(end 0.504 -0.248)
			(stroke
				(width 0.15)
				(type solid)
			)
			(layer "B.Fab")
		)
		(fp_line
			(start -0.494 0.25)
			(end -0.494 -0.248)
			(stroke
				(width 0.15)
				(type solid)
			)
			(layer "B.Fab")
		)
		(pad "1" smd roundrect
			(at -0.48 0 135)
			(size 0.59 0.64)
			(layers "B.Cu" "B.Mask" "B.Paste")
			(roundrect_rratio 0.25)
			(net 1 "GND")
			(pintype "passive")
		)
		(pad "2" smd roundrect
			(at 0.48 0 135)
			(size 0.59 0.64)
			(layers "B.Cu" "B.Mask" "B.Paste")
			(roundrect_rratio 0.25)
			(net 27 "/Deserializer/VDD")
			(pintype "passive")
		)
	)
	(footprint "antmicro-footprints:C_0402_1005Metric"
		(layer "B.Cu")
		(at 139.192 80.772 -45)
		(descr "Capacitor SMD 0402")
		(tags "capacitor SMD 0402")
		(property "Reference" "C50"
			(at -1.660511 0.317093 315)
			(unlocked yes)
			(layer "B.SilkS")
			(effects
				(font
					(size 0.7 0.7)
					(thickness 0.15)
				)
				(justify left bottom mirror)
			)
		)
		(property "Value" "C_10n_0402"
			(at -1.022927 -2.155213 135)
			(layer "B.Fab")
			(effects
				(font
					(size 0.7 0.7)
					(thickness 0.15)
				)
				(justify left bottom mirror)
			)
		)
		(property "Datasheet" "https://www.murata.com/products/productdetail?partno=GRM155R71H103KA88%23"
			(at 0 0 315)
			(layer "F.Fab")
			(hide yes)
			(effects
				(font
					(size 1.27 1.27)
					(thickness 0.15)
				)
			)
		)
		(property "Description" "SMD Multilayer Ceramic Capacitor, 10000 pF, 50 V, 0402 [1005 Metric], ± 10%, X7R, GRM Series"
			(at 0 0 315)
			(layer "F.Fab")
			(hide yes)
			(effects
				(font
					(size 1.27 1.27)
					(thickness 0.15)
				)
			)
		)
		(property "Author" "Antmicro"
			(at -16.346036 122.081178 0)
			(layer "B.Fab")
			(hide yes)
			(effects
				(font
					(size 1 1)
					(thickness 0.15)
				)
				(justify mirror)
			)
		)
		(property "Dielectric" "X7R"
			(at -16.346036 122.081178 0)
			(layer "B.Fab")
			(hide yes)
			(effects
				(font
					(size 1 1)
					(thickness 0.15)
				)
				(justify mirror)
			)
		)
		(property "License" "Apache-2.0"
			(at -16.346036 122.081178 0)
			(layer "B.Fab")
			(hide yes)
			(effects
				(font
					(size 1 1)
					(thickness 0.15)
				)
				(justify mirror)
			)
		)
		(property "MPN" "GRM155R71H103KA88D"
			(at -16.346036 122.081178 0)
			(layer "B.Fab")
			(hide yes)
			(effects
				(font
					(size 1 1)
					(thickness 0.15)
				)
				(justify mirror)
			)
		)
		(property "Manufacturer" "Murata"
			(at -16.346036 122.081178 0)
			(layer "B.Fab")
			(hide yes)
			(effects
				(font
					(size 1 1)
					(thickness 0.15)
				)
				(justify mirror)
			)
		)
		(property "Val" "10n"
			(at -16.346036 122.081178 0)
			(layer "B.Fab")
			(hide yes)
			(effects
				(font
					(size 1 1)
					(thickness 0.15)
				)
				(justify mirror)
			)
		)
		(property "Voltage" "50V"
			(at -16.346036 122.081178 0)
			(layer "B.Fab")
			(hide yes)
			(effects
				(font
					(size 1 1)
					(thickness 0.15)
				)
				(justify mirror)
			)
		)
		(sheetname "/Deserializer/")
		(sheetfile "deserializer.kicad_sch")
		(attr smd)
		(fp_poly
			(pts
				(xy -0.925 0.47) (xy 0.925 0.47) (xy 0.925 -0.47) (xy -0.925 -0.47)
			)
			(stroke
				(width 0.05)
				(type default)
			)
			(fill no)
			(layer "B.CrtYd")
		)
		(fp_line
			(start -0.494 0.25)
			(end -0.494 -0.248)
			(stroke
				(width 0.15)
				(type solid)
			)
			(layer "B.Fab")
		)
		(fp_line
			(start -0.494 -0.248)
			(end 0.504 -0.248)
			(stroke
				(width 0.15)
				(type solid)
			)
			(layer "B.Fab")
		)
		(fp_line
			(start 0.504 0.25)
			(end -0.494 0.25)
			(stroke
				(width 0.15)
				(type solid)
			)
			(layer "B.Fab")
		)
		(fp_line
			(start 0.504 -0.248)
			(end 0.504 0.25)
			(stroke
				(width 0.15)
				(type solid)
			)
			(layer "B.Fab")
		)
		(pad "1" smd roundrect
			(at -0.48 0 315)
			(size 0.59 0.64)
			(layers "B.Cu" "B.Mask" "B.Paste")
			(roundrect_rratio 0.25)
			(net 1 "GND")
			(pintype "passive")
		)
		(pad "2" smd roundrect
			(at 0.48 0 315)
			(size 0.59 0.64)
			(layers "B.Cu" "B.Mask" "B.Paste")
			(roundrect_rratio 0.25)
			(net 146 "VDDIO")
			(pintype "passive")
		)
	)
	(footprint "antmicro-footprints:C_0402_1005Metric"
		(layer "B.Cu")
		(at 151.384 78.47374 -135)
		(descr "Capacitor SMD 0402")
		(tags "capacitor SMD 0402")
		(property "Reference" "C48"
			(at -3.690905 -0.449013 45)
			(layer "B.SilkS")
			(effects
				(font
					(size 0.7 0.7)
					(thickness 0.15)
				)
				(justify left bottom mirror)
			)
		)
		(property "Value" "C_10n_0402"
			(at -1.022927 -2.155213 45)
			(layer "B.Fab")
			(effects
				(font
					(size 0.7 0.7)
					(thickness 0.15)
				)
				(justify left bottom mirror)
			)
		)
		(property "Datasheet" "https://www.murata.com/products/productdetail?partno=GRM155R71H103KA88%23"
			(at 0 0 225)
			(layer "F.Fab")
			(hide yes)
			(effects
				(font
					(size 1.27 1.27)
					(thickness 0.15)
				)
			)
		)
		(property "Description" "SMD Multilayer Ceramic Capacitor, 10000 pF, 50 V, 0402 [1005 Metric], ± 10%, X7R, GRM Series"
			(at 0 0 225)
			(layer "F.Fab")
			(hide yes)
			(effects
				(font
					(size 1.27 1.27)
					(thickness 0.15)
				)
			)
		)
		(property "Author" "Antmicro"
			(at 202.939339 241.007707 0)
			(layer "B.Fab")
			(hide yes)
			(effects
				(font
					(size 1 1)
					(thickness 0.15)
				)
				(justify mirror)
			)
		)
		(property "Dielectric" "X7R"
			(at 202.939339 241.007707 0)
			(layer "B.Fab")
			(hide yes)
			(effects
				(font
					(size 1 1)
					(thickness 0.15)
				)
				(justify mirror)
			)
		)
		(property "License" "Apache-2.0"
			(at 202.939339 241.007707 0)
			(layer "B.Fab")
			(hide yes)
			(effects
				(font
					(size 1 1)
					(thickness 0.15)
				)
				(justify mirror)
			)
		)
		(property "MPN" "GRM155R71H103KA88D"
			(at 202.939339 241.007707 0)
			(layer "B.Fab")
			(hide yes)
			(effects
				(font
					(size 1 1)
					(thickness 0.15)
				)
				(justify mirror)
			)
		)
		(property "Manufacturer" "Murata"
			(at 202.939339 241.007707 0)
			(layer "B.Fab")
			(hide yes)
			(effects
				(font
					(size 1 1)
					(thickness 0.15)
				)
				(justify mirror)
			)
		)
		(property "Val" "10n"
			(at 202.939339 241.007707 0)
			(layer "B.Fab")
			(hide yes)
			(effects
				(font
					(size 1 1)
					(thickness 0.15)
				)
				(justify mirror)
			)
		)
		(property "Voltage" "50V"
			(at 202.939339 241.007707 0)
			(layer "B.Fab")
			(hide yes)
			(effects
				(font
					(size 1 1)
					(thickness 0.15)
				)
				(justify mirror)
			)
		)
		(sheetname "/Deserializer/")
		(sheetfile "deserializer.kicad_sch")
		(attr smd)
		(fp_poly
			(pts
				(xy -0.925 0.47) (xy 0.925 0.47) (xy 0.925 -0.47) (xy -0.925 -0.47)
			)
			(stroke
				(width 0.05)
				(type default)
			)
			(fill no)
			(layer "B.CrtYd")
		)
		(fp_line
			(start 0.504 0.25)
			(end -0.494 0.25)
			(stroke
				(width 0.15)
				(type solid)
			)
			(layer "B.Fab")
		)
		(fp_line
			(start 0.504 -0.248)
			(end 0.504 0.25)
			(stroke
				(width 0.15)
				(type solid)
			)
			(layer "B.Fab")
		)
		(fp_line
			(start -0.494 0.25)
			(end -0.494 -0.248)
			(stroke
				(width 0.15)
				(type solid)
			)
			(layer "B.Fab")
		)
		(fp_line
			(start -0.494 -0.248)
			(end 0.504 -0.248)
			(stroke
				(width 0.15)
				(type solid)
			)
			(layer "B.Fab")
		)
		(pad "1" smd roundrect
			(at -0.48 0 225)
			(size 0.59 0.64)
			(layers "B.Cu" "B.Mask" "B.Paste")
			(roundrect_rratio 0.25)
			(net 1 "GND")
			(pintype "passive")
		)
		(pad "2" smd roundrect
			(at 0.48 0 225)
			(size 0.59 0.64)
			(layers "B.Cu" "B.Mask" "B.Paste")
			(roundrect_rratio 0.25)
			(net 26 "/Deserializer/VDD_1.8V")
			(pintype "passive")
		)
	)
	(footprint "antmicro-footprints:R_0402_1005Metric"
		(layer "B.Cu")
		(at 133.858 82.702 180)
		(descr "Resistor SMD 0402")
		(tags "resistor SMD 0402")
		(property "Reference" "R52"
			(at 1.143 0.406 0)
			(layer "B.SilkS")
			(effects
				(font
					(size 0.7 0.7)
					(thickness 0.15)
				)
				(justify right bottom mirror)
			)
		)
		(property "Value" "R_0R_0402"
			(at -1.011843 -1.772047 0)
			(layer "B.Fab")
			(effects
				(font
					(size 0.7 0.7)
					(thickness 0.15)
				)
				(justify left bottom mirror)
			)
		)
		(property "Datasheet" "https://industrial.panasonic.com/cdbs/www-data/pdf/RDA0000/AOA0000C301.pdf"
			(at 0 0 180)
			(layer "F.Fab")
			(hide yes)
			(effects
				(font
					(size 1.27 1.27)
					(thickness 0.15)
				)
			)
		)
		(property "Description" "SMD Chip Resistor, Jumper, 0 ohm, 100 mW, 0402 [1005 Metric], Thick Film, General Purpose"
			(at 0 0 180)
			(layer "F.Fab")
			(hide yes)
			(effects
				(font
					(size 1.27 1.27)
					(thickness 0.15)
				)
			)
		)
		(property "Author" "Antmicro"
			(at 267.716 165.404 0)
			(layer "B.Fab")
			(hide yes)
			(effects
				(font
					(size 1 1)
					(thickness 0.15)
				)
				(justify mirror)
			)
		)
		(property "Current" "1A"
			(at 267.716 165.404 0)
			(layer "B.Fab")
			(hide yes)
			(effects
				(font
					(size 1 1)
					(thickness 0.15)
				)
				(justify mirror)
			)
		)
		(property "License" "Apache-2.0"
			(at 267.716 165.404 0)
			(layer "B.Fab")
			(hide yes)
			(effects
				(font
					(size 1 1)
					(thickness 0.15)
				)
				(justify mirror)
			)
		)
		(property "MPN" "ERJ2GE0R00X"
			(at 267.716 165.404 0)
			(layer "B.Fab")
			(hide yes)
			(effects
				(font
					(size 1 1)
					(thickness 0.15)
				)
				(justify mirror)
			)
		)
		(property "Manufacturer" "Panasonic"
			(at 267.716 165.404 0)
			(layer "B.Fab")
			(hide yes)
			(effects
				(font
					(size 1 1)
					(thickness 0.15)
				)
				(justify mirror)
			)
		)
		(property "Tolerance" ""
			(at 267.716 165.404 0)
			(layer "B.Fab")
			(hide yes)
			(effects
				(font
					(size 1 1)
					(thickness 0.15)
				)
				(justify mirror)
			)
		)
		(property "Val" "0R"
			(at 267.716 165.404 0)
			(layer "B.Fab")
			(hide yes)
			(effects
				(font
					(size 1 1)
					(thickness 0.15)
				)
				(justify mirror)
			)
		)
		(sheetname "/Deserializer/")
		(sheetfile "deserializer.kicad_sch")
		(attr smd)
		(fp_rect
			(start -0.925 0.47)
			(end 0.925 -0.47)
			(stroke
				(width 0.05)
				(type default)
			)
			(fill no)
			(layer "B.CrtYd")
		)
		(fp_rect
			(start -0.5 0.25)
			(end 0.5 -0.25)
			(stroke
				(width 0.15)
				(type solid)
			)
			(fill no)
			(layer "B.Fab")
		)
		(pad "1" smd roundrect
			(at -0.48 0 180)
			(size 0.59 0.64)
			(layers "B.Cu" "B.Mask" "B.Paste")
			(roundrect_rratio 0.25)
			(net 26 "/Deserializer/VDD_1.8V")
			(pintype "passive")
		)
		(pad "2" smd roundrect
			(at 0.48 0 180)
			(size 0.59 0.64)
			(layers "B.Cu" "B.Mask" "B.Paste")
			(roundrect_rratio 0.25)
			(net 3 "+1V8")
			(pintype "passive")
		)
	)
	(footprint "antmicro-footprints:TP_SMD_0.75mm"
		(layer "B.Cu")
		(at 144.78 97.89 180)
		(property "Reference" "TP17"
			(at 0 0.6 0)
			(layer "B.SilkS")
			(hide yes)
			(effects
				(font
					(size 0.7 0.7)
					(thickness 0.15)
				)
				(justify left bottom mirror)
			)
		)
		(property "Value" "TP_0.75mm_SMD"
			(at 0 -1.2 0)
			(layer "B.Fab")
			(effects
				(font
					(size 0.7 0.7)
					(thickness 0.15)
				)
				(justify left bottom mirror)
			)
		)
		(property "Description" "SMT test point"
			(at 0 0 0)
			(layer "B.Fab")
			(hide yes)
			(effects
				(font
					(size 1.27 1.27)
					(thickness 0.15)
				)
				(justify mirror)
			)
		)
		(property "MPN" ""
			(at 0 0 0)
			(unlocked yes)
			(layer "B.Fab")
			(hide yes)
			(effects
				(font
					(size 1 1)
					(thickness 0.15)
				)
				(justify mirror)
			)
		)
		(property "Manufacturer" ""
			(at 0 0 0)
			(unlocked yes)
			(layer "B.Fab")
			(hide yes)
			(effects
				(font
					(size 1 1)
					(thickness 0.15)
				)
				(justify mirror)
			)
		)
		(property "Author" "Antmicro"
			(at 0 0 0)
			(unlocked yes)
			(layer "B.Fab")
			(hide yes)
			(effects
				(font
					(size 1 1)
					(thickness 0.15)
				)
				(justify mirror)
			)
		)
		(property "License" "Apache-2.0"
			(at 0 0 0)
			(unlocked yes)
			(layer "B.Fab")
			(hide yes)
			(effects
				(font
					(size 1 1)
					(thickness 0.15)
				)
				(justify mirror)
			)
		)
		(sheetname "/Power/")
		(sheetfile "power.kicad_sch")
		(attr exclude_from_pos_files)
		(fp_circle
			(center 0 0)
			(end 0.475 0)
			(stroke
				(width 0.05)
				(type default)
			)
			(fill no)
			(layer "B.CrtYd")
		)
		(fp_text user "${REFERENCE}"
			(at -0.4 -2.7 0)
			(layer "B.Fab")
			(effects
				(font
					(size 0.7 0.7)
					(thickness 0.15)
				)
				(justify left bottom mirror)
			)
		)
		(fp_text user "Author: Antmicro"
			(at -0.4 -3.901 0)
			(layer "B.Fab")
			(effects
				(font
					(size 0.7 0.7)
					(thickness 0.15)
				)
				(justify left bottom mirror)
			)
		)
		(fp_text user "License: Apache-2.0"
			(at -0.4 -5.101 0)
			(layer "B.Fab")
			(effects
				(font
					(size 0.7 0.7)
					(thickness 0.15)
				)
				(justify left bottom mirror)
			)
		)
		(pad "1" smd circle
			(at 0 0 180)
			(size 0.75 0.75)
			(layers "B.Cu" "B.Mask")
			(net 10 "/Power/OUT_1V8")
			(pinfunction "1")
			(pintype "passive")
		)
	)
	(footprint "antmicro-footprints:Spacer_Drill3.7mm_H6mm_9774060151R"
		(layer "B.Cu")
		(at 184.372 93.068 180)
		(descr "Spacer M=3 h=36mm fi=5.1mm")
		(property "Reference" "H1"
			(at 0 3.2 0)
			(layer "B.SilkS")
			(effects
				(font
					(size 0.7 0.7)
					(thickness 0.15)
				)
				(justify left bottom mirror)
			)
		)
		(property "Value" "Spacer_Drill3.7mm_H6mm_9774060151R"
			(at 0 -4 0)
			(layer "B.Fab")
			(effects
				(font
					(size 0.7 0.7)
					(thickness 0.15)
				)
				(justify left bottom mirror)
			)
		)
		(property "Datasheet" "https://www.we-online.com/components/products/datasheet/9774060151R.pdf"
			(at 0 0 180)
			(layer "F.Fab")
			(hide yes)
			(effects
				(font
					(size 1.27 1.27)
					(thickness 0.15)
				)
			)
		)
		(property "Description" "Spacer, SMT, Non Stop, Steel, Swage Round, 5.1 mm x 6 mm, M2.5 Thread, WA-SMSI Series"
			(at 0 0 180)
			(layer "F.Fab")
			(hide yes)
			(effects
				(font
					(size 1.27 1.27)
					(thickness 0.15)
				)
			)
		)
		(property "Author" "Antmicro"
			(at 368.744 186.136 0)
			(layer "B.Fab")
			(hide yes)
			(effects
				(font
					(size 1 1)
					(thickness 0.15)
				)
				(justify mirror)
			)
		)
		(property "License" "Apache-2.0"
			(at 368.744 186.136 0)
			(layer "B.Fab")
			(hide yes)
			(effects
				(font
					(size 1 1)
					(thickness 0.15)
				)
				(justify mirror)
			)
		)
		(property "MPN" "9774060151R"
			(at 368.744 186.136 0)
			(layer "B.Fab")
			(hide yes)
			(effects
				(font
					(size 1 1)
					(thickness 0.15)
				)
				(justify mirror)
			)
		)
		(property "Manufacturer" "Würth Elektronik"
			(at 368.744 186.136 0)
			(layer "B.Fab")
			(hide yes)
			(effects
				(font
					(size 1 1)
					(thickness 0.15)
				)
				(justify mirror)
			)
		)
		(sheetname "/")
		(sheetfile "gmsl-deserializer.kicad_sch")
		(solder_paste_margin_ratio -1)
		(attr smd)
		(fp_circle
			(center 0 0)
			(end 3.05 0)
			(stroke
				(width 0.05)
				(type solid)
			)
			(fill no)
			(layer "B.CrtYd")
		)
		(fp_circle
			(center 0 0)
			(end 2.6 0)
			(stroke
				(width 0.15)
				(type solid)
			)
			(fill no)
			(layer "B.Fab")
		)
		(pad "" smd custom
			(at -1.7 -1.7 90)
			(size 0.62 0.62)
			(layers "B.Paste")
			(thermal_bridge_angle 90)
			(options
				(clearance outline)
				(anchor circle)
			)
			(primitives
				(gr_arc
					(start 1.266786 0.24747)
					(mid 0.285453 -0.29439)
					(end -0.250195 -1.279127)
					(width 0.2)
				)
				(gr_arc
					(start 1.259603 0.339191)
					(mid 0.218448 -0.232561)
					(end -0.34334 -1.279127)
					(width 0.2)
				)
				(gr_arc
					(start 1.255279 0.431435)
					(mid 0.152481 -0.169693)
					(end -0.436309 -1.279127)
					(width 0.2)
				)
				(gr_arc
					(start 1.253811 0.524161)
					(mid 0.087542 -0.105784)
					(end -0.529126 -1.279127)
					(width 0.2)
				)
				(gr_arc
					(start 1.275473 0.621136)
					(mid 0.0309 -0.033527)
					(end -0.621807 -1.279127)
					(width 0.2)
				)
				(gr_arc
					(start 1.263664 0.711602)
					(mid -0.037759 0.026651)
					(end -0.71437 -1.279127)
					(width 0.2)
				)
				(gr_arc
					(start 1.253435 0.802342)
					(mid -0.105837 0.087395)
					(end -0.806826 -1.279127)
					(width 0.2)
				)
				(gr_arc
					(start 1.267475 0.897258)
					(mid -0.165236 0.156885)
					(end -0.899187 -1.279127)
					(width 0.2)
				)
				(gr_arc
					(start 1.270645 0.990112)
					(mid -0.228522 0.222449)
					(end -0.991463 -1.279127)
					(width 0.2)
				)
				(gr_arc
					(start 1.266278 1.081674)
					(mid -0.294507 0.285313)
					(end -1.083663 -1.279127)
					(width 0.2)
				)
				(gr_line
					(start 1.279127 0.250195)
					(end 1.279127 1.083663)
					(width 0.2)
				)
				(gr_line
					(start -0.250195 -1.279127)
					(end -1.083663 -1.279127)
					(width 0.2)
				)
			)
		)
		(pad "" smd custom
			(at -1.7 1.7 180)
			(size 0.62 0.62)
			(layers "B.Paste")
			(thermal_bridge_angle 90)
			(options
				(clearance outline)
				(anchor circle)
			)
			(primitives
				(gr_arc
					(start 1.266786 0.24747)
					(mid 0.285453 -0.29439)
					(end -0.250195 -1.279127)
					(width 0.2)
				)
				(gr_arc
					(start 1.259603 0.339191)
					(mid 0.218448 -0.232561)
					(end -0.34334 -1.279127)
					(width 0.2)
				)
				(gr_arc
					(start 1.255279 0.431435)
					(mid 0.152481 -0.169693)
					(end -0.436309 -1.279127)
					(width 0.2)
				)
				(gr_arc
					(start 1.253811 0.524161)
					(mid 0.087542 -0.105784)
					(end -0.529126 -1.279127)
					(width 0.2)
				)
				(gr_arc
					(start 1.275473 0.621136)
					(mid 0.0309 -0.033527)
					(end -0.621807 -1.279127)
					(width 0.2)
				)
				(gr_arc
					(start 1.263664 0.711602)
					(mid -0.037759 0.026651)
					(end -0.71437 -1.279127)
					(width 0.2)
				)
				(gr_arc
					(start 1.253435 0.802342)
					(mid -0.105837 0.087395)
					(end -0.806826 -1.279127)
					(width 0.2)
				)
				(gr_arc
					(start 1.267475 0.897258)
					(mid -0.165236 0.156885)
					(end -0.899187 -1.279127)
					(width 0.2)
				)
				(gr_arc
					(start 1.270645 0.990112)
					(mid -0.228522 0.222449)
					(end -0.991463 -1.279127)
					(width 0.2)
				)
				(gr_arc
					(start 1.266278 1.081674)
					(mid -0.294507 0.285313)
					(end -1.083663 -1.279127)
					(width 0.2)
				)
				(gr_line
					(start 1.279127 0.250195)
					(end 1.279127 1.083663)
					(width 0.2)
				)
				(gr_line
					(start -0.250195 -1.279127)
					(end -1.083663 -1.279127)
					(width 0.2)
				)
			)
		)
		(pad "" smd custom
			(at 1.7 -1.7)
			(size 0.62 0.62)
			(layers "B.Paste")
			(thermal_bridge_angle 90)
			(options
				(clearance outline)
				(anchor circle)
			)
			(primitives
				(gr_arc
					(start 1.266786 0.24747)
					(mid 0.285453 -0.29439)
					(end -0.250195 -1.279127)
					(width 0.2)
				)
				(gr_arc
					(start 1.259603 0.339191)
					(mid 0.218448 -0.232561)
					(end -0.34334 -1.279127)
					(width 0.2)
				)
				(gr_arc
					(start 1.255279 0.431435)
					(mid 0.152481 -0.169693)
					(end -0.436309 -1.279127)
					(width 0.2)
				)
				(gr_arc
					(start 1.253811 0.524161)
					(mid 0.087542 -0.105784)
					(end -0.529126 -1.279127)
					(width 0.2)
				)
				(gr_arc
					(start 1.275473 0.621136)
					(mid 0.0309 -0.033527)
					(end -0.621807 -1.279127)
					(width 0.2)
				)
				(gr_arc
					(start 1.263664 0.711602)
					(mid -0.037759 0.026651)
					(end -0.71437 -1.279127)
					(width 0.2)
				)
				(gr_arc
					(start 1.253435 0.802342)
					(mid -0.105837 0.087395)
					(end -0.806826 -1.279127)
					(width 0.2)
				)
				(gr_arc
					(start 1.267475 0.897258)
					(mid -0.165236 0.156885)
					(end -0.899187 -1.279127)
					(width 0.2)
				)
				(gr_arc
					(start 1.270645 0.990112)
					(mid -0.228522 0.222449)
					(end -0.991463 -1.279127)
					(width 0.2)
				)
				(gr_arc
					(start 1.266278 1.081674)
					(mid -0.294507 0.285313)
					(end -1.083663 -1.279127)
					(width 0.2)
				)
				(gr_line
					(start 1.279127 0.250195)
					(end 1.279127 1.083663)
					(width 0.2)
				)
				(gr_line
					(start -0.250195 -1.279127)
					(end -1.083663 -1.279127)
					(width 0.2)
				)
			)
		)
		(pad "" smd custom
			(at 1.7 1.7 270)
			(size 0.62 0.62)
			(layers "B.Paste")
			(thermal_bridge_angle 90)
			(options
				(clearance outline)
				(anchor circle)
			)
			(primitives
				(gr_arc
					(start 1.266786 0.24747)
					(mid 0.285453 -0.29439)
					(end -0.250195 -1.279127)
					(width 0.2)
				)
				(gr_arc
					(start 1.259603 0.339191)
					(mid 0.218448 -0.232561)
					(end -0.34334 -1.279127)
					(width 0.2)
				)
				(gr_arc
					(start 1.255279 0.431435)
					(mid 0.152481 -0.169693)
					(end -0.436309 -1.279127)
					(width 0.2)
				)
				(gr_arc
					(start 1.253811 0.524161)
					(mid 0.087542 -0.105784)
					(end -0.529126 -1.279127)
					(width 0.2)
				)
				(gr_arc
					(start 1.275473 0.621136)
					(mid 0.0309 -0.033527)
					(end -0.621807 -1.279127)
					(width 0.2)
				)
				(gr_arc
					(start 1.263664 0.711602)
					(mid -0.037759 0.026651)
					(end -0.71437 -1.279127)
					(width 0.2)
				)
				(gr_arc
					(start 1.253435 0.802342)
					(mid -0.105837 0.087395)
					(end -0.806826 -1.279127)
					(width 0.2)
				)
				(gr_arc
					(start 1.267475 0.897258)
					(mid -0.165236 0.156885)
					(end -0.899187 -1.279127)
					(width 0.2)
				)
				(gr_arc
					(start 1.270645 0.990112)
					(mid -0.228522 0.222449)
					(end -0.991463 -1.279127)
					(width 0.2)
				)
				(gr_arc
					(start 1.266278 1.081674)
					(mid -0.294507 0.285313)
					(end -1.083663 -1.279127)
					(width 0.2)
				)
				(gr_line
					(start 1.279127 0.250195)
					(end 1.279127 1.083663)
					(width 0.2)
				)
				(gr_line
					(start -0.250195 -1.279127)
					(end -1.083663 -1.279127)
					(width 0.2)
				)
			)
		)
		(pad "1" thru_hole circle
			(at 0 0 180)
			(size 6 6)
			(drill 3.7)
			(layers "*.Cu" "*.Mask")
			(remove_unused_layers no)
			(net 1 "GND")
			(pintype "passive")
		)
	)
	(footprint "antmicro-footprints:C_0402_1005Metric"
		(layer "B.Cu")
		(at 141.224 84.582 45)
		(descr "Capacitor SMD 0402")
		(tags "capacitor SMD 0402")
		(property "Reference" "C55"
			(at -3.792854 -0.017147 45)
			(layer "B.SilkS")
			(effects
				(font
					(size 0.7 0.7)
					(thickness 0.15)
				)
				(justify right bottom mirror)
			)
		)
		(property "Value" "C_10u_0402"
			(at -1.022927 -2.155213 45)
			(layer "B.Fab")
			(effects
				(font
					(size 0.7 0.7)
					(thickness 0.15)
				)
				(justify right bottom mirror)
			)
		)
		(property "Datasheet" "https://www.yageo.com/en/Chart/Download/pdf/CC0402MRX5R5BB106"
			(at 0 0 45)
			(layer "F.Fab")
			(hide yes)
			(effects
				(font
					(size 1.27 1.27)
					(thickness 0.15)
				)
			)
		)
		(property "Description" "SMD Multilayer Ceramic Capacitor, 10 µF, 6.3 V, 0402 [1005 Metric], ± 20%, X5R, CC Series"
			(at 0 0 45)
			(layer "F.Fab")
			(hide yes)
			(effects
				(font
					(size 1.27 1.27)
					(thickness 0.15)
				)
			)
		)
		(property "Author" "Antmicro"
			(at 101.172058 -75.086954 0)
			(layer "B.Fab")
			(hide yes)
			(effects
				(font
					(size 1 1)
					(thickness 0.15)
				)
				(justify mirror)
			)
		)
		(property "Dielectric" ""
			(at 101.172058 -75.086954 0)
			(layer "B.Fab")
			(hide yes)
			(effects
				(font
					(size 1 1)
					(thickness 0.15)
				)
				(justify mirror)
			)
		)
		(property "License" "Apache-2.0"
			(at 101.172058 -75.086954 0)
			(layer "B.Fab")
			(hide yes)
			(effects
				(font
					(size 1 1)
					(thickness 0.15)
				)
				(justify mirror)
			)
		)
		(property "MPN" "CC0402MRX5R5BB106"
			(at 101.172058 -75.086954 0)
			(layer "B.Fab")
			(hide yes)
			(effects
				(font
					(size 1 1)
					(thickness 0.15)
				)
				(justify mirror)
			)
		)
		(property "Manufacturer" "YAGEO"
			(at 101.172058 -75.086954 0)
			(layer "B.Fab")
			(hide yes)
			(effects
				(font
					(size 1 1)
					(thickness 0.15)
				)
				(justify mirror)
			)
		)
		(property "Val" "10u"
			(at 101.172058 -75.086954 0)
			(layer "B.Fab")
			(hide yes)
			(effects
				(font
					(size 1 1)
					(thickness 0.15)
				)
				(justify mirror)
			)
		)
		(property "Voltage" ""
			(at 101.172058 -75.086954 0)
			(layer "B.Fab")
			(hide yes)
			(effects
				(font
					(size 1 1)
					(thickness 0.15)
				)
				(justify mirror)
			)
		)
		(sheetname "/Deserializer/")
		(sheetfile "deserializer.kicad_sch")
		(attr smd)
		(fp_poly
			(pts
				(xy -0.925 0.47) (xy 0.925 0.47) (xy 0.925 -0.47) (xy -0.925 -0.47)
			)
			(stroke
				(width 0.05)
				(type default)
			)
			(fill no)
			(layer "B.CrtYd")
		)
		(fp_line
			(start -0.494 -0.248)
			(end 0.504 -0.248)
			(stroke
				(width 0.15)
				(type solid)
			)
			(layer "B.Fab")
		)
		(fp_line
			(start -0.494 0.25)
			(end -0.494 -0.248)
			(stroke
				(width 0.15)
				(type solid)
			)
			(layer "B.Fab")
		)
		(fp_line
			(start 0.504 -0.248)
			(end 0.504 0.25)
			(stroke
				(width 0.15)
				(type solid)
			)
			(layer "B.Fab")
		)
		(fp_line
			(start 0.504 0.25)
			(end -0.494 0.25)
			(stroke
				(width 0.15)
				(type solid)
			)
			(layer "B.Fab")
		)
		(pad "1" smd roundrect
			(at -0.48 0 45)
			(size 0.59 0.64)
			(layers "B.Cu" "B.Mask" "B.Paste")
			(roundrect_rratio 0.25)
			(net 1 "GND")
			(pintype "passive")
		)
		(pad "2" smd roundrect
			(at 0.48 0 45)
			(size 0.59 0.64)
			(layers "B.Cu" "B.Mask" "B.Paste")
			(roundrect_rratio 0.25)
			(net 29 "/Deserializer/VTERM")
			(pintype "passive")
		)
	)
	(footprint "antmicro-footprints:R_0402_1005Metric"
		(layer "B.Cu")
		(at 144.766904 96.385897 -90)
		(descr "Resistor SMD 0402")
		(tags "resistor SMD 0402")
		(property "Reference" "R81"
			(at -5.750329 -0.414422 90)
			(layer "B.SilkS")
			(effects
				(font
					(size 0.7 0.7)
					(thickness 0.15)
				)
				(justify right bottom mirror)
			)
		)
		(property "Value" "R_470R_0402"
			(at -1.011843 -1.772046 90)
			(layer "B.Fab")
			(effects
				(font
					(size 0.7 0.7)
					(thickness 0.15)
				)
				(justify left bottom mirror)
			)
		)
		(property "Datasheet" "https://www.bourns.com/docs/product-datasheets/cr.pdf"
			(at 0 0 90)
			(layer "F.Fab")
			(hide yes)
			(effects
				(font
					(size 1.27 1.27)
					(thickness 0.15)
				)
			)
		)
		(property "Description" "SMD Chip Resistor, 470 ohm, ± 1%, 62.5 mW, 0402 [1005 Metric], Thick Film, General Purpose"
			(at 0 0 90)
			(layer "F.Fab")
			(hide yes)
			(effects
				(font
					(size 1.27 1.27)
					(thickness 0.15)
				)
			)
		)
		(property "Author" "Antmicro"
			(at -25.166382 130.6418 135)
			(layer "B.Fab")
			(hide yes)
			(effects
				(font
					(size 1 1)
					(thickness 0.15)
				)
				(justify mirror)
			)
		)
		(property "License" "Apache-2.0"
			(at -25.166382 130.6418 135)
			(layer "B.Fab")
			(hide yes)
			(effects
				(font
					(size 1 1)
					(thickness 0.15)
				)
				(justify mirror)
			)
		)
		(property "MPN" "CR0402-FX-4700GLF"
			(at -25.166382 130.6418 135)
			(layer "B.Fab")
			(hide yes)
			(effects
				(font
					(size 1 1)
					(thickness 0.15)
				)
				(justify mirror)
			)
		)
		(property "Manufacturer" "Bourns"
			(at -25.166382 130.6418 135)
			(layer "B.Fab")
			(hide yes)
			(effects
				(font
					(size 1 1)
					(thickness 0.15)
				)
				(justify mirror)
			)
		)
		(property "Tolerance" "1%"
			(at -25.166382 130.6418 135)
			(layer "B.Fab")
			(hide yes)
			(effects
				(font
					(size 1 1)
					(thickness 0.15)
				)
				(justify mirror)
			)
		)
		(property "Val" "470R"
			(at -25.166382 130.6418 135)
			(layer "B.Fab")
			(hide yes)
			(effects
				(font
					(size 1 1)
					(thickness 0.15)
				)
				(justify mirror)
			)
		)
		(sheetname "/Power/")
		(sheetfile "power.kicad_sch")
		(attr smd)
		(fp_poly
			(pts
				(xy -0.925 0.47) (xy 0.925 0.47) (xy 0.925 -0.47) (xy -0.925 -0.47)
			)
			(stroke
				(width 0.05)
				(type default)
			)
			(fill no)
			(layer "B.CrtYd")
		)
		(fp_poly
			(pts
				(xy -0.5 0.25) (xy 0.5 0.25) (xy 0.5 -0.25) (xy -0.5 -0.25)
			)
			(stroke
				(width 0.15)
				(type solid)
			)
			(fill no)
			(layer "B.Fab")
		)
		(pad "1" smd roundrect
			(at -0.48 0 270)
			(size 0.59 0.64)
			(layers "B.Cu" "B.Mask" "B.Paste")
			(roundrect_rratio 0.25)
			(net 147 "Net-(D20-A)")
			(pintype "passive")
		)
		(pad "2" smd roundrect
			(at 0.48 0 270)
			(size 0.59 0.64)
			(layers "B.Cu" "B.Mask" "B.Paste")
			(roundrect_rratio 0.25)
			(net 5 "+5V")
			(pintype "passive")
		)
	)
	(footprint "antmicro-footprints:R_0402_1005Metric"
		(layer "B.Cu")
		(at 153.940161 96.375897 90)
		(descr "Resistor SMD 0402")
		(tags "resistor SMD 0402")
		(property "Reference" "R76"
			(at 5.748915 0.415836 90)
			(layer "B.SilkS")
			(effects
				(font
					(size 0.7 0.7)
					(thickness 0.15)
				)
				(justify right bottom mirror)
			)
		)
		(property "Value" "R_1k65_0402"
			(at -1.011843 -1.772046 90)
			(layer "B.Fab")
			(effects
				(font
					(size 0.7 0.7)
					(thickness 0.15)
				)
				(justify right bottom mirror)
			)
		)
		(property "Datasheet" "https://www.farnell.com/datasheets/3795017.pdf"
			(at 0 0 90)
			(layer "F.Fab")
			(hide yes)
			(effects
				(font
					(size 1.27 1.27)
					(thickness 0.15)
				)
			)
		)
		(property "Description" "SMD Chip Resistor, 1.65 kohm, ± 1%, 63 mW, 0402 [1005 Metric], Thick Film, General Purpose"
			(at 0 0 90)
			(layer "F.Fab")
			(hide yes)
			(effects
				(font
					(size 1.27 1.27)
					(thickness 0.15)
				)
			)
		)
		(property "Author" "Antmicro"
			(at 331.049173 54.373765 135)
			(layer "B.Fab")
			(hide yes)
			(effects
				(font
					(size 1 1)
					(thickness 0.15)
				)
				(justify mirror)
			)
		)
		(property "License" "Apache-2.0"
			(at 331.049173 54.373765 135)
			(layer "B.Fab")
			(hide yes)
			(effects
				(font
					(size 1 1)
					(thickness 0.15)
				)
				(justify mirror)
			)
		)
		(property "MPN" "RC0402FR-071K65L"
			(at 331.049173 54.373765 135)
			(layer "B.Fab")
			(hide yes)
			(effects
				(font
					(size 1 1)
					(thickness 0.15)
				)
				(justify mirror)
			)
		)
		(property "Manufacturer" "YAGEO"
			(at 331.049173 54.373765 135)
			(layer "B.Fab")
			(hide yes)
			(effects
				(font
					(size 1 1)
					(thickness 0.15)
				)
				(justify mirror)
			)
		)
		(property "Public" ""
			(at 331.049173 54.373765 135)
			(layer "B.Fab")
			(hide yes)
			(effects
				(font
					(size 1 1)
					(thickness 0.15)
				)
				(justify mirror)
			)
		)
		(property "Tolerance" "1%"
			(at 331.049173 54.373765 135)
			(layer "B.Fab")
			(hide yes)
			(effects
				(font
					(size 1 1)
					(thickness 0.15)
				)
				(justify mirror)
			)
		)
		(property "Val" "1k65"
			(at 331.049173 54.373765 135)
			(layer "B.Fab")
			(hide yes)
			(effects
				(font
					(size 1 1)
					(thickness 0.15)
				)
				(justify mirror)
			)
		)
		(sheetname "/Power/")
		(sheetfile "power.kicad_sch")
		(attr smd)
		(fp_poly
			(pts
				(xy -0.925 0.47) (xy 0.925 0.47) (xy 0.925 -0.47) (xy -0.925 -0.47)
			)
			(stroke
				(width 0.05)
				(type default)
			)
			(fill no)
			(layer "B.CrtYd")
		)
		(fp_poly
			(pts
				(xy -0.5 0.25) (xy 0.5 0.25) (xy 0.5 -0.25) (xy -0.5 -0.25)
			)
			(stroke
				(width 0.15)
				(type solid)
			)
			(fill no)
			(layer "B.Fab")
		)
		(pad "1" smd roundrect
			(at -0.48 0 90)
			(size 0.59 0.64)
			(layers "B.Cu" "B.Mask" "B.Paste")
			(roundrect_rratio 0.25)
			(net 1 "GND")
			(pintype "passive")
		)
		(pad "2" smd roundrect
			(at 0.48 0 90)
			(size 0.59 0.64)
			(layers "B.Cu" "B.Mask" "B.Paste")
			(roundrect_rratio 0.25)
			(net 112 "Net-(D15-C)")
			(pintype "passive")
		)
	)
	(footprint "antmicro-footprints:R_0402_1005Metric"
		(layer "B.Cu")
		(at 164.1 96.2 90)
		(descr "Resistor SMD 0402")
		(tags "resistor SMD 0402")
		(property "Reference" "R73"
			(at -1.05 1.45 90)
			(layer "B.SilkS")
			(effects
				(font
					(size 0.7 0.7)
					(thickness 0.15)
				)
				(justify right bottom mirror)
			)
		)
		(property "Value" "R_40k2_0402"
			(at -1.011843 -1.772047 90)
			(layer "B.Fab")
			(effects
				(font
					(size 0.7 0.7)
					(thickness 0.15)
				)
				(justify right bottom mirror)
			)
		)
		(property "Datasheet" "https://www.bourns.com/docs/product-datasheets/cr.pdf"
			(at 0 0 90)
			(layer "F.Fab")
			(hide yes)
			(effects
				(font
					(size 1.27 1.27)
					(thickness 0.15)
				)
			)
		)
		(property "Description" "SMD Chip Resistor, 40.2 kohm, ± 1%, 63 mW, 0402 [1005 Metric], Thick Film, General Purpose"
			(at 0 0 90)
			(layer "F.Fab")
			(hide yes)
			(effects
				(font
					(size 1.27 1.27)
					(thickness 0.15)
				)
			)
		)
		(property "Author" "Antmicro"
			(at 260.3 -67.9 0)
			(layer "B.Fab")
			(hide yes)
			(effects
				(font
					(size 1 1)
					(thickness 0.15)
				)
				(justify mirror)
			)
		)
		(property "License" "Apache-2.0"
			(at 260.3 -67.9 0)
			(layer "B.Fab")
			(hide yes)
			(effects
				(font
					(size 1 1)
					(thickness 0.15)
				)
				(justify mirror)
			)
		)
		(property "MPN" "CR0402-FX-4022GLF"
			(at 260.3 -67.9 0)
			(layer "B.Fab")
			(hide yes)
			(effects
				(font
					(size 1 1)
					(thickness 0.15)
				)
				(justify mirror)
			)
		)
		(property "Manufacturer" "Bourns"
			(at 260.3 -67.9 0)
			(layer "B.Fab")
			(hide yes)
			(effects
				(font
					(size 1 1)
					(thickness 0.15)
				)
				(justify mirror)
			)
		)
		(property "Public" ""
			(at 260.3 -67.9 0)
			(layer "B.Fab")
			(hide yes)
			(effects
				(font
					(size 1 1)
					(thickness 0.15)
				)
				(justify mirror)
			)
		)
		(property "Tolerance" "1%"
			(at 260.3 -67.9 0)
			(layer "B.Fab")
			(hide yes)
			(effects
				(font
					(size 1 1)
					(thickness 0.15)
				)
				(justify mirror)
			)
		)
		(property "Val" "40k2"
			(at 260.3 -67.9 0)
			(layer "B.Fab")
			(hide yes)
			(effects
				(font
					(size 1 1)
					(thickness 0.15)
				)
				(justify mirror)
			)
		)
		(sheetname "/Connectors/")
		(sheetfile "connectors.kicad_sch")
		(attr smd)
		(fp_rect
			(start -0.925 0.47)
			(end 0.925 -0.47)
			(stroke
				(width 0.05)
				(type default)
			)
			(fill no)
			(layer "B.CrtYd")
		)
		(fp_rect
			(start -0.5 0.25)
			(end 0.5 -0.25)
			(stroke
				(width 0.15)
				(type solid)
			)
			(fill no)
			(layer "B.Fab")
		)
		(pad "1" smd roundrect
			(at -0.48 0 90)
			(size 0.59 0.64)
			(layers "B.Cu" "B.Mask" "B.Paste")
			(roundrect_rratio 0.25)
			(net 84 "/Connectors/MFP4")
			(pintype "passive")
		)
		(pad "2" smd roundrect
			(at 0.48 0 90)
			(size 0.59 0.64)
			(layers "B.Cu" "B.Mask" "B.Paste")
			(roundrect_rratio 0.25)
			(net 146 "VDDIO")
			(pintype "passive")
		)
	)
	(footprint "antmicro-footprints:C_0402_1005Metric"
		(layer "B.Cu")
		(at 149.86 76.962 -135)
		(descr "Capacitor SMD 0402")
		(tags "capacitor SMD 0402")
		(property "Reference" "C44"
			(at -3.672905 -0.449013 45)
			(layer "B.SilkS")
			(effects
				(font
					(size 0.7 0.7)
					(thickness 0.15)
				)
				(justify left bottom mirror)
			)
		)
		(property "Value" "C_10u_0402"
			(at -1.022927 -2.155213 45)
			(layer "B.Fab")
			(effects
				(font
					(size 0.7 0.7)
					(thickness 0.15)
				)
				(justify left bottom mirror)
			)
		)
		(property "Datasheet" "https://www.yageo.com/en/Chart/Download/pdf/CC0402MRX5R5BB106"
			(at 0 0 225)
			(layer "F.Fab")
			(hide yes)
			(effects
				(font
					(size 1.27 1.27)
					(thickness 0.15)
				)
			)
		)
		(property "Description" "SMD Multilayer Ceramic Capacitor, 10 µF, 6.3 V, 0402 [1005 Metric], ± 20%, X5R, CC Series"
			(at 0 0 225)
			(layer "F.Fab")
			(hide yes)
			(effects
				(font
					(size 1.27 1.27)
					(thickness 0.15)
				)
			)
		)
		(property "Author" "Antmicro"
			(at 201.40667 237.349374 0)
			(layer "B.Fab")
			(hide yes)
			(effects
				(font
					(size 1 1)
					(thickness 0.15)
				)
				(justify mirror)
			)
		)
		(property "Dielectric" ""
			(at 201.40667 237.349374 0)
			(layer "B.Fab")
			(hide yes)
			(effects
				(font
					(size 1 1)
					(thickness 0.15)
				)
				(justify mirror)
			)
		)
		(property "License" "Apache-2.0"
			(at 201.40667 237.349374 0)
			(layer "B.Fab")
			(hide yes)
			(effects
				(font
					(size 1 1)
					(thickness 0.15)
				)
				(justify mirror)
			)
		)
		(property "MPN" "CC0402MRX5R5BB106"
			(at 201.40667 237.349374 0)
			(layer "B.Fab")
			(hide yes)
			(effects
				(font
					(size 1 1)
					(thickness 0.15)
				)
				(justify mirror)
			)
		)
		(property "Manufacturer" "YAGEO"
			(at 201.40667 237.349374 0)
			(layer "B.Fab")
			(hide yes)
			(effects
				(font
					(size 1 1)
					(thickness 0.15)
				)
				(justify mirror)
			)
		)
		(property "Val" "10u"
			(at 201.40667 237.349374 0)
			(layer "B.Fab")
			(hide yes)
			(effects
				(font
					(size 1 1)
					(thickness 0.15)
				)
				(justify mirror)
			)
		)
		(property "Voltage" ""
			(at 201.40667 237.349374 0)
			(layer "B.Fab")
			(hide yes)
			(effects
				(font
					(size 1 1)
					(thickness 0.15)
				)
				(justify mirror)
			)
		)
		(sheetname "/Deserializer/")
		(sheetfile "deserializer.kicad_sch")
		(attr smd)
		(fp_poly
			(pts
				(xy -0.925 0.47) (xy 0.925 0.47) (xy 0.925 -0.47) (xy -0.925 -0.47)
			)
			(stroke
				(width 0.05)
				(type default)
			)
			(fill no)
			(layer "B.CrtYd")
		)
		(fp_line
			(start 0.504 0.25)
			(end -0.494 0.25)
			(stroke
				(width 0.15)
				(type solid)
			)
			(layer "B.Fab")
		)
		(fp_line
			(start 0.504 -0.248)
			(end 0.504 0.25)
			(stroke
				(width 0.15)
				(type solid)
			)
			(layer "B.Fab")
		)
		(fp_line
			(start -0.494 0.25)
			(end -0.494 -0.248)
			(stroke
				(width 0.15)
				(type solid)
			)
			(layer "B.Fab")
		)
		(fp_line
			(start -0.494 -0.248)
			(end 0.504 -0.248)
			(stroke
				(width 0.15)
				(type solid)
			)
			(layer "B.Fab")
		)
		(pad "1" smd roundrect
			(at -0.48 0 225)
			(size 0.59 0.64)
			(layers "B.Cu" "B.Mask" "B.Paste")
			(roundrect_rratio 0.25)
			(net 1 "GND")
			(pintype "passive")
		)
		(pad "2" smd roundrect
			(at 0.48 0 225)
			(size 0.59 0.64)
			(layers "B.Cu" "B.Mask" "B.Paste")
			(roundrect_rratio 0.25)
			(net 28 "/Deserializer/CAP_VDD")
			(pintype "passive")
		)
	)
	(footprint "antmicro-footprints:C_0402_1005Metric"
		(layer "B.Cu")
		(at 145.034 74.93 -45)
		(descr "Capacitor SMD 0402")
		(tags "capacitor SMD 0402")
		(property "Reference" "C41"
			(at -1.51321 0.22729 315)
			(unlocked yes)
			(layer "B.SilkS")
			(effects
				(font
					(size 0.7 0.7)
					(thickness 0.15)
				)
				(justify left bottom mirror)
			)
		)
		(property "Value" "C_100n_0402"
			(at -1.022927 -2.155213 135)
			(layer "B.Fab")
			(effects
				(font
					(size 0.7 0.7)
					(thickness 0.15)
				)
				(justify left bottom mirror)
			)
		)
		(property "Datasheet" "https://www.murata.com/products/productdetail?partno=GRM155R61H104KE14%23"
			(at 0 0 315)
			(layer "F.Fab")
			(hide yes)
			(effects
				(font
					(size 1.27 1.27)
					(thickness 0.15)
				)
			)
		)
		(property "Description" "SMD Multilayer Ceramic Capacitor, 0.1 µF, 50 V, 0402 [1005 Metric], ± 10%, X5R, GRM Series"
			(at 0 0 315)
			(layer "F.Fab")
			(hide yes)
			(effects
				(font
					(size 1.27 1.27)
					(thickness 0.15)
				)
			)
		)
		(property "Author" "Antmicro"
			(at -10.504036 124.501014 0)
			(layer "B.Fab")
			(hide yes)
			(effects
				(font
					(size 1 1)
					(thickness 0.15)
				)
				(justify mirror)
			)
		)
		(property "Dielectric" "X5R"
			(at -10.504036 124.501014 0)
			(layer "B.Fab")
			(hide yes)
			(effects
				(font
					(size 1 1)
					(thickness 0.15)
				)
				(justify mirror)
			)
		)
		(property "License" "Apache-2.0"
			(at -10.504036 124.501014 0)
			(layer "B.Fab")
			(hide yes)
			(effects
				(font
					(size 1 1)
					(thickness 0.15)
				)
				(justify mirror)
			)
		)
		(property "MPN" "GRM155R61H104KE14D"
			(at -10.504036 124.501014 0)
			(layer "B.Fab")
			(hide yes)
			(effects
				(font
					(size 1 1)
					(thickness 0.15)
				)
				(justify mirror)
			)
		)
		(property "Manufacturer" "Murata"
			(at -10.504036 124.501014 0)
			(layer "B.Fab")
			(hide yes)
			(effects
				(font
					(size 1 1)
					(thickness 0.15)
				)
				(justify mirror)
			)
		)
		(property "Val" "100n"
			(at -10.504036 124.501014 0)
			(layer "B.Fab")
			(hide yes)
			(effects
				(font
					(size 1 1)
					(thickness 0.15)
				)
				(justify mirror)
			)
		)
		(property "Voltage" "50V"
			(at -10.504036 124.501014 0)
			(layer "B.Fab")
			(hide yes)
			(effects
				(font
					(size 1 1)
					(thickness 0.15)
				)
				(justify mirror)
			)
		)
		(sheetname "/Deserializer/")
		(sheetfile "deserializer.kicad_sch")
		(attr smd)
		(fp_poly
			(pts
				(xy -0.925 0.47) (xy 0.925 0.47) (xy 0.925 -0.47) (xy -0.925 -0.47)
			)
			(stroke
				(width 0.05)
				(type default)
			)
			(fill no)
			(layer "B.CrtYd")
		)
		(fp_line
			(start -0.494 0.25)
			(end -0.494 -0.248)
			(stroke
				(width 0.15)
				(type solid)
			)
			(layer "B.Fab")
		)
		(fp_line
			(start -0.494 -0.248)
			(end 0.504 -0.248)
			(stroke
				(width 0.15)
				(type solid)
			)
			(layer "B.Fab")
		)
		(fp_line
			(start 0.504 0.25)
			(end -0.494 0.25)
			(stroke
				(width 0.15)
				(type solid)
			)
			(layer "B.Fab")
		)
		(fp_line
			(start 0.504 -0.248)
			(end 0.504 0.25)
			(stroke
				(width 0.15)
				(type solid)
			)
			(layer "B.Fab")
		)
		(pad "1" smd roundrect
			(at -0.48 0 315)
			(size 0.59 0.64)
			(layers "B.Cu" "B.Mask" "B.Paste")
			(roundrect_rratio 0.25)
			(net 1 "GND")
			(pintype "passive")
		)
		(pad "2" smd roundrect
			(at 0.48 0 315)
			(size 0.59 0.64)
			(layers "B.Cu" "B.Mask" "B.Paste")
			(roundrect_rratio 0.25)
			(net 28 "/Deserializer/CAP_VDD")
			(pintype "passive")
		)
	)
	(footprint "antmicro-footprints:R_0402_1005Metric"
		(layer "B.Cu")
		(at 133.25 89.45 -90)
		(descr "Resistor SMD 0402")
		(tags "resistor SMD 0402")
		(property "Reference" "R72"
			(at 0.85 -0.45 90)
			(layer "B.SilkS")
			(effects
				(font
					(size 0.7 0.7)
					(thickness 0.15)
				)
				(justify left bottom mirror)
			)
		)
		(property "Value" "R_100k_0402"
			(at -1.011843 -1.772047 90)
			(layer "B.Fab")
			(effects
				(font
					(size 0.7 0.7)
					(thickness 0.15)
				)
				(justify left bottom mirror)
			)
		)
		(property "Datasheet" "https://www.bourns.com/docs/product-datasheets/cr.pdf"
			(at 0 0 270)
			(layer "F.Fab")
			(hide yes)
			(effects
				(font
					(size 1.27 1.27)
					(thickness 0.15)
				)
			)
		)
		(property "Description" "SMD Chip Resistor, 100 kohm, ± 1%, 62.5 mW, 0402 [1005 Metric], Thick Film, General Purpose"
			(at 0 0 270)
			(layer "F.Fab")
			(hide yes)
			(effects
				(font
					(size 1.27 1.27)
					(thickness 0.15)
				)
			)
		)
		(property "Author" "Antmicro"
			(at 43.8 222.7 0)
			(layer "B.Fab")
			(hide yes)
			(effects
				(font
					(size 1 1)
					(thickness 0.15)
				)
				(justify mirror)
			)
		)
		(property "License" "Apache-2.0"
			(at 43.8 222.7 0)
			(layer "B.Fab")
			(hide yes)
			(effects
				(font
					(size 1 1)
					(thickness 0.15)
				)
				(justify mirror)
			)
		)
		(property "MPN" "CR0402-FX-1003GLF"
			(at 43.8 222.7 0)
			(layer "B.Fab")
			(hide yes)
			(effects
				(font
					(size 1 1)
					(thickness 0.15)
				)
				(justify mirror)
			)
		)
		(property "Manufacturer" "Bourns"
			(at 43.8 222.7 0)
			(layer "B.Fab")
			(hide yes)
			(effects
				(font
					(size 1 1)
					(thickness 0.15)
				)
				(justify mirror)
			)
		)
		(property "Tolerance" "1%"
			(at 43.8 222.7 0)
			(layer "B.Fab")
			(hide yes)
			(effects
				(font
					(size 1 1)
					(thickness 0.15)
				)
				(justify mirror)
			)
		)
		(property "Val" "100k"
			(at 43.8 222.7 0)
			(layer "B.Fab")
			(hide yes)
			(effects
				(font
					(size 1 1)
					(thickness 0.15)
				)
				(justify mirror)
			)
		)
		(sheetname "/Power/")
		(sheetfile "power.kicad_sch")
		(attr smd)
		(fp_rect
			(start -0.925 0.47)
			(end 0.925 -0.47)
			(stroke
				(width 0.05)
				(type default)
			)
			(fill no)
			(layer "B.CrtYd")
		)
		(fp_rect
			(start -0.5 0.25)
			(end 0.5 -0.25)
			(stroke
				(width 0.15)
				(type solid)
			)
			(fill no)
			(layer "B.Fab")
		)
		(pad "1" smd roundrect
			(at -0.48 0 270)
			(size 0.59 0.64)
			(layers "B.Cu" "B.Mask" "B.Paste")
			(roundrect_rratio 0.25)
			(net 1 "GND")
			(pintype "passive")
		)
		(pad "2" smd roundrect
			(at 0.48 0 270)
			(size 0.59 0.64)
			(layers "B.Cu" "B.Mask" "B.Paste")
			(roundrect_rratio 0.25)
			(net 11 "/Power/OUT_1V2")
			(pintype "passive")
		)
	)
	(footprint "antmicro-footprints:C_0402_1005Metric"
		(layer "B.Cu")
		(at 141.986 77.978 -45)
		(descr "Capacitor SMD 0402")
		(tags "capacitor SMD 0402")
		(property "Reference" "C42"
			(at -1.52271 0.22729 315)
			(unlocked yes)
			(layer "B.SilkS")
			(effects
				(font
					(size 0.7 0.7)
					(thickness 0.15)
				)
				(justify left bottom mirror)
			)
		)
		(property "Value" "C_10n_0402"
			(at -1.022927 -2.155213 135)
			(layer "B.Fab")
			(effects
				(font
					(size 0.7 0.7)
					(thickness 0.15)
				)
				(justify left bottom mirror)
			)
		)
		(property "Datasheet" "https://www.murata.com/products/productdetail?partno=GRM155R71H103KA88%23"
			(at 0 0 315)
			(layer "F.Fab")
			(hide yes)
			(effects
				(font
					(size 1.27 1.27)
					(thickness 0.15)
				)
			)
		)
		(property "Description" "SMD Multilayer Ceramic Capacitor, 10000 pF, 50 V, 0402 [1005 Metric], ± 10%, X7R, GRM Series"
			(at 0 0 315)
			(layer "F.Fab")
			(hide yes)
			(effects
				(font
					(size 1.27 1.27)
					(thickness 0.15)
				)
			)
		)
		(property "Author" "Antmicro"
			(at -13.552036 123.238491 0)
			(layer "B.Fab")
			(hide yes)
			(effects
				(font
					(size 1 1)
					(thickness 0.15)
				)
				(justify mirror)
			)
		)
		(property "Dielectric" "X7R"
			(at -13.552036 123.238491 0)
			(layer "B.Fab")
			(hide yes)
			(effects
				(font
					(size 1 1)
					(thickness 0.15)
				)
				(justify mirror)
			)
		)
		(property "License" "Apache-2.0"
			(at -13.552036 123.238491 0)
			(layer "B.Fab")
			(hide yes)
			(effects
				(font
					(size 1 1)
					(thickness 0.15)
				)
				(justify mirror)
			)
		)
		(property "MPN" "GRM155R71H103KA88D"
			(at -13.552036 123.238491 0)
			(layer "B.Fab")
			(hide yes)
			(effects
				(font
					(size 1 1)
					(thickness 0.15)
				)
				(justify mirror)
			)
		)
		(property "Manufacturer" "Murata"
			(at -13.552036 123.238491 0)
			(layer "B.Fab")
			(hide yes)
			(effects
				(font
					(size 1 1)
					(thickness 0.15)
				)
				(justify mirror)
			)
		)
		(property "Val" "10n"
			(at -13.552036 123.238491 0)
			(layer "B.Fab")
			(hide yes)
			(effects
				(font
					(size 1 1)
					(thickness 0.15)
				)
				(justify mirror)
			)
		)
		(property "Voltage" "50V"
			(at -13.552036 123.238491 0)
			(layer "B.Fab")
			(hide yes)
			(effects
				(font
					(size 1 1)
					(thickness 0.15)
				)
				(justify mirror)
			)
		)
		(sheetname "/Deserializer/")
		(sheetfile "deserializer.kicad_sch")
		(attr smd)
		(fp_poly
			(pts
				(xy -0.925 0.47) (xy 0.925 0.47) (xy 0.925 -0.47) (xy -0.925 -0.47)
			)
			(stroke
				(width 0.05)
				(type default)
			)
			(fill no)
			(layer "B.CrtYd")
		)
		(fp_line
			(start -0.494 0.25)
			(end -0.494 -0.248)
			(stroke
				(width 0.15)
				(type solid)
			)
			(layer "B.Fab")
		)
		(fp_line
			(start -0.494 -0.248)
			(end 0.504 -0.248)
			(stroke
				(width 0.15)
				(type solid)
			)
			(layer "B.Fab")
		)
		(fp_line
			(start 0.504 0.25)
			(end -0.494 0.25)
			(stroke
				(width 0.15)
				(type solid)
			)
			(layer "B.Fab")
		)
		(fp_line
			(start 0.504 -0.248)
			(end 0.504 0.25)
			(stroke
				(width 0.15)
				(type solid)
			)
			(layer "B.Fab")
		)
		(pad "1" smd roundrect
			(at -0.48 0 315)
			(size 0.59 0.64)
			(layers "B.Cu" "B.Mask" "B.Paste")
			(roundrect_rratio 0.25)
			(net 1 "GND")
			(pintype "passive")
		)
		(pad "2" smd roundrect
			(at 0.48 0 315)
			(size 0.59 0.64)
			(layers "B.Cu" "B.Mask" "B.Paste")
			(roundrect_rratio 0.25)
			(net 26 "/Deserializer/VDD_1.8V")
			(pintype "passive")
		)
	)
	(footprint "antmicro-footprints:Spacer_Drill3.7mm_H6mm_9774060151R"
		(layer "B.Cu")
		(at 184.372 46.068 180)
		(descr "Spacer M=3 h=36mm fi=5.1mm")
		(property "Reference" "H2"
			(at 0 3.2 0)
			(layer "B.SilkS")
			(effects
				(font
					(size 0.7 0.7)
					(thickness 0.15)
				)
				(justify left bottom mirror)
			)
		)
		(property "Value" "Spacer_Drill3.7mm_H6mm_9774060151R"
			(at 0 -4 0)
			(layer "B.Fab")
			(effects
				(font
					(size 0.7 0.7)
					(thickness 0.15)
				)
				(justify left bottom mirror)
			)
		)
		(property "Datasheet" "https://www.we-online.com/components/products/datasheet/9774060151R.pdf"
			(at 0 0 180)
			(layer "F.Fab")
			(hide yes)
			(effects
				(font
					(size 1.27 1.27)
					(thickness 0.15)
				)
			)
		)
		(property "Description" "Spacer, SMT, Non Stop, Steel, Swage Round, 5.1 mm x 6 mm, M2.5 Thread, WA-SMSI Series"
			(at 0 0 180)
			(layer "F.Fab")
			(hide yes)
			(effects
				(font
					(size 1.27 1.27)
					(thickness 0.15)
				)
			)
		)
		(property "Author" "Antmicro"
			(at 368.744 92.136 0)
			(layer "B.Fab")
			(hide yes)
			(effects
				(font
					(size 1 1)
					(thickness 0.15)
				)
				(justify mirror)
			)
		)
		(property "License" "Apache-2.0"
			(at 368.744 92.136 0)
			(layer "B.Fab")
			(hide yes)
			(effects
				(font
					(size 1 1)
					(thickness 0.15)
				)
				(justify mirror)
			)
		)
		(property "MPN" "9774060151R"
			(at 368.744 92.136 0)
			(layer "B.Fab")
			(hide yes)
			(effects
				(font
					(size 1 1)
					(thickness 0.15)
				)
				(justify mirror)
			)
		)
		(property "Manufacturer" "Würth Elektronik"
			(at 368.744 92.136 0)
			(layer "B.Fab")
			(hide yes)
			(effects
				(font
					(size 1 1)
					(thickness 0.15)
				)
				(justify mirror)
			)
		)
		(sheetname "/")
		(sheetfile "gmsl-deserializer.kicad_sch")
		(solder_paste_margin_ratio -1)
		(attr smd)
		(fp_circle
			(center 0 0)
			(end 3.05 0)
			(stroke
				(width 0.05)
				(type solid)
			)
			(fill no)
			(layer "B.CrtYd")
		)
		(fp_circle
			(center 0 0)
			(end 2.6 0)
			(stroke
				(width 0.15)
				(type solid)
			)
			(fill no)
			(layer "B.Fab")
		)
		(pad "" smd custom
			(at -1.7 -1.7 90)
			(size 0.62 0.62)
			(layers "B.Paste")
			(thermal_bridge_angle 90)
			(options
				(clearance outline)
				(anchor circle)
			)
			(primitives
				(gr_arc
					(start 1.266786 0.24747)
					(mid 0.285453 -0.29439)
					(end -0.250195 -1.279127)
					(width 0.2)
				)
				(gr_arc
					(start 1.259603 0.339191)
					(mid 0.218448 -0.232561)
					(end -0.34334 -1.279127)
					(width 0.2)
				)
				(gr_arc
					(start 1.255279 0.431435)
					(mid 0.152481 -0.169693)
					(end -0.436309 -1.279127)
					(width 0.2)
				)
				(gr_arc
					(start 1.253811 0.524161)
					(mid 0.087542 -0.105784)
					(end -0.529126 -1.279127)
					(width 0.2)
				)
				(gr_arc
					(start 1.275473 0.621136)
					(mid 0.0309 -0.033527)
					(end -0.621807 -1.279127)
					(width 0.2)
				)
				(gr_arc
					(start 1.263664 0.711602)
					(mid -0.037759 0.026651)
					(end -0.71437 -1.279127)
					(width 0.2)
				)
				(gr_arc
					(start 1.253435 0.802342)
					(mid -0.105837 0.087395)
					(end -0.806826 -1.279127)
					(width 0.2)
				)
				(gr_arc
					(start 1.267475 0.897258)
					(mid -0.165236 0.156885)
					(end -0.899187 -1.279127)
					(width 0.2)
				)
				(gr_arc
					(start 1.270645 0.990112)
					(mid -0.228522 0.222449)
					(end -0.991463 -1.279127)
					(width 0.2)
				)
				(gr_arc
					(start 1.266278 1.081674)
					(mid -0.294507 0.285313)
					(end -1.083663 -1.279127)
					(width 0.2)
				)
				(gr_line
					(start 1.279127 0.250195)
					(end 1.279127 1.083663)
					(width 0.2)
				)
				(gr_line
					(start -0.250195 -1.279127)
					(end -1.083663 -1.279127)
					(width 0.2)
				)
			)
		)
		(pad "" smd custom
			(at -1.7 1.7 180)
			(size 0.62 0.62)
			(layers "B.Paste")
			(thermal_bridge_angle 90)
			(options
				(clearance outline)
				(anchor circle)
			)
			(primitives
				(gr_arc
					(start 1.266786 0.24747)
					(mid 0.285453 -0.29439)
					(end -0.250195 -1.279127)
					(width 0.2)
				)
				(gr_arc
					(start 1.259603 0.339191)
					(mid 0.218448 -0.232561)
					(end -0.34334 -1.279127)
					(width 0.2)
				)
				(gr_arc
					(start 1.255279 0.431435)
					(mid 0.152481 -0.169693)
					(end -0.436309 -1.279127)
					(width 0.2)
				)
				(gr_arc
					(start 1.253811 0.524161)
					(mid 0.087542 -0.105784)
					(end -0.529126 -1.279127)
					(width 0.2)
				)
				(gr_arc
					(start 1.275473 0.621136)
					(mid 0.0309 -0.033527)
					(end -0.621807 -1.279127)
					(width 0.2)
				)
				(gr_arc
					(start 1.263664 0.711602)
					(mid -0.037759 0.026651)
					(end -0.71437 -1.279127)
					(width 0.2)
				)
				(gr_arc
					(start 1.253435 0.802342)
					(mid -0.105837 0.087395)
					(end -0.806826 -1.279127)
					(width 0.2)
				)
				(gr_arc
					(start 1.267475 0.897258)
					(mid -0.165236 0.156885)
					(end -0.899187 -1.279127)
					(width 0.2)
				)
				(gr_arc
					(start 1.270645 0.990112)
					(mid -0.228522 0.222449)
					(end -0.991463 -1.279127)
					(width 0.2)
				)
				(gr_arc
					(start 1.266278 1.081674)
					(mid -0.294507 0.285313)
					(end -1.083663 -1.279127)
					(width 0.2)
				)
				(gr_line
					(start 1.279127 0.250195)
					(end 1.279127 1.083663)
					(width 0.2)
				)
				(gr_line
					(start -0.250195 -1.279127)
					(end -1.083663 -1.279127)
					(width 0.2)
				)
			)
		)
		(pad "" smd custom
			(at 1.7 -1.7)
			(size 0.62 0.62)
			(layers "B.Paste")
			(thermal_bridge_angle 90)
			(options
				(clearance outline)
				(anchor circle)
			)
			(primitives
				(gr_arc
					(start 1.266786 0.24747)
					(mid 0.285453 -0.29439)
					(end -0.250195 -1.279127)
					(width 0.2)
				)
				(gr_arc
					(start 1.259603 0.339191)
					(mid 0.218448 -0.232561)
					(end -0.34334 -1.279127)
					(width 0.2)
				)
				(gr_arc
					(start 1.255279 0.431435)
					(mid 0.152481 -0.169693)
					(end -0.436309 -1.279127)
					(width 0.2)
				)
				(gr_arc
					(start 1.253811 0.524161)
					(mid 0.087542 -0.105784)
					(end -0.529126 -1.279127)
					(width 0.2)
				)
				(gr_arc
					(start 1.275473 0.621136)
					(mid 0.0309 -0.033527)
					(end -0.621807 -1.279127)
					(width 0.2)
				)
				(gr_arc
					(start 1.263664 0.711602)
					(mid -0.037759 0.026651)
					(end -0.71437 -1.279127)
					(width 0.2)
				)
				(gr_arc
					(start 1.253435 0.802342)
					(mid -0.105837 0.087395)
					(end -0.806826 -1.279127)
					(width 0.2)
				)
				(gr_arc
					(start 1.267475 0.897258)
					(mid -0.165236 0.156885)
					(end -0.899187 -1.279127)
					(width 0.2)
				)
				(gr_arc
					(start 1.270645 0.990112)
					(mid -0.228522 0.222449)
					(end -0.991463 -1.279127)
					(width 0.2)
				)
				(gr_arc
					(start 1.266278 1.081674)
					(mid -0.294507 0.285313)
					(end -1.083663 -1.279127)
					(width 0.2)
				)
				(gr_line
					(start 1.279127 0.250195)
					(end 1.279127 1.083663)
					(width 0.2)
				)
				(gr_line
					(start -0.250195 -1.279127)
					(end -1.083663 -1.279127)
					(width 0.2)
				)
			)
		)
		(pad "" smd custom
			(at 1.7 1.7 270)
			(size 0.62 0.62)
			(layers "B.Paste")
			(thermal_bridge_angle 90)
			(options
				(clearance outline)
				(anchor circle)
			)
			(primitives
				(gr_arc
					(start 1.266786 0.24747)
					(mid 0.285453 -0.29439)
					(end -0.250195 -1.279127)
					(width 0.2)
				)
				(gr_arc
					(start 1.259603 0.339191)
					(mid 0.218448 -0.232561)
					(end -0.34334 -1.279127)
					(width 0.2)
				)
				(gr_arc
					(start 1.255279 0.431435)
					(mid 0.152481 -0.169693)
					(end -0.436309 -1.279127)
					(width 0.2)
				)
				(gr_arc
					(start 1.253811 0.524161)
					(mid 0.087542 -0.105784)
					(end -0.529126 -1.279127)
					(width 0.2)
				)
				(gr_arc
					(start 1.275473 0.621136)
					(mid 0.0309 -0.033527)
					(end -0.621807 -1.279127)
					(width 0.2)
				)
				(gr_arc
					(start 1.263664 0.711602)
					(mid -0.037759 0.026651)
					(end -0.71437 -1.279127)
					(width 0.2)
				)
				(gr_arc
					(start 1.253435 0.802342)
					(mid -0.105837 0.087395)
					(end -0.806826 -1.279127)
					(width 0.2)
				)
				(gr_arc
					(start 1.267475 0.897258)
					(mid -0.165236 0.156885)
					(end -0.899187 -1.279127)
					(width 0.2)
				)
				(gr_arc
					(start 1.270645 0.990112)
					(mid -0.228522 0.222449)
					(end -0.991463 -1.279127)
					(width 0.2)
				)
				(gr_arc
					(start 1.266278 1.081674)
					(mid -0.294507 0.285313)
					(end -1.083663 -1.279127)
					(width 0.2)
				)
				(gr_line
					(start 1.279127 0.250195)
					(end 1.279127 1.083663)
					(width 0.2)
				)
				(gr_line
					(start -0.250195 -1.279127)
					(end -1.083663 -1.279127)
					(width 0.2)
				)
			)
		)
		(pad "1" thru_hole circle
			(at 0 0 180)
			(size 6 6)
			(drill 3.7)
			(layers "*.Cu" "*.Mask")
			(remove_unused_layers no)
			(net 1 "GND")
			(pintype "passive")
		)
	)
	(footprint "antmicro-footprints:TP_SMD_0.75mm"
		(layer "B.Cu")
		(at 153.924 97.89 180)
		(property "Reference" "TP21"
			(at 0 0.6 0)
			(layer "B.SilkS")
			(hide yes)
			(effects
				(font
					(size 0.7 0.7)
					(thickness 0.15)
				)
				(justify left bottom mirror)
			)
		)
		(property "Value" "TP_0.75mm_SMD"
			(at 0 -1.2 0)
			(layer "B.Fab")
			(effects
				(font
					(size 0.7 0.7)
					(thickness 0.15)
				)
				(justify left bottom mirror)
			)
		)
		(property "Description" "SMT test point"
			(at 0 0 0)
			(layer "B.Fab")
			(hide yes)
			(effects
				(font
					(size 1.27 1.27)
					(thickness 0.15)
				)
				(justify mirror)
			)
		)
		(property "MPN" ""
			(at 0 0 0)
			(unlocked yes)
			(layer "B.Fab")
			(hide yes)
			(effects
				(font
					(size 1 1)
					(thickness 0.15)
				)
				(justify mirror)
			)
		)
		(property "Manufacturer" ""
			(at 0 0 0)
			(unlocked yes)
			(layer "B.Fab")
			(hide yes)
			(effects
				(font
					(size 1 1)
					(thickness 0.15)
				)
				(justify mirror)
			)
		)
		(property "Author" "Antmicro"
			(at 0 0 0)
			(unlocked yes)
			(layer "B.Fab")
			(hide yes)
			(effects
				(font
					(size 1 1)
					(thickness 0.15)
				)
				(justify mirror)
			)
		)
		(property "License" "Apache-2.0"
			(at 0 0 0)
			(unlocked yes)
			(layer "B.Fab")
			(hide yes)
			(effects
				(font
					(size 1 1)
					(thickness 0.15)
				)
				(justify mirror)
			)
		)
		(sheetname "/Power/")
		(sheetfile "power.kicad_sch")
		(attr exclude_from_pos_files)
		(fp_circle
			(center 0 0)
			(end 0.475 0)
			(stroke
				(width 0.05)
				(type default)
			)
			(fill no)
			(layer "B.CrtYd")
		)
		(fp_text user "${REFERENCE}"
			(at -0.4 -2.7 0)
			(layer "B.Fab")
			(effects
				(font
					(size 0.7 0.7)
					(thickness 0.15)
				)
				(justify left bottom mirror)
			)
		)
		(fp_text user "License: Apache-2.0"
			(at -0.4 -5.101 0)
			(layer "B.Fab")
			(effects
				(font
					(size 0.7 0.7)
					(thickness 0.15)
				)
				(justify left bottom mirror)
			)
		)
		(fp_text user "Author: Antmicro"
			(at -0.4 -3.901 0)
			(layer "B.Fab")
			(effects
				(font
					(size 0.7 0.7)
					(thickness 0.15)
				)
				(justify left bottom mirror)
			)
		)
		(pad "1" smd circle
			(at 0 0 180)
			(size 0.75 0.75)
			(layers "B.Cu" "B.Mask")
			(net 118 "/Connectors/DC_IN")
			(pinfunction "1")
			(pintype "passive")
		)
	)
	(footprint "antmicro-footprints:C_0402_1005Metric"
		(layer "B.Cu")
		(at 150.622 77.724 -135)
		(descr "Capacitor SMD 0402")
		(tags "capacitor SMD 0402")
		(property "Reference" "C45"
			(at -3.690905 -0.449013 45)
			(layer "B.SilkS")
			(effects
				(font
					(size 0.7 0.7)
					(thickness 0.15)
				)
				(justify left bottom mirror)
			)
		)
		(property "Value" "C_100n_0402"
			(at -1.022927 -2.155213 45)
			(layer "B.Fab")
			(effects
				(font
					(size 0.7 0.7)
					(thickness 0.15)
				)
				(justify left bottom mirror)
			)
		)
		(property "Datasheet" "https://www.murata.com/products/productdetail?partno=GRM155R61H104KE14%23"
			(at 0 0 225)
			(layer "F.Fab")
			(hide yes)
			(effects
				(font
					(size 1.27 1.27)
					(thickness 0.15)
				)
			)
		)
		(property "Description" "SMD Multilayer Ceramic Capacitor, 0.1 µF, 50 V, 0402 [1005 Metric], ± 10%, X5R, GRM Series"
			(at 0 0 225)
			(layer "F.Fab")
			(hide yes)
			(effects
				(font
					(size 1.27 1.27)
					(thickness 0.15)
				)
			)
		)
		(property "Author" "Antmicro"
			(at 202.16867 239.189005 0)
			(layer "B.Fab")
			(hide yes)
			(effects
				(font
					(size 1 1)
					(thickness 0.15)
				)
				(justify mirror)
			)
		)
		(property "Dielectric" "X5R"
			(at 202.16867 239.189005 0)
			(layer "B.Fab")
			(hide yes)
			(effects
				(font
					(size 1 1)
					(thickness 0.15)
				)
				(justify mirror)
			)
		)
		(property "License" "Apache-2.0"
			(at 202.16867 239.189005 0)
			(layer "B.Fab")
			(hide yes)
			(effects
				(font
					(size 1 1)
					(thickness 0.15)
				)
				(justify mirror)
			)
		)
		(property "MPN" "GRM155R61H104KE14D"
			(at 202.16867 239.189005 0)
			(layer "B.Fab")
			(hide yes)
			(effects
				(font
					(size 1 1)
					(thickness 0.15)
				)
				(justify mirror)
			)
		)
		(property "Manufacturer" "Murata"
			(at 202.16867 239.189005 0)
			(layer "B.Fab")
			(hide yes)
			(effects
				(font
					(size 1 1)
					(thickness 0.15)
				)
				(justify mirror)
			)
		)
		(property "Val" "100n"
			(at 202.16867 239.189005 0)
			(layer "B.Fab")
			(hide yes)
			(effects
				(font
					(size 1 1)
					(thickness 0.15)
				)
				(justify mirror)
			)
		)
		(property "Voltage" "50V"
			(at 202.16867 239.189005 0)
			(layer "B.Fab")
			(hide yes)
			(effects
				(font
					(size 1 1)
					(thickness 0.15)
				)
				(justify mirror)
			)
		)
		(sheetname "/Deserializer/")
		(sheetfile "deserializer.kicad_sch")
		(attr smd)
		(fp_poly
			(pts
				(xy -0.925 0.47) (xy 0.925 0.47) (xy 0.925 -0.47) (xy -0.925 -0.47)
			)
			(stroke
				(width 0.05)
				(type default)
			)
			(fill no)
			(layer "B.CrtYd")
		)
		(fp_line
			(start 0.504 0.25)
			(end -0.494 0.25)
			(stroke
				(width 0.15)
				(type solid)
			)
			(layer "B.Fab")
		)
		(fp_line
			(start 0.504 -0.248)
			(end 0.504 0.25)
			(stroke
				(width 0.15)
				(type solid)
			)
			(layer "B.Fab")
		)
		(fp_line
			(start -0.494 0.25)
			(end -0.494 -0.248)
			(stroke
				(width 0.15)
				(type solid)
			)
			(layer "B.Fab")
		)
		(fp_line
			(start -0.494 -0.248)
			(end 0.504 -0.248)
			(stroke
				(width 0.15)
				(type solid)
			)
			(layer "B.Fab")
		)
		(pad "1" smd roundrect
			(at -0.48 0 225)
			(size 0.59 0.64)
			(layers "B.Cu" "B.Mask" "B.Paste")
			(roundrect_rratio 0.25)
			(net 1 "GND")
			(pintype "passive")
		)
		(pad "2" smd roundrect
			(at 0.48 0 225)
			(size 0.59 0.64)
			(layers "B.Cu" "B.Mask" "B.Paste")
			(roundrect_rratio 0.25)
			(net 26 "/Deserializer/VDD_1.8V")
			(pintype "passive")
		)
	)
	(footprint "antmicro-footprints:R_0402_1005Metric"
		(layer "B.Cu")
		(at 150.8809 96.375897 90)
		(descr "Resistor SMD 0402")
		(tags "resistor SMD 0402")
		(property "Reference" "R77"
			(at 5.750329 0.414422 90)
			(layer "B.SilkS")
			(effects
				(font
					(size 0.7 0.7)
					(thickness 0.15)
				)
				(justify right bottom mirror)
			)
		)
		(property "Value" "R_470R_0402"
			(at -1.011843 -1.772046 90)
			(layer "B.Fab")
			(effects
				(font
					(size 0.7 0.7)
					(thickness 0.15)
				)
				(justify right bottom mirror)
			)
		)
		(property "Datasheet" "https://www.bourns.com/docs/product-datasheets/cr.pdf"
			(at 0 0 90)
			(layer "F.Fab")
			(hide yes)
			(effects
				(font
					(size 1.27 1.27)
					(thickness 0.15)
				)
			)
		)
		(property "Description" "SMD Chip Resistor, 470 ohm, ± 1%, 62.5 mW, 0402 [1005 Metric], Thick Film, General Purpose"
			(at 0 0 90)
			(layer "F.Fab")
			(hide yes)
			(effects
				(font
					(size 1.27 1.27)
					(thickness 0.15)
				)
			)
		)
		(property "Author" "Antmicro"
			(at 325.845911 56.529026 135)
			(layer "B.Fab")
			(hide yes)
			(effects
				(font
					(size 1 1)
					(thickness 0.15)
				)
				(justify mirror)
			)
		)
		(property "License" "Apache-2.0"
			(at 325.845911 56.529026 135)
			(layer "B.Fab")
			(hide yes)
			(effects
				(font
					(size 1 1)
					(thickness 0.15)
				)
				(justify mirror)
			)
		)
		(property "MPN" "CR0402-FX-4700GLF"
			(at 325.845911 56.529026 135)
			(layer "B.Fab")
			(hide yes)
			(effects
				(font
					(size 1 1)
					(thickness 0.15)
				)
				(justify mirror)
			)
		)
		(property "Manufacturer" "Bourns"
			(at 325.845911 56.529026 135)
			(layer "B.Fab")
			(hide yes)
			(effects
				(font
					(size 1 1)
					(thickness 0.15)
				)
				(justify mirror)
			)
		)
		(property "Tolerance" "1%"
			(at 325.845911 56.529026 135)
			(layer "B.Fab")
			(hide yes)
			(effects
				(font
					(size 1 1)
					(thickness 0.15)
				)
				(justify mirror)
			)
		)
		(property "Val" "470R"
			(at 325.845911 56.529026 135)
			(layer "B.Fab")
			(hide yes)
			(effects
				(font
					(size 1 1)
					(thickness 0.15)
				)
				(justify mirror)
			)
		)
		(sheetname "/Power/")
		(sheetfile "power.kicad_sch")
		(attr smd)
		(fp_poly
			(pts
				(xy -0.925 0.47) (xy 0.925 0.47) (xy 0.925 -0.47) (xy -0.925 -0.47)
			)
			(stroke
				(width 0.05)
				(type default)
			)
			(fill no)
			(layer "B.CrtYd")
		)
		(fp_poly
			(pts
				(xy -0.5 0.25) (xy 0.5 0.25) (xy 0.5 -0.25) (xy -0.5 -0.25)
			)
			(stroke
				(width 0.15)
				(type solid)
			)
			(fill no)
			(layer "B.Fab")
		)
		(pad "1" smd roundrect
			(at -0.48 0 90)
			(size 0.59 0.64)
			(layers "B.Cu" "B.Mask" "B.Paste")
			(roundrect_rratio 0.25)
			(net 1 "GND")
			(pintype "passive")
		)
		(pad "2" smd roundrect
			(at 0.48 0 90)
			(size 0.59 0.64)
			(layers "B.Cu" "B.Mask" "B.Paste")
			(roundrect_rratio 0.25)
			(net 140 "Net-(D16-C)")
			(pintype "passive")
		)
	)
	(footprint "antmicro-footprints:C_0402_1005Metric"
		(layer "B.Cu")
		(at 140.252 83.996 45)
		(descr "Capacitor SMD 0402")
		(tags "capacitor SMD 0402")
		(property "Reference" "C53"
			(at -3.792854 -0.017147 45)
			(layer "B.SilkS")
			(effects
				(font
					(size 0.7 0.7)
					(thickness 0.15)
				)
				(justify right bottom mirror)
			)
		)
		(property "Value" "C_100n_0402"
			(at -1.022927 -2.155213 45)
			(layer "B.Fab")
			(effects
				(font
					(size 0.7 0.7)
					(thickness 0.15)
				)
				(justify right bottom mirror)
			)
		)
		(property "Datasheet" "https://www.murata.com/products/productdetail?partno=GRM155R61H104KE14%23"
			(at 0 0 45)
			(layer "F.Fab")
			(hide yes)
			(effects
				(font
					(size 1.27 1.27)
					(thickness 0.15)
				)
			)
		)
		(property "Description" "SMD Multilayer Ceramic Capacitor, 0.1 µF, 50 V, 0402 [1005 Metric], ± 10%, X5R, GRM Series"
			(at 0 0 45)
			(layer "F.Fab")
			(hide yes)
			(effects
				(font
					(size 1.27 1.27)
					(thickness 0.15)
				)
			)
		)
		(property "Author" "Antmicro"
			(at 100.40723 -74.772495 0)
			(layer "B.Fab")
			(hide yes)
			(effects
				(font
					(size 1 1)
					(thickness 0.15)
				)
				(justify mirror)
			)
		)
		(property "Dielectric" "X5R"
			(at 100.40723 -74.772495 0)
			(layer "B.Fab")
			(hide yes)
			(effects
				(font
					(size 1 1)
					(thickness 0.15)
				)
				(justify mirror)
			)
		)
		(property "License" "Apache-2.0"
			(at 100.40723 -74.772495 0)
			(layer "B.Fab")
			(hide yes)
			(effects
				(font
					(size 1 1)
					(thickness 0.15)
				)
				(justify mirror)
			)
		)
		(property "MPN" "GRM155R61H104KE14D"
			(at 100.40723 -74.772495 0)
			(layer "B.Fab")
			(hide yes)
			(effects
				(font
					(size 1 1)
					(thickness 0.15)
				)
				(justify mirror)
			)
		)
		(property "Manufacturer" "Murata"
			(at 100.40723 -74.772495 0)
			(layer "B.Fab")
			(hide yes)
			(effects
				(font
					(size 1 1)
					(thickness 0.15)
				)
				(justify mirror)
			)
		)
		(property "Val" "100n"
			(at 100.40723 -74.772495 0)
			(layer "B.Fab")
			(hide yes)
			(effects
				(font
					(size 1 1)
					(thickness 0.15)
				)
				(justify mirror)
			)
		)
		(property "Voltage" "50V"
			(at 100.40723 -74.772495 0)
			(layer "B.Fab")
			(hide yes)
			(effects
				(font
					(size 1 1)
					(thickness 0.15)
				)
				(justify mirror)
			)
		)
		(sheetname "/Deserializer/")
		(sheetfile "deserializer.kicad_sch")
		(attr smd)
		(fp_poly
			(pts
				(xy -0.925 0.47) (xy 0.925 0.47) (xy 0.925 -0.47) (xy -0.925 -0.47)
			)
			(stroke
				(width 0.05)
				(type default)
			)
			(fill no)
			(layer "B.CrtYd")
		)
		(fp_line
			(start -0.494 -0.248)
			(end 0.504 -0.248)
			(stroke
				(width 0.15)
				(type solid)
			)
			(layer "B.Fab")
		)
		(fp_line
			(start -0.494 0.25)
			(end -0.494 -0.248)
			(stroke
				(width 0.15)
				(type solid)
			)
			(layer "B.Fab")
		)
		(fp_line
			(start 0.504 -0.248)
			(end 0.504 0.25)
			(stroke
				(width 0.15)
				(type solid)
			)
			(layer "B.Fab")
		)
		(fp_line
			(start 0.504 0.25)
			(end -0.494 0.25)
			(stroke
				(width 0.15)
				(type solid)
			)
			(layer "B.Fab")
		)
		(pad "1" smd roundrect
			(at -0.48 0 45)
			(size 0.59 0.64)
			(layers "B.Cu" "B.Mask" "B.Paste")
			(roundrect_rratio 0.25)
			(net 1 "GND")
			(pintype "passive")
		)
		(pad "2" smd roundrect
			(at 0.48 0 45)
			(size 0.59 0.64)
			(layers "B.Cu" "B.Mask" "B.Paste")
			(roundrect_rratio 0.25)
			(net 29 "/Deserializer/VTERM")
			(pintype "passive")
		)
	)
	(footprint "antmicro-footprints:TP_SMD_0.75mm"
		(layer "B.Cu")
		(at 146.304 97.89 180)
		(property "Reference" "TP16"
			(at 0 0.6 0)
			(layer "B.SilkS")
			(hide yes)
			(effects
				(font
					(size 0.7 0.7)
					(thickness 0.15)
				)
				(justify left bottom mirror)
			)
		)
		(property "Value" "TP_0.75mm_SMD"
			(at 0 -1.2 0)
			(layer "B.Fab")
			(effects
				(font
					(size 0.7 0.7)
					(thickness 0.15)
				)
				(justify left bottom mirror)
			)
		)
		(property "Description" "SMT test point"
			(at 0 0 0)
			(layer "B.Fab")
			(hide yes)
			(effects
				(font
					(size 1.27 1.27)
					(thickness 0.15)
				)
				(justify mirror)
			)
		)
		(property "MPN" ""
			(at 0 0 0)
			(unlocked yes)
			(layer "B.Fab")
			(hide yes)
			(effects
				(font
					(size 1 1)
					(thickness 0.15)
				)
				(justify mirror)
			)
		)
		(property "Manufacturer" ""
			(at 0 0 0)
			(unlocked yes)
			(layer "B.Fab")
			(hide yes)
			(effects
				(font
					(size 1 1)
					(thickness 0.15)
				)
				(justify mirror)
			)
		)
		(property "Author" "Antmicro"
			(at 0 0 0)
			(unlocked yes)
			(layer "B.Fab")
			(hide yes)
			(effects
				(font
					(size 1 1)
					(thickness 0.15)
				)
				(justify mirror)
			)
		)
		(property "License" "Apache-2.0"
			(at 0 0 0)
			(unlocked yes)
			(layer "B.Fab")
			(hide yes)
			(effects
				(font
					(size 1 1)
					(thickness 0.15)
				)
				(justify mirror)
			)
		)
		(sheetname "/Power/")
		(sheetfile "power.kicad_sch")
		(attr exclude_from_pos_files)
		(fp_circle
			(center 0 0)
			(end 0.475 0)
			(stroke
				(width 0.05)
				(type default)
			)
			(fill no)
			(layer "B.CrtYd")
		)
		(fp_text user "License: Apache-2.0"
			(at -0.4 -5.101 0)
			(layer "B.Fab")
			(effects
				(font
					(size 0.7 0.7)
					(thickness 0.15)
				)
				(justify left bottom mirror)
			)
		)
		(fp_text user "Author: Antmicro"
			(at -0.4 -3.901 0)
			(layer "B.Fab")
			(effects
				(font
					(size 0.7 0.7)
					(thickness 0.15)
				)
				(justify left bottom mirror)
			)
		)
		(fp_text user "${REFERENCE}"
			(at -0.4 -2.7 0)
			(layer "B.Fab")
			(effects
				(font
					(size 0.7 0.7)
					(thickness 0.15)
				)
				(justify left bottom mirror)
			)
		)
		(pad "1" smd circle
			(at 0 0 180)
			(size 0.75 0.75)
			(layers "B.Cu" "B.Mask")
			(net 11 "/Power/OUT_1V2")
			(pinfunction "1")
			(pintype "passive")
		)
	)
	(footprint "antmicro-footprints:C_0402_1005Metric"
		(layer "B.Cu")
		(at 149.098 76.2 -135)
		(descr "Capacitor SMD 0402")
		(tags "capacitor SMD 0402")
		(property "Reference" "C47"
			(at -3.681905 -0.449013 45)
			(layer "B.SilkS")
			(effects
				(font
					(size 0.7 0.7)
					(thickness 0.15)
				)
				(justify left bottom mirror)
			)
		)
		(property "Value" "C_100n_0402"
			(at -1.022927 -2.155213 45)
			(layer "B.Fab")
			(effects
				(font
					(size 0.7 0.7)
					(thickness 0.15)
				)
				(justify left bottom mirror)
			)
		)
		(property "Datasheet" "https://www.murata.com/products/productdetail?partno=GRM155R61H104KE14%23"
			(at 0 0 225)
			(layer "F.Fab")
			(hide yes)
			(effects
				(font
					(size 1.27 1.27)
					(thickness 0.15)
				)
			)
		)
		(property "Description" "SMD Multilayer Ceramic Capacitor, 0.1 µF, 50 V, 0402 [1005 Metric], ± 10%, X5R, GRM Series"
			(at 0 0 225)
			(layer "F.Fab")
			(hide yes)
			(effects
				(font
					(size 1.27 1.27)
					(thickness 0.15)
				)
			)
		)
		(property "Author" "Antmicro"
			(at 200.64467 235.509744 0)
			(layer "B.Fab")
			(hide yes)
			(effects
				(font
					(size 1 1)
					(thickness 0.15)
				)
				(justify mirror)
			)
		)
		(property "Dielectric" "X5R"
			(at 200.64467 235.509744 0)
			(layer "B.Fab")
			(hide yes)
			(effects
				(font
					(size 1 1)
					(thickness 0.15)
				)
				(justify mirror)
			)
		)
		(property "License" "Apache-2.0"
			(at 200.64467 235.509744 0)
			(layer "B.Fab")
			(hide yes)
			(effects
				(font
					(size 1 1)
					(thickness 0.15)
				)
				(justify mirror)
			)
		)
		(property "MPN" "GRM155R61H104KE14D"
			(at 200.64467 235.509744 0)
			(layer "B.Fab")
			(hide yes)
			(effects
				(font
					(size 1 1)
					(thickness 0.15)
				)
				(justify mirror)
			)
		)
		(property "Manufacturer" "Murata"
			(at 200.64467 235.509744 0)
			(layer "B.Fab")
			(hide yes)
			(effects
				(font
					(size 1 1)
					(thickness 0.15)
				)
				(justify mirror)
			)
		)
		(property "Val" "100n"
			(at 200.64467 235.509744 0)
			(layer "B.Fab")
			(hide yes)
			(effects
				(font
					(size 1 1)
					(thickness 0.15)
				)
				(justify mirror)
			)
		)
		(property "Voltage" "50V"
			(at 200.64467 235.509744 0)
			(layer "B.Fab")
			(hide yes)
			(effects
				(font
					(size 1 1)
					(thickness 0.15)
				)
				(justify mirror)
			)
		)
		(sheetname "/Deserializer/")
		(sheetfile "deserializer.kicad_sch")
		(attr smd)
		(fp_poly
			(pts
				(xy -0.925 0.47) (xy 0.925 0.47) (xy 0.925 -0.47) (xy -0.925 -0.47)
			)
			(stroke
				(width 0.05)
				(type default)
			)
			(fill no)
			(layer "B.CrtYd")
		)
		(fp_line
			(start 0.504 0.25)
			(end -0.494 0.25)
			(stroke
				(width 0.15)
				(type solid)
			)
			(layer "B.Fab")
		)
		(fp_line
			(start 0.504 -0.248)
			(end 0.504 0.25)
			(stroke
				(width 0.15)
				(type solid)
			)
			(layer "B.Fab")
		)
		(fp_line
			(start -0.494 0.25)
			(end -0.494 -0.248)
			(stroke
				(width 0.15)
				(type solid)
			)
			(layer "B.Fab")
		)
		(fp_line
			(start -0.494 -0.248)
			(end 0.504 -0.248)
			(stroke
				(width 0.15)
				(type solid)
			)
			(layer "B.Fab")
		)
		(pad "1" smd roundrect
			(at -0.48 0 225)
			(size 0.59 0.64)
			(layers "B.Cu" "B.Mask" "B.Paste")
			(roundrect_rratio 0.25)
			(net 1 "GND")
			(pintype "passive")
		)
		(pad "2" smd roundrect
			(at 0.48 0 225)
			(size 0.59 0.64)
			(layers "B.Cu" "B.Mask" "B.Paste")
			(roundrect_rratio 0.25)
			(net 28 "/Deserializer/CAP_VDD")
			(pintype "passive")
		)
	)
	(footprint "antmicro-footprints:R_0402_1005Metric"
		(layer "B.Cu")
		(at 136.55 89.45 -90)
		(descr "Resistor SMD 0402")
		(tags "resistor SMD 0402")
		(property "Reference" "R74"
			(at 0.85 -0.45 90)
			(layer "B.SilkS")
			(effects
				(font
					(size 0.7 0.7)
					(thickness 0.15)
				)
				(justify left bottom mirror)
			)
		)
		(property "Value" "R_100k_0402"
			(at -1.011843 -1.772047 90)
			(layer "B.Fab")
			(effects
				(font
					(size 0.7 0.7)
					(thickness 0.15)
				)
				(justify left bottom mirror)
			)
		)
		(property "Datasheet" "https://www.bourns.com/docs/product-datasheets/cr.pdf"
			(at 0 0 270)
			(layer "F.Fab")
			(hide yes)
			(effects
				(font
					(size 1.27 1.27)
					(thickness 0.15)
				)
			)
		)
		(property "Description" "SMD Chip Resistor, 100 kohm, ± 1%, 62.5 mW, 0402 [1005 Metric], Thick Film, General Purpose"
			(at 0 0 270)
			(layer "F.Fab")
			(hide yes)
			(effects
				(font
					(size 1.27 1.27)
					(thickness 0.15)
				)
			)
		)
		(property "Author" "Antmicro"
			(at 47.1 226 0)
			(layer "B.Fab")
			(hide yes)
			(effects
				(font
					(size 1 1)
					(thickness 0.15)
				)
				(justify mirror)
			)
		)
		(property "License" "Apache-2.0"
			(at 47.1 226 0)
			(layer "B.Fab")
			(hide yes)
			(effects
				(font
					(size 1 1)
					(thickness 0.15)
				)
				(justify mirror)
			)
		)
		(property "MPN" "CR0402-FX-1003GLF"
			(at 47.1 226 0)
			(layer "B.Fab")
			(hide yes)
			(effects
				(font
					(size 1 1)
					(thickness 0.15)
				)
				(justify mirror)
			)
		)
		(property "Manufacturer" "Bourns"
			(at 47.1 226 0)
			(layer "B.Fab")
			(hide yes)
			(effects
				(font
					(size 1 1)
					(thickness 0.15)
				)
				(justify mirror)
			)
		)
		(property "Tolerance" "1%"
			(at 47.1 226 0)
			(layer "B.Fab")
			(hide yes)
			(effects
				(font
					(size 1 1)
					(thickness 0.15)
				)
				(justify mirror)
			)
		)
		(property "Val" "100k"
			(at 47.1 226 0)
			(layer "B.Fab")
			(hide yes)
			(effects
				(font
					(size 1 1)
					(thickness 0.15)
				)
				(justify mirror)
			)
		)
		(sheetname "/Power/")
		(sheetfile "power.kicad_sch")
		(attr smd)
		(fp_rect
			(start -0.925 0.47)
			(end 0.925 -0.47)
			(stroke
				(width 0.05)
				(type default)
			)
			(fill no)
			(layer "B.CrtYd")
		)
		(fp_rect
			(start -0.5 0.25)
			(end 0.5 -0.25)
			(stroke
				(width 0.15)
				(type solid)
			)
			(fill no)
			(layer "B.Fab")
		)
		(pad "1" smd roundrect
			(at -0.48 0 270)
			(size 0.59 0.64)
			(layers "B.Cu" "B.Mask" "B.Paste")
			(roundrect_rratio 0.25)
			(net 1 "GND")
			(pintype "passive")
		)
		(pad "2" smd roundrect
			(at 0.48 0 270)
			(size 0.59 0.64)
			(layers "B.Cu" "B.Mask" "B.Paste")
			(roundrect_rratio 0.25)
			(net 10 "/Power/OUT_1V8")
			(pintype "passive")
		)
	)
	(footprint "antmicro-footprints:SOT-523"
		(layer "B.Cu")
		(at 134.9 89.65)
		(property "Reference" "Q4"
			(at -0.8 2.05 0)
			(layer "B.SilkS")
			(effects
				(font
					(size 0.7 0.7)
					(thickness 0.15)
				)
				(justify right bottom mirror)
			)
		)
		(property "Value" "DMG1012T-7"
			(at 0.1 -1.824 0)
			(layer "B.Fab")
			(effects
				(font
					(size 0.7 0.7)
					(thickness 0.15)
				)
				(justify right bottom mirror)
			)
		)
		(property "Datasheet" "https://www.diodes.com/assets/Datasheets/ds31783.pdf"
			(at 0 0 0)
			(layer "F.Fab")
			(hide yes)
			(effects
				(font
					(size 1.27 1.27)
					(thickness 0.15)
				)
			)
		)
		(property "Description" "Power MOSFET, N Channel, 20 V, 630 mA, 0.3 ohm, SOT-523, Surface Mount"
			(at 0 0 0)
			(layer "F.Fab")
			(hide yes)
			(effects
				(font
					(size 1.27 1.27)
					(thickness 0.15)
				)
			)
		)
		(property "Author" "Antmicro"
			(at 0 0 0)
			(layer "B.Fab")
			(hide yes)
			(effects
				(font
					(size 1 1)
					(thickness 0.15)
				)
				(justify mirror)
			)
		)
		(property "License" "Apache-2.0"
			(at 0 0 0)
			(layer "B.Fab")
			(hide yes)
			(effects
				(font
					(size 1 1)
					(thickness 0.15)
				)
				(justify mirror)
			)
		)
		(property "MPN" "DMG1012T-7"
			(at 0 0 0)
			(layer "B.Fab")
			(hide yes)
			(effects
				(font
					(size 1 1)
					(thickness 0.15)
				)
				(justify mirror)
			)
		)
		(property "Manufacturer" "Diodes Incorporated"
			(at 0 0 0)
			(layer "B.Fab")
			(hide yes)
			(effects
				(font
					(size 1 1)
					(thickness 0.15)
				)
				(justify mirror)
			)
		)
		(property "Public" ""
			(at 0 0 0)
			(layer "B.Fab")
			(hide yes)
			(effects
				(font
					(size 1 1)
					(thickness 0.15)
				)
				(justify mirror)
			)
		)
		(sheetname "/Power/")
		(sheetfile "power.kicad_sch")
		(attr smd)
		(fp_line
			(start -0.927 0.351)
			(end -0.927 0.051)
			(stroke
				(width 0.15)
				(type solid)
			)
			(layer "B.SilkS")
		)
		(fp_line
			(start -0.725 0.551)
			(end -0.927 0.351)
			(stroke
				(width 0.15)
				(type solid)
			)
			(layer "B.SilkS")
		)
		(fp_line
			(start -0.277 0.551)
			(end -0.725 0.551)
			(stroke
				(width 0.15)
				(type solid)
			)
			(layer "B.SilkS")
		)
		(fp_line
			(start -0.277 0.75)
			(end -0.277 0.551)
			(stroke
				(width 0.15)
				(type solid)
			)
			(layer "B.SilkS")
		)
		(fp_circle
			(center -0.9652 -0.9652)
			(end -0.9152 -0.9652)
			(stroke
				(width 0.15)
				(type solid)
			)
			(fill yes)
			(layer "B.SilkS")
		)
		(fp_line
			(start -1.12 -1.15)
			(end -1.12 1.16)
			(stroke
				(width 0.05)
				(type solid)
			)
			(layer "B.CrtYd")
		)
		(fp_line
			(start 1.1 -1.15)
			(end -1.12 -1.15)
			(stroke
				(width 0.05)
				(type solid)
			)
			(layer "B.CrtYd")
		)
		(fp_line
			(start 1.1 -1.15)
			(end 1.1 1.16)
			(stroke
				(width 0.05)
				(type solid)
			)
			(layer "B.CrtYd")
		)
		(fp_line
			(start 1.1 1.16)
			(end -1.12 1.16)
			(stroke
				(width 0.05)
				(type solid)
			)
			(layer "B.CrtYd")
		)
		(fp_line
			(start -0.802 -0.424)
			(end -0.802 0.276)
			(stroke
				(width 0.15)
				(type solid)
			)
			(layer "B.Fab")
		)
		(fp_line
			(start -0.802 -0.424)
			(end 0.8 -0.424)
			(stroke
				(width 0.15)
				(type solid)
			)
			(layer "B.Fab")
		)
		(fp_line
			(start -0.802 0.276)
			(end -0.652 0.425)
			(stroke
				(width 0.15)
				(type solid)
			)
			(layer "B.Fab")
		)
		(fp_line
			(start -0.652 0.425)
			(end 0.8 0.425)
			(stroke
				(width 0.15)
				(type solid)
			)
			(layer "B.Fab")
		)
		(fp_line
			(start 0.8 -0.424)
			(end 0.8 0.425)
			(stroke
				(width 0.15)
				(type solid)
			)
			(layer "B.Fab")
		)
		(fp_circle
			(center -0.9652 -0.9652)
			(end -0.9144 -0.9652)
			(stroke
				(width 0.15)
				(type solid)
			)
			(fill no)
			(layer "B.Fab")
		)
		(pad "1" smd rect
			(at -0.5 -0.65)
			(size 0.4 0.51)
			(layers "B.Cu" "B.Mask" "B.Paste")
			(net 11 "/Power/OUT_1V2")
			(pinfunction "G")
			(pintype "input")
		)
		(pad "2" smd rect
			(at 0.498 -0.65)
			(size 0.4 0.51)
			(layers "B.Cu" "B.Mask" "B.Paste")
			(net 1 "GND")
			(pinfunction "S")
			(pintype "passive")
		)
		(pad "3" smd rect
			(at 0 0.652)
			(size 0.4 0.51)
			(layers "B.Cu" "B.Mask" "B.Paste")
			(net 143 "Net-(D19-C)")
			(pinfunction "D")
			(pintype "passive")
		)
	)
	(footprint "antmicro-footprints:SOT-523"
		(layer "B.Cu")
		(at 162.45 96.2 180)
		(property "Reference" "Q6"
			(at -1.25 1.3 0)
			(layer "B.SilkS")
			(effects
				(font
					(size 0.7 0.7)
					(thickness 0.15)
				)
				(justify left bottom mirror)
			)
		)
		(property "Value" "DMG1012T-7"
			(at 0.1 -1.824 0)
			(layer "B.Fab")
			(effects
				(font
					(size 0.7 0.7)
					(thickness 0.15)
				)
				(justify left bottom mirror)
			)
		)
		(property "Datasheet" "https://www.diodes.com/assets/Datasheets/ds31783.pdf"
			(at 0 0 180)
			(layer "F.Fab")
			(hide yes)
			(effects
				(font
					(size 1.27 1.27)
					(thickness 0.15)
				)
			)
		)
		(property "Description" "Power MOSFET, N Channel, 20 V, 630 mA, 0.3 ohm, SOT-523, Surface Mount"
			(at 0 0 180)
			(layer "F.Fab")
			(hide yes)
			(effects
				(font
					(size 1.27 1.27)
					(thickness 0.15)
				)
			)
		)
		(property "Author" "Antmicro"
			(at 324.9 192.4 0)
			(layer "B.Fab")
			(hide yes)
			(effects
				(font
					(size 1 1)
					(thickness 0.15)
				)
				(justify mirror)
			)
		)
		(property "License" "Apache-2.0"
			(at 324.9 192.4 0)
			(layer "B.Fab")
			(hide yes)
			(effects
				(font
					(size 1 1)
					(thickness 0.15)
				)
				(justify mirror)
			)
		)
		(property "MPN" "DMG1012T-7"
			(at 324.9 192.4 0)
			(layer "B.Fab")
			(hide yes)
			(effects
				(font
					(size 1 1)
					(thickness 0.15)
				)
				(justify mirror)
			)
		)
		(property "Manufacturer" "Diodes Incorporated"
			(at 324.9 192.4 0)
			(layer "B.Fab")
			(hide yes)
			(effects
				(font
					(size 1 1)
					(thickness 0.15)
				)
				(justify mirror)
			)
		)
		(property "Public" ""
			(at 324.9 192.4 0)
			(layer "B.Fab")
			(hide yes)
			(effects
				(font
					(size 1 1)
					(thickness 0.15)
				)
				(justify mirror)
			)
		)
		(sheetname "/Connectors/")
		(sheetfile "connectors.kicad_sch")
		(attr smd)
		(fp_line
			(start -0.277 0.75)
			(end -0.277 0.551)
			(stroke
				(width 0.15)
				(type solid)
			)
			(layer "B.SilkS")
		)
		(fp_line
			(start -0.277 0.551)
			(end -0.725 0.551)
			(stroke
				(width 0.15)
				(type solid)
			)
			(layer "B.SilkS")
		)
		(fp_line
			(start -0.725 0.551)
			(end -0.927 0.351)
			(stroke
				(width 0.15)
				(type solid)
			)
			(layer "B.SilkS")
		)
		(fp_line
			(start -0.927 0.351)
			(end -0.927 0.051)
			(stroke
				(width 0.15)
				(type solid)
			)
			(layer "B.SilkS")
		)
		(fp_circle
			(center -0.9652 -0.9652)
			(end -0.9152 -0.9652)
			(stroke
				(width 0.15)
				(type solid)
			)
			(fill yes)
			(layer "B.SilkS")
		)
		(fp_line
			(start 1.1 1.16)
			(end -1.12 1.16)
			(stroke
				(width 0.05)
				(type solid)
			)
			(layer "B.CrtYd")
		)
		(fp_line
			(start 1.1 -1.15)
			(end 1.1 1.16)
			(stroke
				(width 0.05)
				(type solid)
			)
			(layer "B.CrtYd")
		)
		(fp_line
			(start 1.1 -1.15)
			(end -1.12 -1.15)
			(stroke
				(width 0.05)
				(type solid)
			)
			(layer "B.CrtYd")
		)
		(fp_line
			(start -1.12 -1.15)
			(end -1.12 1.16)
			(stroke
				(width 0.05)
				(type solid)
			)
			(layer "B.CrtYd")
		)
		(fp_line
			(start 0.8 -0.424)
			(end 0.8 0.425)
			(stroke
				(width 0.15)
				(type solid)
			)
			(layer "B.Fab")
		)
		(fp_line
			(start -0.652 0.425)
			(end 0.8 0.425)
			(stroke
				(width 0.15)
				(type solid)
			)
			(layer "B.Fab")
		)
		(fp_line
			(start -0.802 0.276)
			(end -0.652 0.425)
			(stroke
				(width 0.15)
				(type solid)
			)
			(layer "B.Fab")
		)
		(fp_line
			(start -0.802 -0.424)
			(end 0.8 -0.424)
			(stroke
				(width 0.15)
				(type solid)
			)
			(layer "B.Fab")
		)
		(fp_line
			(start -0.802 -0.424)
			(end -0.802 0.276)
			(stroke
				(width 0.15)
				(type solid)
			)
			(layer "B.Fab")
		)
		(fp_circle
			(center -0.9652 -0.9652)
			(end -0.9144 -0.9652)
			(stroke
				(width 0.15)
				(type solid)
			)
			(fill no)
			(layer "B.Fab")
		)
		(pad "1" smd rect
			(at -0.5 -0.65 180)
			(size 0.4 0.51)
			(layers "B.Cu" "B.Mask" "B.Paste")
			(net 84 "/Connectors/MFP4")
			(pinfunction "G")
			(pintype "input")
		)
		(pad "2" smd rect
			(at 0.498 -0.65 180)
			(size 0.4 0.51)
			(layers "B.Cu" "B.Mask" "B.Paste")
			(net 1 "GND")
			(pinfunction "S")
			(pintype "passive")
		)
		(pad "3" smd rect
			(at 0 0.652 180)
			(size 0.4 0.51)
			(layers "B.Cu" "B.Mask" "B.Paste")
			(net 111 "Net-(D14-C)")
			(pinfunction "D")
			(pintype "passive")
		)
	)
	(footprint "antmicro-footprints:R_0402_1005Metric"
		(layer "B.Cu")
		(at 158.500124 96.375897 -90)
		(descr "Resistor SMD 0402")
		(tags "resistor SMD 0402")
		(property "Reference" "R82"
			(at -2.935369 -0.483209 90)
			(layer "B.SilkS")
			(effects
				(font
					(size 0.7 0.7)
					(thickness 0.15)
				)
				(justify left bottom mirror)
			)
		)
		(property "Value" "R_470R_0402"
			(at -1.011843 -1.772046 90)
			(layer "B.Fab")
			(effects
				(font
					(size 0.7 0.7)
					(thickness 0.15)
				)
				(justify left bottom mirror)
			)
		)
		(property "Datasheet" "https://www.bourns.com/docs/product-datasheets/cr.pdf"
			(at 0 0 90)
			(layer "F.Fab")
			(hide yes)
			(effects
				(font
					(size 1.27 1.27)
					(thickness 0.15)
				)
			)
		)
		(property "Description" "SMD Chip Resistor, 470 ohm, ± 1%, 62.5 mW, 0402 [1005 Metric], Thick Film, General Purpose"
			(at 0 0 90)
			(layer "F.Fab")
			(hide yes)
			(effects
				(font
					(size 1.27 1.27)
					(thickness 0.15)
				)
			)
		)
		(property "Author" "Antmicro"
			(at -21.176172 140.355021 135)
			(layer "B.Fab")
			(hide yes)
			(effects
				(font
					(size 1 1)
					(thickness 0.15)
				)
				(justify mirror)
			)
		)
		(property "License" "Apache-2.0"
			(at -21.176172 140.355021 135)
			(layer "B.Fab")
			(hide yes)
			(effects
				(font
					(size 1 1)
					(thickness 0.15)
				)
				(justify mirror)
			)
		)
		(property "MPN" "CR0402-FX-4700GLF"
			(at -21.176172 140.355021 135)
			(layer "B.Fab")
			(hide yes)
			(effects
				(font
					(size 1 1)
					(thickness 0.15)
				)
				(justify mirror)
			)
		)
		(property "Manufacturer" "Bourns"
			(at -21.176172 140.355021 135)
			(layer "B.Fab")
			(hide yes)
			(effects
				(font
					(size 1 1)
					(thickness 0.15)
				)
				(justify mirror)
			)
		)
		(property "Tolerance" "1%"
			(at -21.176172 140.355021 135)
			(layer "B.Fab")
			(hide yes)
			(effects
				(font
					(size 1 1)
					(thickness 0.15)
				)
				(justify mirror)
			)
		)
		(property "Val" "470R"
			(at -21.176172 140.355021 135)
			(layer "B.Fab")
			(hide yes)
			(effects
				(font
					(size 1 1)
					(thickness 0.15)
				)
				(justify mirror)
			)
		)
		(sheetname "/Connectors/")
		(sheetfile "connectors.kicad_sch")
		(attr smd)
		(fp_poly
			(pts
				(xy -0.925 0.47) (xy 0.925 0.47) (xy 0.925 -0.47) (xy -0.925 -0.47)
			)
			(stroke
				(width 0.05)
				(type default)
			)
			(fill no)
			(layer "B.CrtYd")
		)
		(fp_poly
			(pts
				(xy -0.5 0.25) (xy 0.5 0.25) (xy 0.5 -0.25) (xy -0.5 -0.25)
			)
			(stroke
				(width 0.15)
				(type solid)
			)
			(fill no)
			(layer "B.Fab")
		)
		(pad "1" smd roundrect
			(at -0.48 0 270)
			(size 0.59 0.64)
			(layers "B.Cu" "B.Mask" "B.Paste")
			(roundrect_rratio 0.25)
			(net 110 "Net-(D14-A)")
			(pintype "passive")
		)
		(pad "2" smd roundrect
			(at 0.48 0 270)
			(size 0.59 0.64)
			(layers "B.Cu" "B.Mask" "B.Paste")
			(roundrect_rratio 0.25)
			(net 5 "+5V")
			(pintype "passive")
		)
	)
	(footprint "antmicro-footprints:TP_SMD_0.75mm"
		(layer "B.Cu")
		(at 130.81 84.8 180)
		(property "Reference" "TP27"
			(at 0 0.6 0)
			(layer "B.SilkS")
			(hide yes)
			(effects
				(font
					(size 0.7 0.7)
					(thickness 0.15)
				)
				(justify left bottom mirror)
			)
		)
		(property "Value" "TP_0.75mm_SMD"
			(at 0 -1.2 0)
			(layer "B.Fab")
			(effects
				(font
					(size 0.7 0.7)
					(thickness 0.15)
				)
				(justify left bottom mirror)
			)
		)
		(property "Description" "SMT test point"
			(at 0 0 0)
			(layer "B.Fab")
			(hide yes)
			(effects
				(font
					(size 1.27 1.27)
					(thickness 0.15)
				)
				(justify mirror)
			)
		)
		(property "MPN" ""
			(at 0 0 0)
			(unlocked yes)
			(layer "B.Fab")
			(hide yes)
			(effects
				(font
					(size 1 1)
					(thickness 0.15)
				)
				(justify mirror)
			)
		)
		(property "Manufacturer" ""
			(at 0 0 0)
			(unlocked yes)
			(layer "B.Fab")
			(hide yes)
			(effects
				(font
					(size 1 1)
					(thickness 0.15)
				)
				(justify mirror)
			)
		)
		(property "Author" "Antmicro"
			(at 0 0 0)
			(unlocked yes)
			(layer "B.Fab")
			(hide yes)
			(effects
				(font
					(size 1 1)
					(thickness 0.15)
				)
				(justify mirror)
			)
		)
		(property "License" "Apache-2.0"
			(at 0 0 0)
			(unlocked yes)
			(layer "B.Fab")
			(hide yes)
			(effects
				(font
					(size 1 1)
					(thickness 0.15)
				)
				(justify mirror)
			)
		)
		(sheetname "/Power/")
		(sheetfile "power.kicad_sch")
		(attr exclude_from_pos_files)
		(fp_circle
			(center 0 0)
			(end 0.475 0)
			(stroke
				(width 0.05)
				(type default)
			)
			(fill no)
			(layer "B.CrtYd")
		)
		(fp_text user "${REFERENCE}"
			(at -0.4 -2.7 0)
			(layer "B.Fab")
			(effects
				(font
					(size 0.7 0.7)
					(thickness 0.15)
				)
				(justify left bottom mirror)
			)
		)
		(fp_text user "Author: Antmicro"
			(at -0.4 -3.901 0)
			(layer "B.Fab")
			(effects
				(font
					(size 0.7 0.7)
					(thickness 0.15)
				)
				(justify left bottom mirror)
			)
		)
		(fp_text user "License: Apache-2.0"
			(at -0.4 -5.101 0)
			(layer "B.Fab")
			(effects
				(font
					(size 0.7 0.7)
					(thickness 0.15)
				)
				(justify left bottom mirror)
			)
		)
		(pad "1" smd circle
			(at 0 0 180)
			(size 0.75 0.75)
			(layers "B.Cu" "B.Mask")
			(net 73 "+1V2")
			(pinfunction "1")
			(pintype "passive")
		)
	)
	(footprint "antmicro-footprints:TP_SMD_0.75mm"
		(layer "B.Cu")
		(at 149.35 97.9 180)
		(property "Reference" "TP20"
			(at 0 0.6 0)
			(layer "B.SilkS")
			(hide yes)
			(effects
				(font
					(size 0.7 0.7)
					(thickness 0.15)
				)
				(justify left bottom mirror)
			)
		)
		(property "Value" "TP_0.75mm_SMD"
			(at 0 -1.2 0)
			(layer "B.Fab")
			(effects
				(font
					(size 0.7 0.7)
					(thickness 0.15)
				)
				(justify left bottom mirror)
			)
		)
		(property "Description" "SMT test point"
			(at 0 0 0)
			(layer "B.Fab")
			(hide yes)
			(effects
				(font
					(size 1.27 1.27)
					(thickness 0.15)
				)
				(justify mirror)
			)
		)
		(property "MPN" ""
			(at 0 0 0)
			(unlocked yes)
			(layer "B.Fab")
			(hide yes)
			(effects
				(font
					(size 1 1)
					(thickness 0.15)
				)
				(justify mirror)
			)
		)
		(property "Manufacturer" ""
			(at 0 0 0)
			(unlocked yes)
			(layer "B.Fab")
			(hide yes)
			(effects
				(font
					(size 1 1)
					(thickness 0.15)
				)
				(justify mirror)
			)
		)
		(property "Author" "Antmicro"
			(at 0 0 0)
			(unlocked yes)
			(layer "B.Fab")
			(hide yes)
			(effects
				(font
					(size 1 1)
					(thickness 0.15)
				)
				(justify mirror)
			)
		)
		(property "License" "Apache-2.0"
			(at 0 0 0)
			(unlocked yes)
			(layer "B.Fab")
			(hide yes)
			(effects
				(font
					(size 1 1)
					(thickness 0.15)
				)
				(justify mirror)
			)
		)
		(sheetname "/Power/")
		(sheetfile "power.kicad_sch")
		(attr exclude_from_pos_files)
		(fp_circle
			(center 0 0)
			(end 0.475 0)
			(stroke
				(width 0.05)
				(type default)
			)
			(fill no)
			(layer "B.CrtYd")
		)
		(fp_text user "Author: Antmicro"
			(at -0.4 -3.901 0)
			(layer "B.Fab")
			(effects
				(font
					(size 0.7 0.7)
					(thickness 0.15)
				)
				(justify left bottom mirror)
			)
		)
		(fp_text user "${REFERENCE}"
			(at -0.4 -2.7 0)
			(layer "B.Fab")
			(effects
				(font
					(size 0.7 0.7)
					(thickness 0.15)
				)
				(justify left bottom mirror)
			)
		)
		(fp_text user "License: Apache-2.0"
			(at -0.4 -5.101 0)
			(layer "B.Fab")
			(effects
				(font
					(size 0.7 0.7)
					(thickness 0.15)
				)
				(justify left bottom mirror)
			)
		)
		(pad "1" smd circle
			(at 0 0 180)
			(size 0.75 0.75)
			(layers "B.Cu" "B.Mask")
			(net 4 "+12V")
			(pinfunction "1")
			(pintype "passive")
		)
	)
	(footprint "antmicro-footprints:R_0402_1005Metric"
		(layer "B.Cu")
		(at 147.867621 96.375897 90)
		(descr "Resistor SMD 0402")
		(tags "resistor SMD 0402")
		(property "Reference" "R78"
			(at 5.724873 0.425736 90)
			(layer "B.SilkS")
			(effects
				(font
					(size 0.7 0.7)
					(thickness 0.15)
				)
				(justify right bottom mirror)
			)
		)
		(property "Value" "R_1k65_0402"
			(at -1.011843 -1.772046 90)
			(layer "B.Fab")
			(effects
				(font
					(size 0.7 0.7)
					(thickness 0.15)
				)
				(justify right bottom mirror)
			)
		)
		(property "Datasheet" "https://www.farnell.com/datasheets/3795017.pdf"
			(at 0 0 90)
			(layer "F.Fab")
			(hide yes)
			(effects
				(font
					(size 1.27 1.27)
					(thickness 0.15)
				)
			)
		)
		(property "Description" "SMD Chip Resistor, 1.65 kohm, ± 1%, 63 mW, 0402 [1005 Metric], Thick Film, General Purpose"
			(at 0 0 90)
			(layer "F.Fab")
			(hide yes)
			(effects
				(font
					(size 1.27 1.27)
					(thickness 0.15)
				)
			)
		)
		(property "Author" "Antmicro"
			(at 320.63778 58.566305 135)
			(layer "B.Fab")
			(hide yes)
			(effects
				(font
					(size 1 1)
					(thickness 0.15)
				)
				(justify mirror)
			)
		)
		(property "License" "Apache-2.0"
			(at 320.63778 58.566305 135)
			(layer "B.Fab")
			(hide yes)
			(effects
				(font
					(size 1 1)
					(thickness 0.15)
				)
				(justify mirror)
			)
		)
		(property "MPN" "RC0402FR-071K65L"
			(at 320.63778 58.566305 135)
			(layer "B.Fab")
			(hide yes)
			(effects
				(font
					(size 1 1)
					(thickness 0.15)
				)
				(justify mirror)
			)
		)
		(property "Manufacturer" "YAGEO"
			(at 320.63778 58.566305 135)
			(layer "B.Fab")
			(hide yes)
			(effects
				(font
					(size 1 1)
					(thickness 0.15)
				)
				(justify mirror)
			)
		)
		(property "Public" ""
			(at 320.63778 58.566305 135)
			(layer "B.Fab")
			(hide yes)
			(effects
				(font
					(size 1 1)
					(thickness 0.15)
				)
				(justify mirror)
			)
		)
		(property "Tolerance" "1%"
			(at 320.63778 58.566305 135)
			(layer "B.Fab")
			(hide yes)
			(effects
				(font
					(size 1 1)
					(thickness 0.15)
				)
				(justify mirror)
			)
		)
		(property "Val" "1k65"
			(at 320.63778 58.566305 135)
			(layer "B.Fab")
			(hide yes)
			(effects
				(font
					(size 1 1)
					(thickness 0.15)
				)
				(justify mirror)
			)
		)
		(sheetname "/Power/")
		(sheetfile "power.kicad_sch")
		(attr smd)
		(fp_poly
			(pts
				(xy -0.925 0.47) (xy 0.925 0.47) (xy 0.925 -0.47) (xy -0.925 -0.47)
			)
			(stroke
				(width 0.05)
				(type default)
			)
			(fill no)
			(layer "B.CrtYd")
		)
		(fp_poly
			(pts
				(xy -0.5 0.25) (xy 0.5 0.25) (xy 0.5 -0.25) (xy -0.5 -0.25)
			)
			(stroke
				(width 0.15)
				(type solid)
			)
			(fill no)
			(layer "B.Fab")
		)
		(pad "1" smd roundrect
			(at -0.48 0 90)
			(size 0.59 0.64)
			(layers "B.Cu" "B.Mask" "B.Paste")
			(roundrect_rratio 0.25)
			(net 1 "GND")
			(pintype "passive")
		)
		(pad "2" smd roundrect
			(at 0.48 0 90)
			(size 0.59 0.64)
			(layers "B.Cu" "B.Mask" "B.Paste")
			(roundrect_rratio 0.25)
			(net 142 "Net-(D18-C)")
			(pintype "passive")
		)
	)
	(footprint "antmicro-footprints:SOT-523"
		(layer "B.Cu")
		(at 138.2 89.65)
		(property "Reference" "Q5"
			(at -0.75 2 0)
			(layer "B.SilkS")
			(effects
				(font
					(size 0.7 0.7)
					(thickness 0.15)
				)
				(justify right bottom mirror)
			)
		)
		(property "Value" "DMG1012T-7"
			(at 0.1 -1.824 0)
			(layer "B.Fab")
			(effects
				(font
					(size 0.7 0.7)
					(thickness 0.15)
				)
				(justify right bottom mirror)
			)
		)
		(property "Datasheet" "https://www.diodes.com/assets/Datasheets/ds31783.pdf"
			(at 0 0 0)
			(layer "F.Fab")
			(hide yes)
			(effects
				(font
					(size 1.27 1.27)
					(thickness 0.15)
				)
			)
		)
		(property "Description" "Power MOSFET, N Channel, 20 V, 630 mA, 0.3 ohm, SOT-523, Surface Mount"
			(at 0 0 0)
			(layer "F.Fab")
			(hide yes)
			(effects
				(font
					(size 1.27 1.27)
					(thickness 0.15)
				)
			)
		)
		(property "Author" "Antmicro"
			(at 0 0 0)
			(layer "B.Fab")
			(hide yes)
			(effects
				(font
					(size 1 1)
					(thickness 0.15)
				)
				(justify mirror)
			)
		)
		(property "License" "Apache-2.0"
			(at 0 0 0)
			(layer "B.Fab")
			(hide yes)
			(effects
				(font
					(size 1 1)
					(thickness 0.15)
				)
				(justify mirror)
			)
		)
		(property "MPN" "DMG1012T-7"
			(at 0 0 0)
			(layer "B.Fab")
			(hide yes)
			(effects
				(font
					(size 1 1)
					(thickness 0.15)
				)
				(justify mirror)
			)
		)
		(property "Manufacturer" "Diodes Incorporated"
			(at 0 0 0)
			(layer "B.Fab")
			(hide yes)
			(effects
				(font
					(size 1 1)
					(thickness 0.15)
				)
				(justify mirror)
			)
		)
		(property "Public" ""
			(at 0 0 0)
			(layer "B.Fab")
			(hide yes)
			(effects
				(font
					(size 1 1)
					(thickness 0.15)
				)
				(justify mirror)
			)
		)
		(sheetname "/Power/")
		(sheetfile "power.kicad_sch")
		(attr smd)
		(fp_line
			(start -0.927 0.351)
			(end -0.927 0.051)
			(stroke
				(width 0.15)
				(type solid)
			)
			(layer "B.SilkS")
		)
		(fp_line
			(start -0.725 0.551)
			(end -0.927 0.351)
			(stroke
				(width 0.15)
				(type solid)
			)
			(layer "B.SilkS")
		)
		(fp_line
			(start -0.277 0.551)
			(end -0.725 0.551)
			(stroke
				(width 0.15)
				(type solid)
			)
			(layer "B.SilkS")
		)
		(fp_line
			(start -0.277 0.75)
			(end -0.277 0.551)
			(stroke
				(width 0.15)
				(type solid)
			)
			(layer "B.SilkS")
		)
		(fp_circle
			(center -0.9652 -0.9652)
			(end -0.9152 -0.9652)
			(stroke
				(width 0.15)
				(type solid)
			)
			(fill yes)
			(layer "B.SilkS")
		)
		(fp_line
			(start -1.12 -1.15)
			(end -1.12 1.16)
			(stroke
				(width 0.05)
				(type solid)
			)
			(layer "B.CrtYd")
		)
		(fp_line
			(start 1.1 -1.15)
			(end -1.12 -1.15)
			(stroke
				(width 0.05)
				(type solid)
			)
			(layer "B.CrtYd")
		)
		(fp_line
			(start 1.1 -1.15)
			(end 1.1 1.16)
			(stroke
				(width 0.05)
				(type solid)
			)
			(layer "B.CrtYd")
		)
		(fp_line
			(start 1.1 1.16)
			(end -1.12 1.16)
			(stroke
				(width 0.05)
				(type solid)
			)
			(layer "B.CrtYd")
		)
		(fp_line
			(start -0.802 -0.424)
			(end -0.802 0.276)
			(stroke
				(width 0.15)
				(type solid)
			)
			(layer "B.Fab")
		)
		(fp_line
			(start -0.802 -0.424)
			(end 0.8 -0.424)
			(stroke
				(width 0.15)
				(type solid)
			)
			(layer "B.Fab")
		)
		(fp_line
			(start -0.802 0.276)
			(end -0.652 0.425)
			(stroke
				(width 0.15)
				(type solid)
			)
			(layer "B.Fab")
		)
		(fp_line
			(start -0.652 0.425)
			(end 0.8 0.425)
			(stroke
				(width 0.15)
				(type solid)
			)
			(layer "B.Fab")
		)
		(fp_line
			(start 0.8 -0.424)
			(end 0.8 0.425)
			(stroke
				(width 0.15)
				(type solid)
			)
			(layer "B.Fab")
		)
		(fp_circle
			(center -0.9652 -0.9652)
			(end -0.9144 -0.9652)
			(stroke
				(width 0.15)
				(type solid)
			)
			(fill no)
			(layer "B.Fab")
		)
		(pad "1" smd rect
			(at -0.5 -0.65)
			(size 0.4 0.51)
			(layers "B.Cu" "B.Mask" "B.Paste")
			(net 10 "/Power/OUT_1V8")
			(pinfunction "G")
			(pintype "input")
		)
		(pad "2" smd rect
			(at 0.498 -0.65)
			(size 0.4 0.51)
			(layers "B.Cu" "B.Mask" "B.Paste")
			(net 1 "GND")
			(pinfunction "S")
			(pintype "passive")
		)
		(pad "3" smd rect
			(at 0 0.652)
			(size 0.4 0.51)
			(layers "B.Cu" "B.Mask" "B.Paste")
			(net 145 "Net-(D20-C)")
			(pinfunction "D")
			(pintype "passive")
		)
	)
	(footprint "antmicro-footprints:TP_SMD_0.75mm"
		(layer "B.Cu")
		(at 142.748 97.78 180)
		(property "Reference" "TP26"
			(at 0 0.6 0)
			(layer "B.SilkS")
			(hide yes)
			(effects
				(font
					(size 0.7 0.7)
					(thickness 0.15)
				)
				(justify left bottom mirror)
			)
		)
		(property "Value" "TP_0.75mm_SMD"
			(at 0 -1.2 0)
			(layer "B.Fab")
			(effects
				(font
					(size 0.7 0.7)
					(thickness 0.15)
				)
				(justify left bottom mirror)
			)
		)
		(property "Description" "SMT test point"
			(at 0 0 0)
			(layer "B.Fab")
			(hide yes)
			(effects
				(font
					(size 1.27 1.27)
					(thickness 0.15)
				)
				(justify mirror)
			)
		)
		(property "MPN" ""
			(at 0 0 0)
			(unlocked yes)
			(layer "B.Fab")
			(hide yes)
			(effects
				(font
					(size 1 1)
					(thickness 0.15)
				)
				(justify mirror)
			)
		)
		(property "Manufacturer" ""
			(at 0 0 0)
			(unlocked yes)
			(layer "B.Fab")
			(hide yes)
			(effects
				(font
					(size 1 1)
					(thickness 0.15)
				)
				(justify mirror)
			)
		)
		(property "Author" "Antmicro"
			(at 0 0 0)
			(unlocked yes)
			(layer "B.Fab")
			(hide yes)
			(effects
				(font
					(size 1 1)
					(thickness 0.15)
				)
				(justify mirror)
			)
		)
		(property "License" "Apache-2.0"
			(at 0 0 0)
			(unlocked yes)
			(layer "B.Fab")
			(hide yes)
			(effects
				(font
					(size 1 1)
					(thickness 0.15)
				)
				(justify mirror)
			)
		)
		(sheetname "/Power/")
		(sheetfile "power.kicad_sch")
		(attr exclude_from_pos_files)
		(fp_circle
			(center 0 0)
			(end 0.475 0)
			(stroke
				(width 0.05)
				(type default)
			)
			(fill no)
			(layer "B.CrtYd")
		)
		(fp_text user "${REFERENCE}"
			(at -0.4 -2.7 0)
			(layer "B.Fab")
			(effects
				(font
					(size 0.7 0.7)
					(thickness 0.15)
				)
				(justify left bottom mirror)
			)
		)
		(fp_text user "License: Apache-2.0"
			(at -0.4 -5.101 0)
			(layer "B.Fab")
			(effects
				(font
					(size 0.7 0.7)
					(thickness 0.15)
				)
				(justify left bottom mirror)
			)
		)
		(fp_text user "Author: Antmicro"
			(at -0.4 -3.901 0)
			(layer "B.Fab")
			(effects
				(font
					(size 0.7 0.7)
					(thickness 0.15)
				)
				(justify left bottom mirror)
			)
		)
		(pad "1" smd circle
			(at 0 0 180)
			(size 0.75 0.75)
			(layers "B.Cu" "B.Mask")
			(net 1 "GND")
			(pinfunction "1")
			(pintype "passive")
		)
	)
	(footprint "antmicro-footprints:R_0402_1005Metric"
		(layer "B.Cu")
		(at 156.972494 96.375897 90)
		(descr "Resistor SMD 0402")
		(tags "resistor SMD 0402")
		(property "Reference" "R70"
			(at 5.74043 0.41018 90)
			(layer "B.SilkS")
			(effects
				(font
					(size 0.7 0.7)
					(thickness 0.15)
				)
				(justify right bottom mirror)
			)
		)
		(property "Value" "R_200R_0402"
			(at -1.011843 -1.772046 90)
			(layer "B.Fab")
			(effects
				(font
					(size 0.7 0.7)
					(thickness 0.15)
				)
				(justify right bottom mirror)
			)
		)
		(property "Datasheet" "https://www.bourns.com/docs/product-datasheets/cr.pdf"
			(at 0 0 90)
			(layer "F.Fab")
			(hide yes)
			(effects
				(font
					(size 1.27 1.27)
					(thickness 0.15)
				)
			)
		)
		(property "Description" "SMD Chip Resistor, 200 ohm, ± 1%, 62.5 mW, 0402 [1005 Metric], Thick Film, General Purpose"
			(at 0 0 90)
			(layer "F.Fab")
			(hide yes)
			(effects
				(font
					(size 1.27 1.27)
					(thickness 0.15)
				)
			)
		)
		(property "Author" "Antmicro"
			(at 336.245363 52.201432 135)
			(layer "B.Fab")
			(hide yes)
			(effects
				(font
					(size 1 1)
					(thickness 0.15)
				)
				(justify mirror)
			)
		)
		(property "License" "Apache-2.0"
			(at 336.245363 52.201432 135)
			(layer "B.Fab")
			(hide yes)
			(effects
				(font
					(size 1 1)
					(thickness 0.15)
				)
				(justify mirror)
			)
		)
		(property "MPN" "CR0402-FX-2000GLF"
			(at 336.245363 52.201432 135)
			(layer "B.Fab")
			(hide yes)
			(effects
				(font
					(size 1 1)
					(thickness 0.15)
				)
				(justify mirror)
			)
		)
		(property "Manufacturer" "Bourns"
			(at 336.245363 52.201432 135)
			(layer "B.Fab")
			(hide yes)
			(effects
				(font
					(size 1 1)
					(thickness 0.15)
				)
				(justify mirror)
			)
		)
		(property "Public" ""
			(at 336.245363 52.201432 135)
			(layer "B.Fab")
			(hide yes)
			(effects
				(font
					(size 1 1)
					(thickness 0.15)
				)
				(justify mirror)
			)
		)
		(property "Tolerance" "1%"
			(at 336.245363 52.201432 135)
			(layer "B.Fab")
			(hide yes)
			(effects
				(font
					(size 1 1)
					(thickness 0.15)
				)
				(justify mirror)
			)
		)
		(property "Val" "200R"
			(at 336.245363 52.201432 135)
			(layer "B.Fab")
			(hide yes)
			(effects
				(font
					(size 1 1)
					(thickness 0.15)
				)
				(justify mirror)
			)
		)
		(sheetname "/Connectors/")
		(sheetfile "connectors.kicad_sch")
		(attr smd)
		(fp_poly
			(pts
				(xy -0.925 0.47) (xy 0.925 0.47) (xy 0.925 -0.47) (xy -0.925 -0.47)
			)
			(stroke
				(width 0.05)
				(type default)
			)
			(fill no)
			(layer "B.CrtYd")
		)
		(fp_poly
			(pts
				(xy -0.5 0.25) (xy 0.5 0.25) (xy 0.5 -0.25) (xy -0.5 -0.25)
			)
			(stroke
				(width 0.15)
				(type solid)
			)
			(fill no)
			(layer "B.Fab")
		)
		(pad "1" smd roundrect
			(at -0.48 0 90)
			(size 0.59 0.64)
			(layers "B.Cu" "B.Mask" "B.Paste")
			(roundrect_rratio 0.25)
			(net 1 "GND")
			(pintype "passive")
		)
		(pad "2" smd roundrect
			(at 0.48 0 90)
			(size 0.59 0.64)
			(layers "B.Cu" "B.Mask" "B.Paste")
			(roundrect_rratio 0.25)
			(net 65 "Net-(D12-C)")
			(pintype "passive")
		)
	)
	(footprint "antmicro-footprints:R_0402_1005Metric"
		(layer "B.Cu")
		(at 133.791 86.318 180)
		(descr "Resistor SMD 0402")
		(tags "resistor SMD 0402")
		(property "Reference" "R57"
			(at -1.083109 0.379967 0)
			(layer "B.SilkS")
			(effects
				(font
					(size 0.7 0.7)
					(thickness 0.15)
				)
				(justify left bottom mirror)
			)
		)
		(property "Value" "R_0R_0402"
			(at -1.011843 -1.772047 0)
			(layer "B.Fab")
			(effects
				(font
					(size 0.7 0.7)
					(thickness 0.15)
				)
				(justify left bottom mirror)
			)
		)
		(property "Datasheet" "https://industrial.panasonic.com/cdbs/www-data/pdf/RDA0000/AOA0000C301.pdf"
			(at 0 0 180)
			(layer "F.Fab")
			(hide yes)
			(effects
				(font
					(size 1.27 1.27)
					(thickness 0.15)
				)
			)
		)
		(property "Description" "SMD Chip Resistor, Jumper, 0 ohm, 100 mW, 0402 [1005 Metric], Thick Film, General Purpose"
			(at 0 0 180)
			(layer "F.Fab")
			(hide yes)
			(effects
				(font
					(size 1.27 1.27)
					(thickness 0.15)
				)
			)
		)
		(property "Author" "Antmicro"
			(at 267.582 172.636 0)
			(layer "B.Fab")
			(hide yes)
			(effects
				(font
					(size 1 1)
					(thickness 0.15)
				)
				(justify mirror)
			)
		)
		(property "Current" "1A"
			(at 267.582 172.636 0)
			(layer "B.Fab")
			(hide yes)
			(effects
				(font
					(size 1 1)
					(thickness 0.15)
				)
				(justify mirror)
			)
		)
		(property "License" "Apache-2.0"
			(at 267.582 172.636 0)
			(layer "B.Fab")
			(hide yes)
			(effects
				(font
					(size 1 1)
					(thickness 0.15)
				)
				(justify mirror)
			)
		)
		(property "MPN" "ERJ2GE0R00X"
			(at 267.582 172.636 0)
			(layer "B.Fab")
			(hide yes)
			(effects
				(font
					(size 1 1)
					(thickness 0.15)
				)
				(justify mirror)
			)
		)
		(property "Manufacturer" "Panasonic"
			(at 267.582 172.636 0)
			(layer "B.Fab")
			(hide yes)
			(effects
				(font
					(size 1 1)
					(thickness 0.15)
				)
				(justify mirror)
			)
		)
		(property "Tolerance" ""
			(at 267.582 172.636 0)
			(layer "B.Fab")
			(hide yes)
			(effects
				(font
					(size 1 1)
					(thickness 0.15)
				)
				(justify mirror)
			)
		)
		(property "Val" "0R"
			(at 267.582 172.636 0)
			(layer "B.Fab")
			(hide yes)
			(effects
				(font
					(size 1 1)
					(thickness 0.15)
				)
				(justify mirror)
			)
		)
		(sheetname "/Deserializer/")
		(sheetfile "deserializer.kicad_sch")
		(attr smd)
		(fp_rect
			(start -0.925 0.47)
			(end 0.925 -0.47)
			(stroke
				(width 0.05)
				(type default)
			)
			(fill no)
			(layer "B.CrtYd")
		)
		(fp_rect
			(start -0.5 0.25)
			(end 0.5 -0.25)
			(stroke
				(width 0.15)
				(type solid)
			)
			(fill no)
			(layer "B.Fab")
		)
		(pad "1" smd roundrect
			(at -0.48 0 180)
			(size 0.59 0.64)
			(layers "B.Cu" "B.Mask" "B.Paste")
			(roundrect_rratio 0.25)
			(net 29 "/Deserializer/VTERM")
			(pintype "passive")
		)
		(pad "2" smd roundrect
			(at 0.48 0 180)
			(size 0.59 0.64)
			(layers "B.Cu" "B.Mask" "B.Paste")
			(roundrect_rratio 0.25)
			(net 73 "+1V2")
			(pintype "passive")
		)
	)
	(footprint "antmicro-footprints:C_0402_1005Metric"
		(layer "B.Cu")
		(at 152.146 84.074 135)
		(descr "Capacitor SMD 0402")
		(tags "capacitor SMD 0402")
		(property "Reference" "C40"
			(at -1.00197 -1.314713 315)
			(unlocked yes)
			(layer "B.SilkS")
			(effects
				(font
					(size 0.7 0.7)
					(thickness 0.15)
				)
				(justify right bottom mirror)
			)
		)
		(property "Value" "C_100n_0402"
			(at -1.022927 -2.155213 135)
			(layer "B.Fab")
			(effects
				(font
					(size 0.7 0.7)
					(thickness 0.15)
				)
				(justify right bottom mirror)
			)
		)
		(property "Datasheet" "https://www.murata.com/products/productdetail?partno=GRM155R61H104KE14%23"
			(at 0 0 135)
			(layer "F.Fab")
			(hide yes)
			(effects
				(font
					(size 1.27 1.27)
					(thickness 0.15)
				)
			)
		)
		(property "Description" "SMD Multilayer Ceramic Capacitor, 0.1 µF, 50 V, 0402 [1005 Metric], ± 10%, X5R, GRM Series"
			(at 0 0 135)
			(layer "F.Fab")
			(hide yes)
			(effects
				(font
					(size 1.27 1.27)
					(thickness 0.15)
				)
			)
		)
		(property "Author" "Antmicro"
			(at 319.178764 35.939827 0)
			(layer "B.Fab")
			(hide yes)
			(effects
				(font
					(size 1 1)
					(thickness 0.15)
				)
				(justify mirror)
			)
		)
		(property "Dielectric" "X5R"
			(at 319.178764 35.939827 0)
			(layer "B.Fab")
			(hide yes)
			(effects
				(font
					(size 1 1)
					(thickness 0.15)
				)
				(justify mirror)
			)
		)
		(property "License" "Apache-2.0"
			(at 319.178764 35.939827 0)
			(layer "B.Fab")
			(hide yes)
			(effects
				(font
					(size 1 1)
					(thickness 0.15)
				)
				(justify mirror)
			)
		)
		(property "MPN" "GRM155R61H104KE14D"
			(at 319.178764 35.939827 0)
			(layer "B.Fab")
			(hide yes)
			(effects
				(font
					(size 1 1)
					(thickness 0.15)
				)
				(justify mirror)
			)
		)
		(property "Manufacturer" "Murata"
			(at 319.178764 35.939827 0)
			(layer "B.Fab")
			(hide yes)
			(effects
				(font
					(size 1 1)
					(thickness 0.15)
				)
				(justify mirror)
			)
		)
		(property "Val" "100n"
			(at 319.178764 35.939827 0)
			(layer "B.Fab")
			(hide yes)
			(effects
				(font
					(size 1 1)
					(thickness 0.15)
				)
				(justify mirror)
			)
		)
		(property "Voltage" "50V"
			(at 319.178764 35.939827 0)
			(layer "B.Fab")
			(hide yes)
			(effects
				(font
					(size 1 1)
					(thickness 0.15)
				)
				(justify mirror)
			)
		)
		(sheetname "/Deserializer/")
		(sheetfile "deserializer.kicad_sch")
		(attr smd)
		(fp_poly
			(pts
				(xy -0.925 0.47) (xy 0.925 0.47) (xy 0.925 -0.47) (xy -0.925 -0.47)
			)
			(stroke
				(width 0.05)
				(type default)
			)
			(fill no)
			(layer "B.CrtYd")
		)
		(fp_line
			(start 0.504 -0.248)
			(end 0.504 0.25)
			(stroke
				(width 0.15)
				(type solid)
			)
			(layer "B.Fab")
		)
		(fp_line
			(start 0.504 0.25)
			(end -0.494 0.25)
			(stroke
				(width 0.15)
				(type solid)
			)
			(layer "B.Fab")
		)
		(fp_line
			(start -0.494 -0.248)
			(end 0.504 -0.248)
			(stroke
				(width 0.15)
				(type solid)
			)
			(layer "B.Fab")
		)
		(fp_line
			(start -0.494 0.25)
			(end -0.494 -0.248)
			(stroke
				(width 0.15)
				(type solid)
			)
			(layer "B.Fab")
		)
		(pad "1" smd roundrect
			(at -0.48 0 135)
			(size 0.59 0.64)
			(layers "B.Cu" "B.Mask" "B.Paste")
			(roundrect_rratio 0.25)
			(net 1 "GND")
			(pintype "passive")
		)
		(pad "2" smd roundrect
			(at 0.48 0 135)
			(size 0.59 0.64)
			(layers "B.Cu" "B.Mask" "B.Paste")
			(roundrect_rratio 0.25)
			(net 27 "/Deserializer/VDD")
			(pintype "passive")
		)
	)
	(footprint "antmicro-footprints:TP_SMD_0.75mm"
		(layer "B.Cu")
		(at 152.4 97.89 180)
		(property "Reference" "TP22"
			(at 0 0.6 0)
			(layer "B.SilkS")
			(hide yes)
			(effects
				(font
					(size 0.7 0.7)
					(thickness 0.15)
				)
				(justify left bottom mirror)
			)
		)
		(property "Value" "TP_0.75mm_SMD"
			(at 0 -1.2 0)
			(layer "B.Fab")
			(effects
				(font
					(size 0.7 0.7)
					(thickness 0.15)
				)
				(justify left bottom mirror)
			)
		)
		(property "Description" "SMT test point"
			(at 0 0 0)
			(layer "B.Fab")
			(hide yes)
			(effects
				(font
					(size 1.27 1.27)
					(thickness 0.15)
				)
				(justify mirror)
			)
		)
		(property "MPN" ""
			(at 0 0 0)
			(unlocked yes)
			(layer "B.Fab")
			(hide yes)
			(effects
				(font
					(size 1 1)
					(thickness 0.15)
				)
				(justify mirror)
			)
		)
		(property "Manufacturer" ""
			(at 0 0 0)
			(unlocked yes)
			(layer "B.Fab")
			(hide yes)
			(effects
				(font
					(size 1 1)
					(thickness 0.15)
				)
				(justify mirror)
			)
		)
		(property "Author" "Antmicro"
			(at 0 0 0)
			(unlocked yes)
			(layer "B.Fab")
			(hide yes)
			(effects
				(font
					(size 1 1)
					(thickness 0.15)
				)
				(justify mirror)
			)
		)
		(property "License" "Apache-2.0"
			(at 0 0 0)
			(unlocked yes)
			(layer "B.Fab")
			(hide yes)
			(effects
				(font
					(size 1 1)
					(thickness 0.15)
				)
				(justify mirror)
			)
		)
		(sheetname "/Connectors/")
		(sheetfile "connectors.kicad_sch")
		(attr exclude_from_pos_files)
		(fp_circle
			(center 0 0)
			(end 0.475 0)
			(stroke
				(width 0.05)
				(type default)
			)
			(fill no)
			(layer "B.CrtYd")
		)
		(fp_text user "License: Apache-2.0"
			(at -0.4 -5.101 0)
			(layer "B.Fab")
			(effects
				(font
					(size 0.7 0.7)
					(thickness 0.15)
				)
				(justify left bottom mirror)
			)
		)
		(fp_text user "Author: Antmicro"
			(at -0.4 -3.901 0)
			(layer "B.Fab")
			(effects
				(font
					(size 0.7 0.7)
					(thickness 0.15)
				)
				(justify left bottom mirror)
			)
		)
		(fp_text user "${REFERENCE}"
			(at -0.4 -2.7 0)
			(layer "B.Fab")
			(effects
				(font
					(size 0.7 0.7)
					(thickness 0.15)
				)
				(justify left bottom mirror)
			)
		)
		(pad "1" smd circle
			(at 0 0 180)
			(size 0.75 0.75)
			(layers "B.Cu" "B.Mask")
			(net 2 "/Connectors/DC_UNFUSED")
			(pinfunction "1")
			(pintype "passive")
		)
	)
	(footprint "antmicro-footprints:TP_SMD_0.75mm"
		(layer "B.Cu")
		(at 132.2 84.8 180)
		(property "Reference" "TP28"
			(at 0 0.6 0)
			(layer "B.SilkS")
			(hide yes)
			(effects
				(font
					(size 0.7 0.7)
					(thickness 0.15)
				)
				(justify left bottom mirror)
			)
		)
		(property "Value" "TP_0.75mm_SMD"
			(at 0 -1.2 0)
			(layer "B.Fab")
			(effects
				(font
					(size 0.7 0.7)
					(thickness 0.15)
				)
				(justify left bottom mirror)
			)
		)
		(property "Description" "SMT test point"
			(at 0 0 0)
			(layer "B.Fab")
			(hide yes)
			(effects
				(font
					(size 1.27 1.27)
					(thickness 0.15)
				)
				(justify mirror)
			)
		)
		(property "MPN" ""
			(at 0 0 0)
			(unlocked yes)
			(layer "B.Fab")
			(hide yes)
			(effects
				(font
					(size 1 1)
					(thickness 0.15)
				)
				(justify mirror)
			)
		)
		(property "Manufacturer" ""
			(at 0 0 0)
			(unlocked yes)
			(layer "B.Fab")
			(hide yes)
			(effects
				(font
					(size 1 1)
					(thickness 0.15)
				)
				(justify mirror)
			)
		)
		(property "Author" "Antmicro"
			(at 0 0 0)
			(unlocked yes)
			(layer "B.Fab")
			(hide yes)
			(effects
				(font
					(size 1 1)
					(thickness 0.15)
				)
				(justify mirror)
			)
		)
		(property "License" "Apache-2.0"
			(at 0 0 0)
			(unlocked yes)
			(layer "B.Fab")
			(hide yes)
			(effects
				(font
					(size 1 1)
					(thickness 0.15)
				)
				(justify mirror)
			)
		)
		(sheetname "/Power/")
		(sheetfile "power.kicad_sch")
		(attr exclude_from_pos_files)
		(fp_circle
			(center 0 0)
			(end 0.475 0)
			(stroke
				(width 0.05)
				(type default)
			)
			(fill no)
			(layer "B.CrtYd")
		)
		(fp_text user "${REFERENCE}"
			(at -0.4 -2.7 0)
			(layer "B.Fab")
			(effects
				(font
					(size 0.7 0.7)
					(thickness 0.15)
				)
				(justify left bottom mirror)
			)
		)
		(fp_text user "Author: Antmicro"
			(at -0.4 -3.901 0)
			(layer "B.Fab")
			(effects
				(font
					(size 0.7 0.7)
					(thickness 0.15)
				)
				(justify left bottom mirror)
			)
		)
		(fp_text user "License: Apache-2.0"
			(at -0.4 -5.101 0)
			(layer "B.Fab")
			(effects
				(font
					(size 0.7 0.7)
					(thickness 0.15)
				)
				(justify left bottom mirror)
			)
		)
		(pad "1" smd circle
			(at 0 0 180)
			(size 0.75 0.75)
			(layers "B.Cu" "B.Mask")
			(net 3 "+1V8")
			(pinfunction "1")
			(pintype "passive")
		)
	)
	(footprint "antmicro-footprints:Spacer_Drill3.7mm_H6mm_9774060151R"
		(layer "B.Cu")
		(at 120.498 44.164 180)
		(descr "Spacer M=3 h=36mm fi=5.1mm")
		(property "Reference" "H3"
			(at 0 3.2 0)
			(layer "B.SilkS")
			(effects
				(font
					(size 0.7 0.7)
					(thickness 0.15)
				)
				(justify left bottom mirror)
			)
		)
		(property "Value" "Spacer_Drill3.7mm_H6mm_9774060151R"
			(at 0 -4 0)
			(layer "B.Fab")
			(effects
				(font
					(size 0.7 0.7)
					(thickness 0.15)
				)
				(justify left bottom mirror)
			)
		)
		(property "Datasheet" "https://www.we-online.com/components/products/datasheet/9774060151R.pdf"
			(at 0 0 180)
			(layer "F.Fab")
			(hide yes)
			(effects
				(font
					(size 1.27 1.27)
					(thickness 0.15)
				)
			)
		)
		(property "Description" "Spacer, SMT, Non Stop, Steel, Swage Round, 5.1 mm x 6 mm, M2.5 Thread, WA-SMSI Series"
			(at 0 0 180)
			(layer "F.Fab")
			(hide yes)
			(effects
				(font
					(size 1.27 1.27)
					(thickness 0.15)
				)
			)
		)
		(property "Author" "Antmicro"
			(at 240.996 88.328 0)
			(layer "B.Fab")
			(hide yes)
			(effects
				(font
					(size 1 1)
					(thickness 0.15)
				)
				(justify mirror)
			)
		)
		(property "License" "Apache-2.0"
			(at 240.996 88.328 0)
			(layer "B.Fab")
			(hide yes)
			(effects
				(font
					(size 1 1)
					(thickness 0.15)
				)
				(justify mirror)
			)
		)
		(property "MPN" "9774060151R"
			(at 240.996 88.328 0)
			(layer "B.Fab")
			(hide yes)
			(effects
				(font
					(size 1 1)
					(thickness 0.15)
				)
				(justify mirror)
			)
		)
		(property "Manufacturer" "Würth Elektronik"
			(at 240.996 88.328 0)
			(layer "B.Fab")
			(hide yes)
			(effects
				(font
					(size 1 1)
					(thickness 0.15)
				)
				(justify mirror)
			)
		)
		(sheetname "/")
		(sheetfile "gmsl-deserializer.kicad_sch")
		(solder_paste_margin_ratio -1)
		(attr smd)
		(fp_circle
			(center 0 0)
			(end 3.05 0)
			(stroke
				(width 0.05)
				(type solid)
			)
			(fill no)
			(layer "B.CrtYd")
		)
		(fp_circle
			(center 0 0)
			(end 2.6 0)
			(stroke
				(width 0.15)
				(type solid)
			)
			(fill no)
			(layer "B.Fab")
		)
		(pad "" smd custom
			(at -1.7 -1.7 90)
			(size 0.62 0.62)
			(layers "B.Paste")
			(thermal_bridge_angle 90)
			(options
				(clearance outline)
				(anchor circle)
			)
			(primitives
				(gr_arc
					(start 1.266786 0.24747)
					(mid 0.285453 -0.29439)
					(end -0.250195 -1.279127)
					(width 0.2)
				)
				(gr_arc
					(start 1.259603 0.339191)
					(mid 0.218448 -0.232561)
					(end -0.34334 -1.279127)
					(width 0.2)
				)
				(gr_arc
					(start 1.255279 0.431435)
					(mid 0.152481 -0.169693)
					(end -0.436309 -1.279127)
					(width 0.2)
				)
				(gr_arc
					(start 1.253811 0.524161)
					(mid 0.087542 -0.105784)
					(end -0.529126 -1.279127)
					(width 0.2)
				)
				(gr_arc
					(start 1.275473 0.621136)
					(mid 0.0309 -0.033527)
					(end -0.621807 -1.279127)
					(width 0.2)
				)
				(gr_arc
					(start 1.263664 0.711602)
					(mid -0.037759 0.026651)
					(end -0.71437 -1.279127)
					(width 0.2)
				)
				(gr_arc
					(start 1.253435 0.802342)
					(mid -0.105837 0.087395)
					(end -0.806826 -1.279127)
					(width 0.2)
				)
				(gr_arc
					(start 1.267475 0.897258)
					(mid -0.165236 0.156885)
					(end -0.899187 -1.279127)
					(width 0.2)
				)
				(gr_arc
					(start 1.270645 0.990112)
					(mid -0.228522 0.222449)
					(end -0.991463 -1.279127)
					(width 0.2)
				)
				(gr_arc
					(start 1.266278 1.081674)
					(mid -0.294507 0.285313)
					(end -1.083663 -1.279127)
					(width 0.2)
				)
				(gr_line
					(start 1.279127 0.250195)
					(end 1.279127 1.083663)
					(width 0.2)
				)
				(gr_line
					(start -0.250195 -1.279127)
					(end -1.083663 -1.279127)
					(width 0.2)
				)
			)
		)
		(pad "" smd custom
			(at -1.7 1.7 180)
			(size 0.62 0.62)
			(layers "B.Paste")
			(thermal_bridge_angle 90)
			(options
				(clearance outline)
				(anchor circle)
			)
			(primitives
				(gr_arc
					(start 1.266786 0.24747)
					(mid 0.285453 -0.29439)
					(end -0.250195 -1.279127)
					(width 0.2)
				)
				(gr_arc
					(start 1.259603 0.339191)
					(mid 0.218448 -0.232561)
					(end -0.34334 -1.279127)
					(width 0.2)
				)
				(gr_arc
					(start 1.255279 0.431435)
					(mid 0.152481 -0.169693)
					(end -0.436309 -1.279127)
					(width 0.2)
				)
				(gr_arc
					(start 1.253811 0.524161)
					(mid 0.087542 -0.105784)
					(end -0.529126 -1.279127)
					(width 0.2)
				)
				(gr_arc
					(start 1.275473 0.621136)
					(mid 0.0309 -0.033527)
					(end -0.621807 -1.279127)
					(width 0.2)
				)
				(gr_arc
					(start 1.263664 0.711602)
					(mid -0.037759 0.026651)
					(end -0.71437 -1.279127)
					(width 0.2)
				)
				(gr_arc
					(start 1.253435 0.802342)
					(mid -0.105837 0.087395)
					(end -0.806826 -1.279127)
					(width 0.2)
				)
				(gr_arc
					(start 1.267475 0.897258)
					(mid -0.165236 0.156885)
					(end -0.899187 -1.279127)
					(width 0.2)
				)
				(gr_arc
					(start 1.270645 0.990112)
					(mid -0.228522 0.222449)
					(end -0.991463 -1.279127)
					(width 0.2)
				)
				(gr_arc
					(start 1.266278 1.081674)
					(mid -0.294507 0.285313)
					(end -1.083663 -1.279127)
					(width 0.2)
				)
				(gr_line
					(start 1.279127 0.250195)
					(end 1.279127 1.083663)
					(width 0.2)
				)
				(gr_line
					(start -0.250195 -1.279127)
					(end -1.083663 -1.279127)
					(width 0.2)
				)
			)
		)
		(pad "" smd custom
			(at 1.7 -1.7)
			(size 0.62 0.62)
			(layers "B.Paste")
			(thermal_bridge_angle 90)
			(options
				(clearance outline)
				(anchor circle)
			)
			(primitives
				(gr_arc
					(start 1.266786 0.24747)
					(mid 0.285453 -0.29439)
					(end -0.250195 -1.279127)
					(width 0.2)
				)
				(gr_arc
					(start 1.259603 0.339191)
					(mid 0.218448 -0.232561)
					(end -0.34334 -1.279127)
					(width 0.2)
				)
				(gr_arc
					(start 1.255279 0.431435)
					(mid 0.152481 -0.169693)
					(end -0.436309 -1.279127)
					(width 0.2)
				)
				(gr_arc
					(start 1.253811 0.524161)
					(mid 0.087542 -0.105784)
					(end -0.529126 -1.279127)
					(width 0.2)
				)
				(gr_arc
					(start 1.275473 0.621136)
					(mid 0.0309 -0.033527)
					(end -0.621807 -1.279127)
					(width 0.2)
				)
				(gr_arc
					(start 1.263664 0.711602)
					(mid -0.037759 0.026651)
					(end -0.71437 -1.279127)
					(width 0.2)
				)
				(gr_arc
					(start 1.253435 0.802342)
					(mid -0.105837 0.087395)
					(end -0.806826 -1.279127)
					(width 0.2)
				)
				(gr_arc
					(start 1.267475 0.897258)
					(mid -0.165236 0.156885)
					(end -0.899187 -1.279127)
					(width 0.2)
				)
				(gr_arc
					(start 1.270645 0.990112)
					(mid -0.228522 0.222449)
					(end -0.991463 -1.279127)
					(width 0.2)
				)
				(gr_arc
					(start 1.266278 1.081674)
					(mid -0.294507 0.285313)
					(end -1.083663 -1.279127)
					(width 0.2)
				)
				(gr_line
					(start 1.279127 0.250195)
					(end 1.279127 1.083663)
					(width 0.2)
				)
				(gr_line
					(start -0.250195 -1.279127)
					(end -1.083663 -1.279127)
					(width 0.2)
				)
			)
		)
		(pad "" smd custom
			(at 1.7 1.7 270)
			(size 0.62 0.62)
			(layers "B.Paste")
			(thermal_bridge_angle 90)
			(options
				(clearance outline)
				(anchor circle)
			)
			(primitives
				(gr_arc
					(start 1.266786 0.24747)
					(mid 0.285453 -0.29439)
					(end -0.250195 -1.279127)
					(width 0.2)
				)
				(gr_arc
					(start 1.259603 0.339191)
					(mid 0.218448 -0.232561)
					(end -0.34334 -1.279127)
					(width 0.2)
				)
				(gr_arc
					(start 1.255279 0.431435)
					(mid 0.152481 -0.169693)
					(end -0.436309 -1.279127)
					(width 0.2)
				)
				(gr_arc
					(start 1.253811 0.524161)
					(mid 0.087542 -0.105784)
					(end -0.529126 -1.279127)
					(width 0.2)
				)
				(gr_arc
					(start 1.275473 0.621136)
					(mid 0.0309 -0.033527)
					(end -0.621807 -1.279127)
					(width 0.2)
				)
				(gr_arc
					(start 1.263664 0.711602)
					(mid -0.037759 0.026651)
					(end -0.71437 -1.279127)
					(width 0.2)
				)
				(gr_arc
					(start 1.253435 0.802342)
					(mid -0.105837 0.087395)
					(end -0.806826 -1.279127)
					(width 0.2)
				)
				(gr_arc
					(start 1.267475 0.897258)
					(mid -0.165236 0.156885)
					(end -0.899187 -1.279127)
					(width 0.2)
				)
				(gr_arc
					(start 1.270645 0.990112)
					(mid -0.228522 0.222449)
					(end -0.991463 -1.279127)
					(width 0.2)
				)
				(gr_arc
					(start 1.266278 1.081674)
					(mid -0.294507 0.285313)
					(end -1.083663 -1.279127)
					(width 0.2)
				)
				(gr_line
					(start 1.279127 0.250195)
					(end 1.279127 1.083663)
					(width 0.2)
				)
				(gr_line
					(start -0.250195 -1.279127)
					(end -1.083663 -1.279127)
					(width 0.2)
				)
			)
		)
		(pad "1" thru_hole circle
			(at 0 0 180)
			(size 6 6)
			(drill 3.7)
			(layers "*.Cu" "*.Mask")
			(remove_unused_layers no)
			(net 1 "GND")
			(pintype "passive")
		)
	)
	(footprint "antmicro-footprints:R_0402_1005Metric"
		(layer "B.Cu")
		(at 133.858 83.82 180)
		(descr "Resistor SMD 0402")
		(tags "resistor SMD 0402")
		(property "Reference" "R56"
			(at -1.016109 -1.229033 0)
			(layer "B.SilkS")
			(effects
				(font
					(size 0.7 0.7)
					(thickness 0.15)
				)
				(justify left bottom mirror)
			)
		)
		(property "Value" "R_0R_0402"
			(at -1.011843 -1.772047 0)
			(layer "B.Fab")
			(effects
				(font
					(size 0.7 0.7)
					(thickness 0.15)
				)
				(justify left bottom mirror)
			)
		)
		(property "Datasheet" "https://industrial.panasonic.com/cdbs/www-data/pdf/RDA0000/AOA0000C301.pdf"
			(at 0 0 180)
			(layer "F.Fab")
			(hide yes)
			(effects
				(font
					(size 1.27 1.27)
					(thickness 0.15)
				)
			)
		)
		(property "Description" "SMD Chip Resistor, Jumper, 0 ohm, 100 mW, 0402 [1005 Metric], Thick Film, General Purpose"
			(at 0 0 180)
			(layer "F.Fab")
			(hide yes)
			(effects
				(font
					(size 1.27 1.27)
					(thickness 0.15)
				)
			)
		)
		(property "Author" "Antmicro"
			(at 267.716 167.64 0)
			(layer "B.Fab")
			(hide yes)
			(effects
				(font
					(size 1 1)
					(thickness 0.15)
				)
				(justify mirror)
			)
		)
		(property "Current" "1A"
			(at 267.716 167.64 0)
			(layer "B.Fab")
			(hide yes)
			(effects
				(font
					(size 1 1)
					(thickness 0.15)
				)
				(justify mirror)
			)
		)
		(property "License" "Apache-2.0"
			(at 267.716 167.64 0)
			(layer "B.Fab")
			(hide yes)
			(effects
				(font
					(size 1 1)
					(thickness 0.15)
				)
				(justify mirror)
			)
		)
		(property "MPN" "ERJ2GE0R00X"
			(at 267.716 167.64 0)
			(layer "B.Fab")
			(hide yes)
			(effects
				(font
					(size 1 1)
					(thickness 0.15)
				)
				(justify mirror)
			)
		)
		(property "Manufacturer" "Panasonic"
			(at 267.716 167.64 0)
			(layer "B.Fab")
			(hide yes)
			(effects
				(font
					(size 1 1)
					(thickness 0.15)
				)
				(justify mirror)
			)
		)
		(property "Tolerance" ""
			(at 267.716 167.64 0)
			(layer "B.Fab")
			(hide yes)
			(effects
				(font
					(size 1 1)
					(thickness 0.15)
				)
				(justify mirror)
			)
		)
		(property "Val" "0R"
			(at 267.716 167.64 0)
			(layer "B.Fab")
			(hide yes)
			(effects
				(font
					(size 1 1)
					(thickness 0.15)
				)
				(justify mirror)
			)
		)
		(sheetname "/Deserializer/")
		(sheetfile "deserializer.kicad_sch")
		(attr smd)
		(fp_rect
			(start -0.925 0.47)
			(end 0.925 -0.47)
			(stroke
				(width 0.05)
				(type default)
			)
			(fill no)
			(layer "B.CrtYd")
		)
		(fp_rect
			(start -0.5 0.25)
			(end 0.5 -0.25)
			(stroke
				(width 0.15)
				(type solid)
			)
			(fill no)
			(layer "B.Fab")
		)
		(pad "1" smd roundrect
			(at -0.48 0 180)
			(size 0.59 0.64)
			(layers "B.Cu" "B.Mask" "B.Paste")
			(roundrect_rratio 0.25)
			(net 146 "VDDIO")
			(pintype "passive")
		)
		(pad "2" smd roundrect
			(at 0.48 0 180)
			(size 0.59 0.64)
			(layers "B.Cu" "B.Mask" "B.Paste")
			(roundrect_rratio 0.25)
			(net 3 "+1V8")
			(pintype "passive")
		)
	)
	(footprint "antmicro-footprints:C_0402_1005Metric"
		(layer "B.Cu")
		(at 154.432 81.788 135)
		(descr "Capacitor SMD 0402")
		(tags "capacitor SMD 0402")
		(property "Reference" "C49"
			(at -1.271378 0.052326 315)
			(unlocked yes)
			(layer "B.SilkS")
			(effects
				(font
					(size 0.7 0.7)
					(thickness 0.15)
				)
				(justify right bottom mirror)
			)
		)
		(property "Value" "C_10n_0402"
			(at -1.022927 -2.155213 135)
			(layer "B.Fab")
			(effects
				(font
					(size 0.7 0.7)
					(thickness 0.15)
				)
				(justify right bottom mirror)
			)
		)
		(property "Datasheet" "https://www.murata.com/products/productdetail?partno=GRM155R71H103KA88%23"
			(at 0 0 135)
			(layer "F.Fab")
			(hide yes)
			(effects
				(font
					(size 1.27 1.27)
					(thickness 0.15)
				)
			)
		)
		(property "Description" "SMD Multilayer Ceramic Capacitor, 10000 pF, 50 V, 0402 [1005 Metric], ± 10%, X7R, GRM Series"
			(at 0 0 135)
			(layer "F.Fab")
			(hide yes)
			(effects
				(font
					(size 1.27 1.27)
					(thickness 0.15)
				)
			)
		)
		(property "Author" "Antmicro"
			(at 321.464764 30.420935 0)
			(layer "B.Fab")
			(hide yes)
			(effects
				(font
					(size 1 1)
					(thickness 0.15)
				)
				(justify mirror)
			)
		)
		(property "Dielectric" "X7R"
			(at 321.464764 30.420935 0)
			(layer "B.Fab")
			(hide yes)
			(effects
				(font
					(size 1 1)
					(thickness 0.15)
				)
				(justify mirror)
			)
		)
		(property "License" "Apache-2.0"
			(at 321.464764 30.420935 0)
			(layer "B.Fab")
			(hide yes)
			(effects
				(font
					(size 1 1)
					(thickness 0.15)
				)
				(justify mirror)
			)
		)
		(property "MPN" "GRM155R71H103KA88D"
			(at 321.464764 30.420935 0)
			(layer "B.Fab")
			(hide yes)
			(effects
				(font
					(size 1 1)
					(thickness 0.15)
				)
				(justify mirror)
			)
		)
		(property "Manufacturer" "Murata"
			(at 321.464764 30.420935 0)
			(layer "B.Fab")
			(hide yes)
			(effects
				(font
					(size 1 1)
					(thickness 0.15)
				)
				(justify mirror)
			)
		)
		(property "Val" "10n"
			(at 321.464764 30.420935 0)
			(layer "B.Fab")
			(hide yes)
			(effects
				(font
					(size 1 1)
					(thickness 0.15)
				)
				(justify mirror)
			)
		)
		(property "Voltage" "50V"
			(at 321.464764 30.420935 0)
			(layer "B.Fab")
			(hide yes)
			(effects
				(font
					(size 1 1)
					(thickness 0.15)
				)
				(justify mirror)
			)
		)
		(sheetname "/Deserializer/")
		(sheetfile "deserializer.kicad_sch")
		(attr smd)
		(fp_poly
			(pts
				(xy -0.925 0.47) (xy 0.925 0.47) (xy 0.925 -0.47) (xy -0.925 -0.47)
			)
			(stroke
				(width 0.05)
				(type default)
			)
			(fill no)
			(layer "B.CrtYd")
		)
		(fp_line
			(start 0.504 -0.248)
			(end 0.504 0.25)
			(stroke
				(width 0.15)
				(type solid)
			)
			(layer "B.Fab")
		)
		(fp_line
			(start 0.504 0.25)
			(end -0.494 0.25)
			(stroke
				(width 0.15)
				(type solid)
			)
			(layer "B.Fab")
		)
		(fp_line
			(start -0.494 -0.248)
			(end 0.504 -0.248)
			(stroke
				(width 0.15)
				(type solid)
			)
			(layer "B.Fab")
		)
		(fp_line
			(start -0.494 0.25)
			(end -0.494 -0.248)
			(stroke
				(width 0.15)
				(type solid)
			)
			(layer "B.Fab")
		)
		(pad "1" smd roundrect
			(at -0.48 0 135)
			(size 0.59 0.64)
			(layers "B.Cu" "B.Mask" "B.Paste")
			(roundrect_rratio 0.25)
			(net 1 "GND")
			(pintype "passive")
		)
		(pad "2" smd roundrect
			(at 0.48 0 135)
			(size 0.59 0.64)
			(layers "B.Cu" "B.Mask" "B.Paste")
			(roundrect_rratio 0.25)
			(net 27 "/Deserializer/VDD")
			(pintype "passive")
		)
	)
	(footprint "antmicro-footprints:C_0402_1005Metric"
		(layer "B.Cu")
		(at 139.7 83.058 45)
		(descr "Capacitor SMD 0402")
		(tags "capacitor SMD 0402")
		(property "Reference" "C51"
			(at -3.788853 -0.017146 45)
			(layer "B.SilkS")
			(effects
				(font
					(size 0.7 0.7)
					(thickness 0.15)
				)
				(justify right bottom mirror)
			)
		)
		(property "Value" "C_10n_0402"
			(at -1.022927 -2.155213 45)
			(layer "B.Fab")
			(effects
				(font
					(size 0.7 0.7)
					(thickness 0.15)
				)
				(justify right bottom mirror)
			)
		)
		(property "Datasheet" "https://www.murata.com/products/productdetail?partno=GRM155R71H103KA88%23"
			(at 0 0 45)
			(layer "F.Fab")
			(hide yes)
			(effects
				(font
					(size 1.27 1.27)
					(thickness 0.15)
				)
			)
		)
		(property "Description" "SMD Multilayer Ceramic Capacitor, 10000 pF, 50 V, 0402 [1005 Metric], ± 10%, X7R, GRM Series"
			(at 0 0 45)
			(layer "F.Fab")
			(hide yes)
			(effects
				(font
					(size 1.27 1.27)
					(thickness 0.15)
				)
			)
		)
		(property "Author" "Antmicro"
			(at 99.648057 -74.455692 0)
			(layer "B.Fab")
			(hide yes)
			(effects
				(font
					(size 1 1)
					(thickness 0.15)
				)
				(justify mirror)
			)
		)
		(property "Dielectric" "X7R"
			(at 99.648057 -74.455692 0)
			(layer "B.Fab")
			(hide yes)
			(effects
				(font
					(size 1 1)
					(thickness 0.15)
				)
				(justify mirror)
			)
		)
		(property "License" "Apache-2.0"
			(at 99.648057 -74.455692 0)
			(layer "B.Fab")
			(hide yes)
			(effects
				(font
					(size 1 1)
					(thickness 0.15)
				)
				(justify mirror)
			)
		)
		(property "MPN" "GRM155R71H103KA88D"
			(at 99.648057 -74.455692 0)
			(layer "B.Fab")
			(hide yes)
			(effects
				(font
					(size 1 1)
					(thickness 0.15)
				)
				(justify mirror)
			)
		)
		(property "Manufacturer" "Murata"
			(at 99.648057 -74.455692 0)
			(layer "B.Fab")
			(hide yes)
			(effects
				(font
					(size 1 1)
					(thickness 0.15)
				)
				(justify mirror)
			)
		)
		(property "Val" "10n"
			(at 99.648057 -74.455692 0)
			(layer "B.Fab")
			(hide yes)
			(effects
				(font
					(size 1 1)
					(thickness 0.15)
				)
				(justify mirror)
			)
		)
		(property "Voltage" "50V"
			(at 99.648057 -74.455692 0)
			(layer "B.Fab")
			(hide yes)
			(effects
				(font
					(size 1 1)
					(thickness 0.15)
				)
				(justify mirror)
			)
		)
		(sheetname "/Deserializer/")
		(sheetfile "deserializer.kicad_sch")
		(attr smd)
		(fp_poly
			(pts
				(xy -0.925 0.47) (xy 0.925 0.47) (xy 0.925 -0.47) (xy -0.925 -0.47)
			)
			(stroke
				(width 0.05)
				(type default)
			)
			(fill no)
			(layer "B.CrtYd")
		)
		(fp_line
			(start -0.494 -0.248)
			(end 0.504 -0.248)
			(stroke
				(width 0.15)
				(type solid)
			)
			(layer "B.Fab")
		)
		(fp_line
			(start -0.494 0.25)
			(end -0.494 -0.248)
			(stroke
				(width 0.15)
				(type solid)
			)
			(layer "B.Fab")
		)
		(fp_line
			(start 0.504 -0.248)
			(end 0.504 0.25)
			(stroke
				(width 0.15)
				(type solid)
			)
			(layer "B.Fab")
		)
		(fp_line
			(start 0.504 0.25)
			(end -0.494 0.25)
			(stroke
				(width 0.15)
				(type solid)
			)
			(layer "B.Fab")
		)
		(pad "1" smd roundrect
			(at -0.48 0 45)
			(size 0.59 0.64)
			(layers "B.Cu" "B.Mask" "B.Paste")
			(roundrect_rratio 0.25)
			(net 1 "GND")
			(pintype "passive")
		)
		(pad "2" smd roundrect
			(at 0.48 0 45)
			(size 0.59 0.64)
			(layers "B.Cu" "B.Mask" "B.Paste")
			(roundrect_rratio 0.25)
			(net 29 "/Deserializer/VTERM")
			(pintype "passive")
		)
	)
	(footprint "antmicro-footprints:C_0402_1005Metric"
		(layer "B.Cu")
		(at 143.51 76.454 -45)
		(descr "Capacitor SMD 0402")
		(tags "capacitor SMD 0402")
		(property "Reference" "C36"
			(at -1.52271 0.22729 315)
			(unlocked yes)
			(layer "B.SilkS")
			(effects
				(font
					(size 0.7 0.7)
					(thickness 0.15)
				)
				(justify left bottom mirror)
			)
		)
		(property "Value" "C_10u_0402"
			(at -1.022927 -2.155213 135)
			(layer "B.Fab")
			(effects
				(font
					(size 0.7 0.7)
					(thickness 0.15)
				)
				(justify left bottom mirror)
			)
		)
		(property "Datasheet" "https://www.yageo.com/en/Chart/Download/pdf/CC0402MRX5R5BB106"
			(at 0 0 315)
			(layer "F.Fab")
			(hide yes)
			(effects
				(font
					(size 1.27 1.27)
					(thickness 0.15)
				)
			)
		)
		(property "Description" "SMD Multilayer Ceramic Capacitor, 10 µF, 6.3 V, 0402 [1005 Metric], ± 20%, X5R, CC Series"
			(at 0 0 315)
			(layer "F.Fab")
			(hide yes)
			(effects
				(font
					(size 1.27 1.27)
					(thickness 0.15)
				)
			)
		)
		(property "Author" "Antmicro"
			(at -12.028036 123.869753 0)
			(layer "B.Fab")
			(hide yes)
			(effects
				(font
					(size 1 1)
					(thickness 0.15)
				)
				(justify mirror)
			)
		)
		(property "Dielectric" ""
			(at -12.028036 123.869753 0)
			(layer "B.Fab")
			(hide yes)
			(effects
				(font
					(size 1 1)
					(thickness 0.15)
				)
				(justify mirror)
			)
		)
		(property "License" "Apache-2.0"
			(at -12.028036 123.869753 0)
			(layer "B.Fab")
			(hide yes)
			(effects
				(font
					(size 1 1)
					(thickness 0.15)
				)
				(justify mirror)
			)
		)
		(property "MPN" "CC0402MRX5R5BB106"
			(at -12.028036 123.869753 0)
			(layer "B.Fab")
			(hide yes)
			(effects
				(font
					(size 1 1)
					(thickness 0.15)
				)
				(justify mirror)
			)
		)
		(property "Manufacturer" "YAGEO"
			(at -12.028036 123.869753 0)
			(layer "B.Fab")
			(hide yes)
			(effects
				(font
					(size 1 1)
					(thickness 0.15)
				)
				(justify mirror)
			)
		)
		(property "Val" "10u"
			(at -12.028036 123.869753 0)
			(layer "B.Fab")
			(hide yes)
			(effects
				(font
					(size 1 1)
					(thickness 0.15)
				)
				(justify mirror)
			)
		)
		(property "Voltage" ""
			(at -12.028036 123.869753 0)
			(layer "B.Fab")
			(hide yes)
			(effects
				(font
					(size 1 1)
					(thickness 0.15)
				)
				(justify mirror)
			)
		)
		(sheetname "/Deserializer/")
		(sheetfile "deserializer.kicad_sch")
		(attr smd)
		(fp_poly
			(pts
				(xy -0.925 0.47) (xy 0.925 0.47) (xy 0.925 -0.47) (xy -0.925 -0.47)
			)
			(stroke
				(width 0.05)
				(type default)
			)
			(fill no)
			(layer "B.CrtYd")
		)
		(fp_line
			(start -0.494 0.25)
			(end -0.494 -0.248)
			(stroke
				(width 0.15)
				(type solid)
			)
			(layer "B.Fab")
		)
		(fp_line
			(start -0.494 -0.248)
			(end 0.504 -0.248)
			(stroke
				(width 0.15)
				(type solid)
			)
			(layer "B.Fab")
		)
		(fp_line
			(start 0.504 0.25)
			(end -0.494 0.25)
			(stroke
				(width 0.15)
				(type solid)
			)
			(layer "B.Fab")
		)
		(fp_line
			(start 0.504 -0.248)
			(end 0.504 0.25)
			(stroke
				(width 0.15)
				(type solid)
			)
			(layer "B.Fab")
		)
		(pad "1" smd roundrect
			(at -0.48 0 315)
			(size 0.59 0.64)
			(layers "B.Cu" "B.Mask" "B.Paste")
			(roundrect_rratio 0.25)
			(net 1 "GND")
			(pintype "passive")
		)
		(pad "2" smd roundrect
			(at 0.48 0 315)
			(size 0.59 0.64)
			(layers "B.Cu" "B.Mask" "B.Paste")
			(roundrect_rratio 0.25)
			(net 26 "/Deserializer/VDD_1.8V")
			(pintype "passive")
		)
	)
	(footprint "antmicro-footprints:R_0402_1005Metric"
		(layer "B.Cu")
		(at 149.33434 96.355897 90)
		(descr "Resistor SMD 0402")
		(tags "resistor SMD 0402")
		(property "Reference" "R75"
			(at 5.726288 0.424322 90)
			(layer "B.SilkS")
			(effects
				(font
					(size 0.7 0.7)
					(thickness 0.15)
				)
				(justify right bottom mirror)
			)
		)
		(property "Value" "R_1k65_0402"
			(at -1.011843 -1.772046 90)
			(layer "B.Fab")
			(effects
				(font
					(size 0.7 0.7)
					(thickness 0.15)
				)
				(justify right bottom mirror)
			)
		)
		(property "Datasheet" "https://www.farnell.com/datasheets/3795017.pdf"
			(at 0 0 90)
			(layer "F.Fab")
			(hide yes)
			(effects
				(font
					(size 1.27 1.27)
					(thickness 0.15)
				)
			)
		)
		(property "Description" "SMD Chip Resistor, 1.65 kohm, ± 1%, 63 mW, 0402 [1005 Metric], Thick Film, General Purpose"
			(at 0 0 90)
			(layer "F.Fab")
			(hide yes)
			(effects
				(font
					(size 1.27 1.27)
					(thickness 0.15)
				)
			)
		)
		(property "Author" "Antmicro"
			(at 323.23721 57.589586 135)
			(layer "B.Fab")
			(hide yes)
			(effects
				(font
					(size 1 1)
					(thickness 0.15)
				)
				(justify mirror)
			)
		)
		(property "License" "Apache-2.0"
			(at 323.23721 57.589586 135)
			(layer "B.Fab")
			(hide yes)
			(effects
				(font
					(size 1 1)
					(thickness 0.15)
				)
				(justify mirror)
			)
		)
		(property "MPN" "RC0402FR-071K65L"
			(at 323.23721 57.589586 135)
			(layer "B.Fab")
			(hide yes)
			(effects
				(font
					(size 1 1)
					(thickness 0.15)
				)
				(justify mirror)
			)
		)
		(property "Manufacturer" "YAGEO"
			(at 323.23721 57.589586 135)
			(layer "B.Fab")
			(hide yes)
			(effects
				(font
					(size 1 1)
					(thickness 0.15)
				)
				(justify mirror)
			)
		)
		(property "Public" ""
			(at 323.23721 57.589586 135)
			(layer "B.Fab")
			(hide yes)
			(effects
				(font
					(size 1 1)
					(thickness 0.15)
				)
				(justify mirror)
			)
		)
		(property "Tolerance" "1%"
			(at 323.23721 57.589586 135)
			(layer "B.Fab")
			(hide yes)
			(effects
				(font
					(size 1 1)
					(thickness 0.15)
				)
				(justify mirror)
			)
		)
		(property "Val" "1k65"
			(at 323.23721 57.589586 135)
			(layer "B.Fab")
			(hide yes)
			(effects
				(font
					(size 1 1)
					(thickness 0.15)
				)
				(justify mirror)
			)
		)
		(sheetname "/Power/")
		(sheetfile "power.kicad_sch")
		(attr smd)
		(fp_poly
			(pts
				(xy -0.925 0.47) (xy 0.925 0.47) (xy 0.925 -0.47) (xy -0.925 -0.47)
			)
			(stroke
				(width 0.05)
				(type default)
			)
			(fill no)
			(layer "B.CrtYd")
		)
		(fp_poly
			(pts
				(xy -0.5 0.25) (xy 0.5 0.25) (xy 0.5 -0.25) (xy -0.5 -0.25)
			)
			(stroke
				(width 0.15)
				(type solid)
			)
			(fill no)
			(layer "B.Fab")
		)
		(pad "1" smd roundrect
			(at -0.48 0 90)
			(size 0.59 0.64)
			(layers "B.Cu" "B.Mask" "B.Paste")
			(roundrect_rratio 0.25)
			(net 1 "GND")
			(pintype "passive")
		)
		(pad "2" smd roundrect
			(at 0.48 0 90)
			(size 0.59 0.64)
			(layers "B.Cu" "B.Mask" "B.Paste")
			(roundrect_rratio 0.25)
			(net 141 "Net-(D17-C)")
			(pintype "passive")
		)
	)
	(footprint "antmicro-footprints:TP_SMD_0.75mm"
		(layer "B.Cu")
		(at 147.828 97.89 180)
		(property "Reference" "TP18"
			(at 0 0.6 0)
			(layer "B.SilkS")
			(hide yes)
			(effects
				(font
					(size 0.7 0.7)
					(thickness 0.15)
				)
				(justify left bottom mirror)
			)
		)
		(property "Value" "TP_0.75mm_SMD"
			(at 0 -1.2 0)
			(layer "B.Fab")
			(effects
				(font
					(size 0.7 0.7)
					(thickness 0.15)
				)
				(justify left bottom mirror)
			)
		)
		(property "Description" "SMT test point"
			(at 0 0 0)
			(layer "B.Fab")
			(hide yes)
			(effects
				(font
					(size 1.27 1.27)
					(thickness 0.15)
				)
				(justify mirror)
			)
		)
		(property "MPN" ""
			(at 0 0 0)
			(unlocked yes)
			(layer "B.Fab")
			(hide yes)
			(effects
				(font
					(size 1 1)
					(thickness 0.15)
				)
				(justify mirror)
			)
		)
		(property "Manufacturer" ""
			(at 0 0 0)
			(unlocked yes)
			(layer "B.Fab")
			(hide yes)
			(effects
				(font
					(size 1 1)
					(thickness 0.15)
				)
				(justify mirror)
			)
		)
		(property "Author" "Antmicro"
			(at 0 0 0)
			(unlocked yes)
			(layer "B.Fab")
			(hide yes)
			(effects
				(font
					(size 1 1)
					(thickness 0.15)
				)
				(justify mirror)
			)
		)
		(property "License" "Apache-2.0"
			(at 0 0 0)
			(unlocked yes)
			(layer "B.Fab")
			(hide yes)
			(effects
				(font
					(size 1 1)
					(thickness 0.15)
				)
				(justify mirror)
			)
		)
		(sheetname "/Power/")
		(sheetfile "power.kicad_sch")
		(attr exclude_from_pos_files)
		(fp_circle
			(center 0 0)
			(end 0.475 0)
			(stroke
				(width 0.05)
				(type default)
			)
			(fill no)
			(layer "B.CrtYd")
		)
		(fp_text user "Author: Antmicro"
			(at -0.4 -3.901 0)
			(layer "B.Fab")
			(effects
				(font
					(size 0.7 0.7)
					(thickness 0.15)
				)
				(justify left bottom mirror)
			)
		)
		(fp_text user "${REFERENCE}"
			(at -0.4 -2.7 0)
			(layer "B.Fab")
			(effects
				(font
					(size 0.7 0.7)
					(thickness 0.15)
				)
				(justify left bottom mirror)
			)
		)
		(fp_text user "License: Apache-2.0"
			(at -0.4 -5.101 0)
			(layer "B.Fab")
			(effects
				(font
					(size 0.7 0.7)
					(thickness 0.15)
				)
				(justify left bottom mirror)
			)
		)
		(pad "1" smd circle
			(at 0 0 180)
			(size 0.75 0.75)
			(layers "B.Cu" "B.Mask")
			(net 123 "/Power/OUT_12V")
			(pinfunction "1")
			(pintype "passive")
		)
	)
	(footprint "antmicro-footprints:R_0402_1005Metric"
		(layer "B.Cu")
		(at 133.791 87.334 180)
		(descr "Resistor SMD 0402")
		(tags "resistor SMD 0402")
		(property "Reference" "R53"
			(at -1.083 -1.266 0)
			(layer "B.SilkS")
			(effects
				(font
					(size 0.7 0.7)
					(thickness 0.15)
				)
				(justify left bottom mirror)
			)
		)
		(property "Value" "R_0R_0402"
			(at -1.011843 -1.772047 0)
			(layer "B.Fab")
			(effects
				(font
					(size 0.7 0.7)
					(thickness 0.15)
				)
				(justify left bottom mirror)
			)
		)
		(property "Datasheet" "https://industrial.panasonic.com/cdbs/www-data/pdf/RDA0000/AOA0000C301.pdf"
			(at 0 0 180)
			(layer "F.Fab")
			(hide yes)
			(effects
				(font
					(size 1.27 1.27)
					(thickness 0.15)
				)
			)
		)
		(property "Description" "SMD Chip Resistor, Jumper, 0 ohm, 100 mW, 0402 [1005 Metric], Thick Film, General Purpose"
			(at 0 0 180)
			(layer "F.Fab")
			(hide yes)
			(effects
				(font
					(size 1.27 1.27)
					(thickness 0.15)
				)
			)
		)
		(property "Author" "Antmicro"
			(at 267.582 174.668 0)
			(layer "B.Fab")
			(hide yes)
			(effects
				(font
					(size 1 1)
					(thickness 0.15)
				)
				(justify mirror)
			)
		)
		(property "Current" "1A"
			(at 267.582 174.668 0)
			(layer "B.Fab")
			(hide yes)
			(effects
				(font
					(size 1 1)
					(thickness 0.15)
				)
				(justify mirror)
			)
		)
		(property "License" "Apache-2.0"
			(at 267.582 174.668 0)
			(layer "B.Fab")
			(hide yes)
			(effects
				(font
					(size 1 1)
					(thickness 0.15)
				)
				(justify mirror)
			)
		)
		(property "MPN" "ERJ2GE0R00X"
			(at 267.582 174.668 0)
			(layer "B.Fab")
			(hide yes)
			(effects
				(font
					(size 1 1)
					(thickness 0.15)
				)
				(justify mirror)
			)
		)
		(property "Manufacturer" "Panasonic"
			(at 267.582 174.668 0)
			(layer "B.Fab")
			(hide yes)
			(effects
				(font
					(size 1 1)
					(thickness 0.15)
				)
				(justify mirror)
			)
		)
		(property "Tolerance" ""
			(at 267.582 174.668 0)
			(layer "B.Fab")
			(hide yes)
			(effects
				(font
					(size 1 1)
					(thickness 0.15)
				)
				(justify mirror)
			)
		)
		(property "Val" "0R"
			(at 267.582 174.668 0)
			(layer "B.Fab")
			(hide yes)
			(effects
				(font
					(size 1 1)
					(thickness 0.15)
				)
				(justify mirror)
			)
		)
		(sheetname "/Deserializer/")
		(sheetfile "deserializer.kicad_sch")
		(attr smd)
		(fp_rect
			(start -0.925 0.47)
			(end 0.925 -0.47)
			(stroke
				(width 0.05)
				(type default)
			)
			(fill no)
			(layer "B.CrtYd")
		)
		(fp_rect
			(start -0.5 0.25)
			(end 0.5 -0.25)
			(stroke
				(width 0.15)
				(type solid)
			)
			(fill no)
			(layer "B.Fab")
		)
		(pad "1" smd roundrect
			(at -0.48 0 180)
			(size 0.59 0.64)
			(layers "B.Cu" "B.Mask" "B.Paste")
			(roundrect_rratio 0.25)
			(net 27 "/Deserializer/VDD")
			(pintype "passive")
		)
		(pad "2" smd roundrect
			(at 0.48 0 180)
			(size 0.59 0.64)
			(layers "B.Cu" "B.Mask" "B.Paste")
			(roundrect_rratio 0.25)
			(net 73 "+1V2")
			(pintype "passive")
		)
	)
	(footprint "antmicro-footprints:TP_SMD_0.75mm"
		(layer "B.Cu")
		(at 156.972 97.89 180)
		(property "Reference" "TP24"
			(at 0 0.6 0)
			(layer "B.SilkS")
			(hide yes)
			(effects
				(font
					(size 0.7 0.7)
					(thickness 0.15)
				)
				(justify left bottom mirror)
			)
		)
		(property "Value" "TP_0.75mm_SMD"
			(at 0 -1.2 0)
			(layer "B.Fab")
			(effects
				(font
					(size 0.7 0.7)
					(thickness 0.15)
				)
				(justify left bottom mirror)
			)
		)
		(property "Description" "SMT test point"
			(at 0 0 0)
			(layer "B.Fab")
			(hide yes)
			(effects
				(font
					(size 1.27 1.27)
					(thickness 0.15)
				)
				(justify mirror)
			)
		)
		(property "MPN" ""
			(at 0 0 0)
			(unlocked yes)
			(layer "B.Fab")
			(hide yes)
			(effects
				(font
					(size 1 1)
					(thickness 0.15)
				)
				(justify mirror)
			)
		)
		(property "Manufacturer" ""
			(at 0 0 0)
			(unlocked yes)
			(layer "B.Fab")
			(hide yes)
			(effects
				(font
					(size 1 1)
					(thickness 0.15)
				)
				(justify mirror)
			)
		)
		(property "Author" "Antmicro"
			(at 0 0 0)
			(unlocked yes)
			(layer "B.Fab")
			(hide yes)
			(effects
				(font
					(size 1 1)
					(thickness 0.15)
				)
				(justify mirror)
			)
		)
		(property "License" "Apache-2.0"
			(at 0 0 0)
			(unlocked yes)
			(layer "B.Fab")
			(hide yes)
			(effects
				(font
					(size 1 1)
					(thickness 0.15)
				)
				(justify mirror)
			)
		)
		(sheetname "/Connectors/")
		(sheetfile "connectors.kicad_sch")
		(attr exclude_from_pos_files)
		(fp_circle
			(center 0 0)
			(end 0.475 0)
			(stroke
				(width 0.05)
				(type default)
			)
			(fill no)
			(layer "B.CrtYd")
		)
		(fp_text user "Author: Antmicro"
			(at -0.4 -3.901 0)
			(layer "B.Fab")
			(effects
				(font
					(size 0.7 0.7)
					(thickness 0.15)
				)
				(justify left bottom mirror)
			)
		)
		(fp_text user "License: Apache-2.0"
			(at -0.4 -5.101 0)
			(layer "B.Fab")
			(effects
				(font
					(size 0.7 0.7)
					(thickness 0.15)
				)
				(justify left bottom mirror)
			)
		)
		(fp_text user "${REFERENCE}"
			(at -0.4 -2.7 0)
			(layer "B.Fab")
			(effects
				(font
					(size 0.7 0.7)
					(thickness 0.15)
				)
				(justify left bottom mirror)
			)
		)
		(pad "1" smd circle
			(at 0 0 180)
			(size 0.75 0.75)
			(layers "B.Cu" "B.Mask")
			(net 50 "/Connectors/FFC_3V3")
			(pinfunction "1")
			(pintype "passive")
		)
	)
	(footprint "antmicro-footprints:C_0402_1005Metric"
		(layer "B.Cu")
		(at 151.384 84.836 135)
		(descr "Capacitor SMD 0402")
		(tags "capacitor SMD 0402")
		(property "Reference" "C37"
			(at -0.97797 -1.314712 315)
			(unlocked yes)
			(layer "B.SilkS")
			(effects
				(font
					(size 0.7 0.7)
					(thickness 0.15)
				)
				(justify right bottom mirror)
			)
		)
		(property "Value" "C_10u_0402"
			(at -1.022927 -2.155213 135)
			(layer "B.Fab")
			(effects
				(font
					(size 0.7 0.7)
					(thickness 0.15)
				)
				(justify right bottom mirror)
			)
		)
		(property "Datasheet" "https://www.yageo.com/en/Chart/Download/pdf/CC0402MRX5R5BB106"
			(at 0 0 135)
			(layer "F.Fab")
			(hide yes)
			(effects
				(font
					(size 1.27 1.27)
					(thickness 0.15)
				)
			)
		)
		(property "Description" "SMD Multilayer Ceramic Capacitor, 10 µF, 6.3 V, 0402 [1005 Metric], ± 20%, X5R, CC Series"
			(at 0 0 135)
			(layer "F.Fab")
			(hide yes)
			(effects
				(font
					(size 1.27 1.27)
					(thickness 0.15)
				)
			)
		)
		(property "Author" "Antmicro"
			(at 318.416764 37.779458 0)
			(layer "B.Fab")
			(hide yes)
			(effects
				(font
					(size 1 1)
					(thickness 0.15)
				)
				(justify mirror)
			)
		)
		(property "Dielectric" ""
			(at 318.416764 37.779458 0)
			(layer "B.Fab")
			(hide yes)
			(effects
				(font
					(size 1 1)
					(thickness 0.15)
				)
				(justify mirror)
			)
		)
		(property "License" "Apache-2.0"
			(at 318.416764 37.779458 0)
			(layer "B.Fab")
			(hide yes)
			(effects
				(font
					(size 1 1)
					(thickness 0.15)
				)
				(justify mirror)
			)
		)
		(property "MPN" "CC0402MRX5R5BB106"
			(at 318.416764 37.779458 0)
			(layer "B.Fab")
			(hide yes)
			(effects
				(font
					(size 1 1)
					(thickness 0.15)
				)
				(justify mirror)
			)
		)
		(property "Manufacturer" "YAGEO"
			(at 318.416764 37.779458 0)
			(layer "B.Fab")
			(hide yes)
			(effects
				(font
					(size 1 1)
					(thickness 0.15)
				)
				(justify mirror)
			)
		)
		(property "Val" "10u"
			(at 318.416764 37.779458 0)
			(layer "B.Fab")
			(hide yes)
			(effects
				(font
					(size 1 1)
					(thickness 0.15)
				)
				(justify mirror)
			)
		)
		(property "Voltage" ""
			(at 318.416764 37.779458 0)
			(layer "B.Fab")
			(hide yes)
			(effects
				(font
					(size 1 1)
					(thickness 0.15)
				)
				(justify mirror)
			)
		)
		(sheetname "/Deserializer/")
		(sheetfile "deserializer.kicad_sch")
		(attr smd)
		(fp_poly
			(pts
				(xy -0.925 0.47) (xy 0.925 0.47) (xy 0.925 -0.47) (xy -0.925 -0.47)
			)
			(stroke
				(width 0.05)
				(type default)
			)
			(fill no)
			(layer "B.CrtYd")
		)
		(fp_line
			(start 0.504 -0.248)
			(end 0.504 0.25)
			(stroke
				(width 0.15)
				(type solid)
			)
			(layer "B.Fab")
		)
		(fp_line
			(start 0.504 0.25)
			(end -0.494 0.25)
			(stroke
				(width 0.15)
				(type solid)
			)
			(layer "B.Fab")
		)
		(fp_line
			(start -0.494 -0.248)
			(end 0.504 -0.248)
			(stroke
				(width 0.15)
				(type solid)
			)
			(layer "B.Fab")
		)
		(fp_line
			(start -0.494 0.25)
			(end -0.494 -0.248)
			(stroke
				(width 0.15)
				(type solid)
			)
			(layer "B.Fab")
		)
		(pad "1" smd roundrect
			(at -0.48 0 135)
			(size 0.59 0.64)
			(layers "B.Cu" "B.Mask" "B.Paste")
			(roundrect_rratio 0.25)
			(net 1 "GND")
			(pintype "passive")
		)
		(pad "2" smd roundrect
			(at 0.48 0 135)
			(size 0.59 0.64)
			(layers "B.Cu" "B.Mask" "B.Paste")
			(roundrect_rratio 0.25)
			(net 27 "/Deserializer/VDD")
			(pintype "passive")
		)
	)
	(footprint "antmicro-footprints:C_0402_1005Metric"
		(layer "B.Cu")
		(at 139.954 80.01 -45)
		(descr "Capacitor SMD 0402")
		(tags "capacitor SMD 0402")
		(property "Reference" "C52"
			(at -1.612512 0.317093 315)
			(unlocked yes)
			(layer "B.SilkS")
			(effects
				(font
					(size 0.7 0.7)
					(thickness 0.15)
				)
				(justify left bottom mirror)
			)
		)
		(property "Value" "C_100n_0402"
			(at -1.022927 -2.155213 135)
			(layer "B.Fab")
			(effects
				(font
					(size 0.7 0.7)
					(thickness 0.15)
				)
				(justify left bottom mirror)
			)
		)
		(property "Datasheet" "https://www.murata.com/products/productdetail?partno=GRM155R61H104KE14%23"
			(at 0 0 315)
			(layer "F.Fab")
			(hide yes)
			(effects
				(font
					(size 1.27 1.27)
					(thickness 0.15)
				)
			)
		)
		(property "Description" "SMD Multilayer Ceramic Capacitor, 0.1 µF, 50 V, 0402 [1005 Metric], ± 10%, X5R, GRM Series"
			(at 0 0 315)
			(layer "F.Fab")
			(hide yes)
			(effects
				(font
					(size 1.27 1.27)
					(thickness 0.15)
				)
			)
		)
		(property "Author" "Antmicro"
			(at -15.584036 122.396809 0)
			(layer "B.Fab")
			(hide yes)
			(effects
				(font
					(size 1 1)
					(thickness 0.15)
				)
				(justify mirror)
			)
		)
		(property "Dielectric" "X5R"
			(at -15.584036 122.396809 0)
			(layer "B.Fab")
			(hide yes)
			(effects
				(font
					(size 1 1)
					(thickness 0.15)
				)
				(justify mirror)
			)
		)
		(property "License" "Apache-2.0"
			(at -15.584036 122.396809 0)
			(layer "B.Fab")
			(hide yes)
			(effects
				(font
					(size 1 1)
					(thickness 0.15)
				)
				(justify mirror)
			)
		)
		(property "MPN" "GRM155R61H104KE14D"
			(at -15.584036 122.396809 0)
			(layer "B.Fab")
			(hide yes)
			(effects
				(font
					(size 1 1)
					(thickness 0.15)
				)
				(justify mirror)
			)
		)
		(property "Manufacturer" "Murata"
			(at -15.584036 122.396809 0)
			(layer "B.Fab")
			(hide yes)
			(effects
				(font
					(size 1 1)
					(thickness 0.15)
				)
				(justify mirror)
			)
		)
		(property "Val" "100n"
			(at -15.584036 122.396809 0)
			(layer "B.Fab")
			(hide yes)
			(effects
				(font
					(size 1 1)
					(thickness 0.15)
				)
				(justify mirror)
			)
		)
		(property "Voltage" "50V"
			(at -15.584036 122.396809 0)
			(layer "B.Fab")
			(hide yes)
			(effects
				(font
					(size 1 1)
					(thickness 0.15)
				)
				(justify mirror)
			)
		)
		(sheetname "/Deserializer/")
		(sheetfile "deserializer.kicad_sch")
		(attr smd)
		(fp_poly
			(pts
				(xy -0.925 0.47) (xy 0.925 0.47) (xy 0.925 -0.47) (xy -0.925 -0.47)
			)
			(stroke
				(width 0.05)
				(type default)
			)
			(fill no)
			(layer "B.CrtYd")
		)
		(fp_line
			(start -0.494 0.25)
			(end -0.494 -0.248)
			(stroke
				(width 0.15)
				(type solid)
			)
			(layer "B.Fab")
		)
		(fp_line
			(start -0.494 -0.248)
			(end 0.504 -0.248)
			(stroke
				(width 0.15)
				(type solid)
			)
			(layer "B.Fab")
		)
		(fp_line
			(start 0.504 0.25)
			(end -0.494 0.25)
			(stroke
				(width 0.15)
				(type solid)
			)
			(layer "B.Fab")
		)
		(fp_line
			(start 0.504 -0.248)
			(end 0.504 0.25)
			(stroke
				(width 0.15)
				(type solid)
			)
			(layer "B.Fab")
		)
		(pad "1" smd roundrect
			(at -0.48 0 315)
			(size 0.59 0.64)
			(layers "B.Cu" "B.Mask" "B.Paste")
			(roundrect_rratio 0.25)
			(net 1 "GND")
			(pintype "passive")
		)
		(pad "2" smd roundrect
			(at 0.48 0 315)
			(size 0.59 0.64)
			(layers "B.Cu" "B.Mask" "B.Paste")
			(roundrect_rratio 0.25)
			(net 146 "VDDIO")
			(pintype "passive")
		)
	)
	(footprint "antmicro-footprints:TP_SMD_0.75mm"
		(layer "B.Cu")
		(at 155.448 97.89 180)
		(property "Reference" "TP23"
			(at 0 0.6 0)
			(layer "B.SilkS")
			(hide yes)
			(effects
				(font
					(size 0.7 0.7)
					(thickness 0.15)
				)
				(justify left bottom mirror)
			)
		)
		(property "Value" "TP_0.75mm_SMD"
			(at 0 -1.2 0)
			(layer "B.Fab")
			(effects
				(font
					(size 0.7 0.7)
					(thickness 0.15)
				)
				(justify left bottom mirror)
			)
		)
		(property "Description" "SMT test point"
			(at 0 0 0)
			(layer "B.Fab")
			(hide yes)
			(effects
				(font
					(size 1.27 1.27)
					(thickness 0.15)
				)
				(justify mirror)
			)
		)
		(property "MPN" ""
			(at 0 0 0)
			(unlocked yes)
			(layer "B.Fab")
			(hide yes)
			(effects
				(font
					(size 1 1)
					(thickness 0.15)
				)
				(justify mirror)
			)
		)
		(property "Manufacturer" ""
			(at 0 0 0)
			(unlocked yes)
			(layer "B.Fab")
			(hide yes)
			(effects
				(font
					(size 1 1)
					(thickness 0.15)
				)
				(justify mirror)
			)
		)
		(property "Author" "Antmicro"
			(at 0 0 0)
			(unlocked yes)
			(layer "B.Fab")
			(hide yes)
			(effects
				(font
					(size 1 1)
					(thickness 0.15)
				)
				(justify mirror)
			)
		)
		(property "License" "Apache-2.0"
			(at 0 0 0)
			(unlocked yes)
			(layer "B.Fab")
			(hide yes)
			(effects
				(font
					(size 1 1)
					(thickness 0.15)
				)
				(justify mirror)
			)
		)
		(sheetname "/Connectors/")
		(sheetfile "connectors.kicad_sch")
		(attr exclude_from_pos_files)
		(fp_circle
			(center 0 0)
			(end 0.475 0)
			(stroke
				(width 0.05)
				(type default)
			)
			(fill no)
			(layer "B.CrtYd")
		)
		(fp_text user "Author: Antmicro"
			(at -0.4 -3.901 0)
			(layer "B.Fab")
			(effects
				(font
					(size 0.7 0.7)
					(thickness 0.15)
				)
				(justify left bottom mirror)
			)
		)
		(fp_text user "License: Apache-2.0"
			(at -0.4 -5.101 0)
			(layer "B.Fab")
			(effects
				(font
					(size 0.7 0.7)
					(thickness 0.15)
				)
				(justify left bottom mirror)
			)
		)
		(fp_text user "${REFERENCE}"
			(at -0.4 -2.7 0)
			(layer "B.Fab")
			(effects
				(font
					(size 0.7 0.7)
					(thickness 0.15)
				)
				(justify left bottom mirror)
			)
		)
		(pad "1" smd circle
			(at 0 0 180)
			(size 0.75 0.75)
			(layers "B.Cu" "B.Mask")
			(net 113 "/Connectors/FFC_5V")
			(pinfunction "1")
			(pintype "passive")
		)
	)
	(footprint "antmicro-footprints:TP_SMD_0.75mm"
		(layer "B.Cu")
		(at 150.876 97.89 180)
		(property "Reference" "TP19"
			(at 0 0.6 0)
			(layer "B.SilkS")
			(hide yes)
			(effects
				(font
					(size 0.7 0.7)
					(thickness 0.15)
				)
				(justify left bottom mirror)
			)
		)
		(property "Value" "TP_0.75mm_SMD"
			(at 0 -1.2 0)
			(layer "B.Fab")
			(effects
				(font
					(size 0.7 0.7)
					(thickness 0.15)
				)
				(justify left bottom mirror)
			)
		)
		(property "Description" "SMT test point"
			(at 0 0 0)
			(layer "B.Fab")
			(hide yes)
			(effects
				(font
					(size 1.27 1.27)
					(thickness 0.15)
				)
				(justify mirror)
			)
		)
		(property "MPN" ""
			(at 0 0 0)
			(unlocked yes)
			(layer "B.Fab")
			(hide yes)
			(effects
				(font
					(size 1 1)
					(thickness 0.15)
				)
				(justify mirror)
			)
		)
		(property "Manufacturer" ""
			(at 0 0 0)
			(unlocked yes)
			(layer "B.Fab")
			(hide yes)
			(effects
				(font
					(size 1 1)
					(thickness 0.15)
				)
				(justify mirror)
			)
		)
		(property "Author" "Antmicro"
			(at 0 0 0)
			(unlocked yes)
			(layer "B.Fab")
			(hide yes)
			(effects
				(font
					(size 1 1)
					(thickness 0.15)
				)
				(justify mirror)
			)
		)
		(property "License" "Apache-2.0"
			(at 0 0 0)
			(unlocked yes)
			(layer "B.Fab")
			(hide yes)
			(effects
				(font
					(size 1 1)
					(thickness 0.15)
				)
				(justify mirror)
			)
		)
		(sheetname "/Power/")
		(sheetfile "power.kicad_sch")
		(attr exclude_from_pos_files)
		(fp_circle
			(center 0 0)
			(end 0.475 0)
			(stroke
				(width 0.05)
				(type default)
			)
			(fill no)
			(layer "B.CrtYd")
		)
		(fp_text user "Author: Antmicro"
			(at -0.4 -3.901 0)
			(layer "B.Fab")
			(effects
				(font
					(size 0.7 0.7)
					(thickness 0.15)
				)
				(justify left bottom mirror)
			)
		)
		(fp_text user "${REFERENCE}"
			(at -0.4 -2.7 0)
			(layer "B.Fab")
			(effects
				(font
					(size 0.7 0.7)
					(thickness 0.15)
				)
				(justify left bottom mirror)
			)
		)
		(fp_text user "License: Apache-2.0"
			(at -0.4 -5.101 0)
			(layer "B.Fab")
			(effects
				(font
					(size 0.7 0.7)
					(thickness 0.15)
				)
				(justify left bottom mirror)
			)
		)
		(pad "1" smd circle
			(at 0 0 180)
			(size 0.75 0.75)
			(layers "B.Cu" "B.Mask")
			(net 5 "+5V")
			(pinfunction "1")
			(pintype "passive")
		)
	)
	(footprint "antmicro-footprints:R_0402_1005Metric"
		(layer "B.Cu")
		(at 155.467792 96.395897 90)
		(descr "Resistor SMD 0402")
		(tags "resistor SMD 0402")
		(property "Reference" "R71"
			(at 5.73053 0.434221 90)
			(layer "B.SilkS")
			(effects
				(font
					(size 0.7 0.7)
					(thickness 0.15)
				)
				(justify right bottom mirror)
			)
		)
		(property "Value" "R_470R_0402"
			(at -1.011843 -1.772046 90)
			(layer "B.Fab")
			(effects
				(font
					(size 0.7 0.7)
					(thickness 0.15)
				)
				(justify right bottom mirror)
			)
		)
		(property "Datasheet" "https://www.bourns.com/docs/product-datasheets/cr.pdf"
			(at 0 0 90)
			(layer "F.Fab")
			(hide yes)
			(effects
				(font
					(size 1.27 1.27)
					(thickness 0.15)
				)
			)
		)
		(property "Description" "SMD Chip Resistor, 470 ohm, ± 1%, 62.5 mW, 0402 [1005 Metric], Thick Film, General Purpose"
			(at 0 0 90)
			(layer "F.Fab")
			(hide yes)
			(effects
				(font
					(size 1.27 1.27)
					(thickness 0.15)
				)
			)
		)
		(property "Author" "Antmicro"
			(at 333.650804 53.296134 135)
			(layer "B.Fab")
			(hide yes)
			(effects
				(font
					(size 1 1)
					(thickness 0.15)
				)
				(justify mirror)
			)
		)
		(property "License" "Apache-2.0"
			(at 333.650804 53.296134 135)
			(layer "B.Fab")
			(hide yes)
			(effects
				(font
					(size 1 1)
					(thickness 0.15)
				)
				(justify mirror)
			)
		)
		(property "MPN" "CR0402-FX-4700GLF"
			(at 333.650804 53.296134 135)
			(layer "B.Fab")
			(hide yes)
			(effects
				(font
					(size 1 1)
					(thickness 0.15)
				)
				(justify mirror)
			)
		)
		(property "Manufacturer" "Bourns"
			(at 333.650804 53.296134 135)
			(layer "B.Fab")
			(hide yes)
			(effects
				(font
					(size 1 1)
					(thickness 0.15)
				)
				(justify mirror)
			)
		)
		(property "Tolerance" "1%"
			(at 333.650804 53.296134 135)
			(layer "B.Fab")
			(hide yes)
			(effects
				(font
					(size 1 1)
					(thickness 0.15)
				)
				(justify mirror)
			)
		)
		(property "Val" "470R"
			(at 333.650804 53.296134 135)
			(layer "B.Fab")
			(hide yes)
			(effects
				(font
					(size 1 1)
					(thickness 0.15)
				)
				(justify mirror)
			)
		)
		(sheetname "/Connectors/")
		(sheetfile "connectors.kicad_sch")
		(attr smd)
		(fp_poly
			(pts
				(xy -0.925 0.47) (xy 0.925 0.47) (xy 0.925 -0.47) (xy -0.925 -0.47)
			)
			(stroke
				(width 0.05)
				(type default)
			)
			(fill no)
			(layer "B.CrtYd")
		)
		(fp_poly
			(pts
				(xy -0.5 0.25) (xy 0.5 0.25) (xy 0.5 -0.25) (xy -0.5 -0.25)
			)
			(stroke
				(width 0.15)
				(type solid)
			)
			(fill no)
			(layer "B.Fab")
		)
		(pad "1" smd roundrect
			(at -0.48 0 90)
			(size 0.59 0.64)
			(layers "B.Cu" "B.Mask" "B.Paste")
			(roundrect_rratio 0.25)
			(net 1 "GND")
			(pintype "passive")
		)
		(pad "2" smd roundrect
			(at 0.48 0 90)
			(size 0.59 0.64)
			(layers "B.Cu" "B.Mask" "B.Paste")
			(roundrect_rratio 0.25)
			(net 109 "Net-(D13-C)")
			(pintype "passive")
		)
	)
	(footprint "antmicro-footprints:C_0402_1005Metric"
		(layer "B.Cu")
		(at 140.716 79.248 -45)
		(descr "Capacitor SMD 0402")
		(tags "capacitor SMD 0402")
		(property "Reference" "C54"
			(at -1.588513 0.317094 315)
			(unlocked yes)
			(layer "B.SilkS")
			(effects
				(font
					(size 0.7 0.7)
					(thickness 0.15)
				)
				(justify left bottom mirror)
			)
		)
		(property "Value" "C_10u_0402"
			(at -1.022927 -2.155213 135)
			(layer "B.Fab")
			(effects
				(font
					(size 0.7 0.7)
					(thickness 0.15)
				)
				(justify left bottom mirror)
			)
		)
		(property "Datasheet" "https://www.yageo.com/en/Chart/Download/pdf/CC0402MRX5R5BB106"
			(at 0 0 315)
			(layer "F.Fab")
			(hide yes)
			(effects
				(font
					(size 1.27 1.27)
					(thickness 0.15)
				)
			)
		)
		(property "Description" "SMD Multilayer Ceramic Capacitor, 10 µF, 6.3 V, 0402 [1005 Metric], ± 20%, X5R, CC Series"
			(at 0 0 315)
			(layer "F.Fab")
			(hide yes)
			(effects
				(font
					(size 1.27 1.27)
					(thickness 0.15)
				)
			)
		)
		(property "Author" "Antmicro"
			(at -14.822036 122.712439 0)
			(layer "B.Fab")
			(hide yes)
			(effects
				(font
					(size 1 1)
					(thickness 0.15)
				)
				(justify mirror)
			)
		)
		(property "Dielectric" ""
			(at -14.822036 122.712439 0)
			(layer "B.Fab")
			(hide yes)
			(effects
				(font
					(size 1 1)
					(thickness 0.15)
				)
				(justify mirror)
			)
		)
		(property "License" "Apache-2.0"
			(at -14.822036 122.712439 0)
			(layer "B.Fab")
			(hide yes)
			(effects
				(font
					(size 1 1)
					(thickness 0.15)
				)
				(justify mirror)
			)
		)
		(property "MPN" "CC0402MRX5R5BB106"
			(at -14.822036 122.712439 0)
			(layer "B.Fab")
			(hide yes)
			(effects
				(font
					(size 1 1)
					(thickness 0.15)
				)
				(justify mirror)
			)
		)
		(property "Manufacturer" "YAGEO"
			(at -14.822036 122.712439 0)
			(layer "B.Fab")
			(hide yes)
			(effects
				(font
					(size 1 1)
					(thickness 0.15)
				)
				(justify mirror)
			)
		)
		(property "Val" "10u"
			(at -14.822036 122.712439 0)
			(layer "B.Fab")
			(hide yes)
			(effects
				(font
					(size 1 1)
					(thickness 0.15)
				)
				(justify mirror)
			)
		)
		(property "Voltage" ""
			(at -14.822036 122.712439 0)
			(layer "B.Fab")
			(hide yes)
			(effects
				(font
					(size 1 1)
					(thickness 0.15)
				)
				(justify mirror)
			)
		)
		(sheetname "/Deserializer/")
		(sheetfile "deserializer.kicad_sch")
		(attr smd)
		(fp_poly
			(pts
				(xy -0.925 0.47) (xy 0.925 0.47) (xy 0.925 -0.47) (xy -0.925 -0.47)
			)
			(stroke
				(width 0.05)
				(type default)
			)
			(fill no)
			(layer "B.CrtYd")
		)
		(fp_line
			(start -0.494 0.25)
			(end -0.494 -0.248)
			(stroke
				(width 0.15)
				(type solid)
			)
			(layer "B.Fab")
		)
		(fp_line
			(start -0.494 -0.248)
			(end 0.504 -0.248)
			(stroke
				(width 0.15)
				(type solid)
			)
			(layer "B.Fab")
		)
		(fp_line
			(start 0.504 0.25)
			(end -0.494 0.25)
			(stroke
				(width 0.15)
				(type solid)
			)
			(layer "B.Fab")
		)
		(fp_line
			(start 0.504 -0.248)
			(end 0.504 0.25)
			(stroke
				(width 0.15)
				(type solid)
			)
			(layer "B.Fab")
		)
		(pad "1" smd roundrect
			(at -0.48 0 315)
			(size 0.59 0.64)
			(layers "B.Cu" "B.Mask" "B.Paste")
			(roundrect_rratio 0.25)
			(net 1 "GND")
			(pintype "passive")
		)
		(pad "2" smd roundrect
			(at 0.48 0 315)
			(size 0.59 0.64)
			(layers "B.Cu" "B.Mask" "B.Paste")
			(roundrect_rratio 0.25)
			(net 146 "VDDIO")
			(pintype "passive")
		)
	)
	(footprint "antmicro-footprints:TP_SMD_0.75mm"
		(layer "B.Cu")
		(at 155.7 76.75 180)
		(property "Reference" "TP24"
			(at 0 0.6 0)
			(layer "B.SilkS")
			(hide yes)
			(effects
				(font
					(size 0.7 0.7)
					(thickness 0.15)
				)
				(justify left bottom mirror)
			)
		)
		(property "Value" "TP_0.75mm_SMD"
			(at 0 -1.2 0)
			(layer "B.Fab")
			(effects
				(font
					(size 0.7 0.7)
					(thickness 0.15)
				)
				(justify left bottom mirror)
			)
		)
		(property "Description" "SMT test point"
			(at 0 0 0)
			(layer "B.Fab")
			(hide yes)
			(effects
				(font
					(size 1.27 1.27)
					(thickness 0.15)
				)
				(justify mirror)
			)
		)
		(property "MPN" ""
			(at 0 0 0)
			(unlocked yes)
			(layer "B.Fab")
			(hide yes)
			(effects
				(font
					(size 1 1)
					(thickness 0.15)
				)
				(justify mirror)
			)
		)
		(property "Manufacturer" ""
			(at 0 0 0)
			(unlocked yes)
			(layer "B.Fab")
			(hide yes)
			(effects
				(font
					(size 1 1)
					(thickness 0.15)
				)
				(justify mirror)
			)
		)
		(property "Author" "Antmicro"
			(at 0 0 0)
			(unlocked yes)
			(layer "B.Fab")
			(hide yes)
			(effects
				(font
					(size 1 1)
					(thickness 0.15)
				)
				(justify mirror)
			)
		)
		(property "License" "Apache-2.0"
			(at 0 0 0)
			(unlocked yes)
			(layer "B.Fab")
			(hide yes)
			(effects
				(font
					(size 1 1)
					(thickness 0.15)
				)
				(justify mirror)
			)
		)
		(sheetname "/Connectors/")
		(sheetfile "connectors.kicad_sch")
		(attr exclude_from_pos_files)
		(fp_circle
			(center 0 0)
			(end 0.475 0)
			(stroke
				(width 0.05)
				(type default)
			)
			(fill no)
			(layer "B.CrtYd")
		)
		(fp_text user "License: Apache-2.0"
			(at -0.4 -5.101 0)
			(layer "B.Fab")
			(effects
				(font
					(size 0.7 0.7)
					(thickness 0.15)
				)
				(justify left bottom mirror)
			)
		)
		(fp_text user "${REFERENCE}"
			(at -0.4 -2.7 0)
			(layer "B.Fab")
			(effects
				(font
					(size 0.7 0.7)
					(thickness 0.15)
				)
				(justify left bottom mirror)
			)
		)
		(fp_text user "Author: Antmicro"
			(at -0.4 -3.901 0)
			(layer "B.Fab")
			(effects
				(font
					(size 0.7 0.7)
					(thickness 0.15)
				)
				(justify left bottom mirror)
			)
		)
		(pad "1" smd circle
			(at 0 0 180)
			(size 0.75 0.75)
			(layers "B.Cu" "B.Mask")
			(net 88 "/Connectors/SDA")
			(pinfunction "1")
			(pintype "passive")
		)
	)
	(footprint "antmicro-footprints:R_0402_1005Metric"
		(layer "B.Cu")
		(at 152.43253 96.385897 90)
		(descr "Resistor SMD 0402")
		(tags "resistor SMD 0402")
		(property "Reference" "R7"
			(at 5.775194 0.427452 90)
			(layer "B.SilkS")
			(effects
				(font
					(size 0.7 0.7)
					(thickness 0.15)
				)
				(justify right bottom mirror)
			)
		)
		(property "Value" "R_470R_0402"
			(at -1.011843 -1.772046 90)
			(layer "B.Fab")
			(effects
				(font
					(size 0.7 0.7)
					(thickness 0.15)
				)
				(justify right bottom mirror)
			)
		)
		(property "Datasheet" "https://www.bourns.com/docs/product-datasheets/cr.pdf"
			(at 0 0 90)
			(layer "F.Fab")
			(hide yes)
			(effects
				(font
					(size 1.27 1.27)
					(thickness 0.15)
				)
			)
		)
		(property "Description" "SMD Chip Resistor, 470 ohm, ± 1%, 62.5 mW, 0402 [1005 Metric], Thick Film, General Purpose"
			(at 0 0 90)
			(layer "F.Fab")
			(hide yes)
			(effects
				(font
					(size 1.27 1.27)
					(thickness 0.15)
				)
			)
		)
		(property "Author" "Antmicro"
			(at 328.456079 55.454932 135)
			(layer "B.Fab")
			(hide yes)
			(effects
				(font
					(size 1 1)
					(thickness 0.15)
				)
				(justify mirror)
			)
		)
		(property "License" "Apache-2.0"
			(at 328.456079 55.454932 135)
			(layer "B.Fab")
			(hide yes)
			(effects
				(font
					(size 1 1)
					(thickness 0.15)
				)
				(justify mirror)
			)
		)
		(property "MPN" "CR0402-FX-4700GLF"
			(at 328.456079 55.454932 135)
			(layer "B.Fab")
			(hide yes)
			(effects
				(font
					(size 1 1)
					(thickness 0.15)
				)
				(justify mirror)
			)
		)
		(property "Manufacturer" "Bourns"
			(at 328.456079 55.454932 135)
			(layer "B.Fab")
			(hide yes)
			(effects
				(font
					(size 1 1)
					(thickness 0.15)
				)
				(justify mirror)
			)
		)
		(property "Tolerance" "1%"
			(at 328.456079 55.454932 135)
			(layer "B.Fab")
			(hide yes)
			(effects
				(font
					(size 1 1)
					(thickness 0.15)
				)
				(justify mirror)
			)
		)
		(property "Val" "470R"
			(at 328.456079 55.454932 135)
			(layer "B.Fab")
			(hide yes)
			(effects
				(font
					(size 1 1)
					(thickness 0.15)
				)
				(justify mirror)
			)
		)
		(sheetname "/Connectors/")
		(sheetfile "connectors.kicad_sch")
		(attr smd)
		(fp_poly
			(pts
				(xy -0.925 0.47) (xy 0.925 0.47) (xy 0.925 -0.47) (xy -0.925 -0.47)
			)
			(stroke
				(width 0.05)
				(type default)
			)
			(fill no)
			(layer "B.CrtYd")
		)
		(fp_poly
			(pts
				(xy -0.5 0.25) (xy 0.5 0.25) (xy 0.5 -0.25) (xy -0.5 -0.25)
			)
			(stroke
				(width 0.15)
				(type solid)
			)
			(fill no)
			(layer "B.Fab")
		)
		(pad "1" smd roundrect
			(at -0.48 0 90)
			(size 0.59 0.64)
			(layers "B.Cu" "B.Mask" "B.Paste")
			(roundrect_rratio 0.25)
			(net 1 "GND")
			(pintype "passive")
		)
		(pad "2" smd roundrect
			(at 0.48 0 90)
			(size 0.59 0.64)
			(layers "B.Cu" "B.Mask" "B.Paste")
			(roundrect_rratio 0.25)
			(net 64 "Net-(D2-C)")
			(pintype "passive")
		)
	)
	(footprint "antmicro-footprints:Spacer_Drill3.7mm_H6mm_9774060151R"
		(layer "B.Cu")
		(at 123.372 93.068 180)
		(descr "Spacer M=3 h=36mm fi=5.1mm")
		(property "Reference" "H4"
			(at 0 3.2 0)
			(layer "B.SilkS")
			(effects
				(font
					(size 0.7 0.7)
					(thickness 0.15)
				)
				(justify left bottom mirror)
			)
		)
		(property "Value" "Spacer_Drill3.7mm_H6mm_9774060151R"
			(at 0 -4 0)
			(layer "B.Fab")
			(effects
				(font
					(size 0.7 0.7)
					(thickness 0.15)
				)
				(justify left bottom mirror)
			)
		)
		(property "Datasheet" "https://www.we-online.com/components/products/datasheet/9774060151R.pdf"
			(at 0 0 180)
			(layer "F.Fab")
			(hide yes)
			(effects
				(font
					(size 1.27 1.27)
					(thickness 0.15)
				)
			)
		)
		(property "Description" "Spacer, SMT, Non Stop, Steel, Swage Round, 5.1 mm x 6 mm, M2.5 Thread, WA-SMSI Series"
			(at 0 0 180)
			(layer "F.Fab")
			(hide yes)
			(effects
				(font
					(size 1.27 1.27)
					(thickness 0.15)
				)
			)
		)
		(property "Author" "Antmicro"
			(at 246.744 186.136 0)
			(layer "B.Fab")
			(hide yes)
			(effects
				(font
					(size 1 1)
					(thickness 0.15)
				)
				(justify mirror)
			)
		)
		(property "License" "Apache-2.0"
			(at 246.744 186.136 0)
			(layer "B.Fab")
			(hide yes)
			(effects
				(font
					(size 1 1)
					(thickness 0.15)
				)
				(justify mirror)
			)
		)
		(property "MPN" "9774060151R"
			(at 246.744 186.136 0)
			(layer "B.Fab")
			(hide yes)
			(effects
				(font
					(size 1 1)
					(thickness 0.15)
				)
				(justify mirror)
			)
		)
		(property "Manufacturer" "Würth Elektronik"
			(at 246.744 186.136 0)
			(layer "B.Fab")
			(hide yes)
			(effects
				(font
					(size 1 1)
					(thickness 0.15)
				)
				(justify mirror)
			)
		)
		(sheetname "/")
		(sheetfile "gmsl-deserializer.kicad_sch")
		(solder_paste_margin_ratio -1)
		(attr smd)
		(fp_circle
			(center 0 0)
			(end 3.05 0)
			(stroke
				(width 0.05)
				(type solid)
			)
			(fill no)
			(layer "B.CrtYd")
		)
		(fp_circle
			(center 0 0)
			(end 2.6 0)
			(stroke
				(width 0.15)
				(type solid)
			)
			(fill no)
			(layer "B.Fab")
		)
		(pad "" smd custom
			(at -1.7 -1.7 90)
			(size 0.62 0.62)
			(layers "B.Paste")
			(thermal_bridge_angle 90)
			(options
				(clearance outline)
				(anchor circle)
			)
			(primitives
				(gr_arc
					(start 1.266786 0.24747)
					(mid 0.285453 -0.29439)
					(end -0.250195 -1.279127)
					(width 0.2)
				)
				(gr_arc
					(start 1.259603 0.339191)
					(mid 0.218448 -0.232561)
					(end -0.34334 -1.279127)
					(width 0.2)
				)
				(gr_arc
					(start 1.255279 0.431435)
					(mid 0.152481 -0.169693)
					(end -0.436309 -1.279127)
					(width 0.2)
				)
				(gr_arc
					(start 1.253811 0.524161)
					(mid 0.087542 -0.105784)
					(end -0.529126 -1.279127)
					(width 0.2)
				)
				(gr_arc
					(start 1.275473 0.621136)
					(mid 0.0309 -0.033527)
					(end -0.621807 -1.279127)
					(width 0.2)
				)
				(gr_arc
					(start 1.263664 0.711602)
					(mid -0.037759 0.026651)
					(end -0.71437 -1.279127)
					(width 0.2)
				)
				(gr_arc
					(start 1.253435 0.802342)
					(mid -0.105837 0.087395)
					(end -0.806826 -1.279127)
					(width 0.2)
				)
				(gr_arc
					(start 1.267475 0.897258)
					(mid -0.165236 0.156885)
					(end -0.899187 -1.279127)
					(width 0.2)
				)
				(gr_arc
					(start 1.270645 0.990112)
					(mid -0.228522 0.222449)
					(end -0.991463 -1.279127)
					(width 0.2)
				)
				(gr_arc
					(start 1.266278 1.081674)
					(mid -0.294507 0.285313)
					(end -1.083663 -1.279127)
					(width 0.2)
				)
				(gr_line
					(start 1.279127 0.250195)
					(end 1.279127 1.083663)
					(width 0.2)
				)
				(gr_line
					(start -0.250195 -1.279127)
					(end -1.083663 -1.279127)
					(width 0.2)
				)
			)
		)
		(pad "" smd custom
			(at -1.7 1.7 180)
			(size 0.62 0.62)
			(layers "B.Paste")
			(thermal_bridge_angle 90)
			(options
				(clearance outline)
				(anchor circle)
			)
			(primitives
				(gr_arc
					(start 1.266786 0.24747)
					(mid 0.285453 -0.29439)
					(end -0.250195 -1.279127)
					(width 0.2)
				)
				(gr_arc
					(start 1.259603 0.339191)
					(mid 0.218448 -0.232561)
					(end -0.34334 -1.279127)
					(width 0.2)
				)
				(gr_arc
					(start 1.255279 0.431435)
					(mid 0.152481 -0.169693)
					(end -0.436309 -1.279127)
					(width 0.2)
				)
				(gr_arc
					(start 1.253811 0.524161)
					(mid 0.087542 -0.105784)
					(end -0.529126 -1.279127)
					(width 0.2)
				)
				(gr_arc
					(start 1.275473 0.621136)
					(mid 0.0309 -0.033527)
					(end -0.621807 -1.279127)
					(width 0.2)
				)
				(gr_arc
					(start 1.263664 0.711602)
					(mid -0.037759 0.026651)
					(end -0.71437 -1.279127)
					(width 0.2)
				)
				(gr_arc
					(start 1.253435 0.802342)
					(mid -0.105837 0.087395)
					(end -0.806826 -1.279127)
					(width 0.2)
				)
				(gr_arc
					(start 1.267475 0.897258)
					(mid -0.165236 0.156885)
					(end -0.899187 -1.279127)
					(width 0.2)
				)
				(gr_arc
					(start 1.270645 0.990112)
					(mid -0.228522 0.222449)
					(end -0.991463 -1.279127)
					(width 0.2)
				)
				(gr_arc
					(start 1.266278 1.081674)
					(mid -0.294507 0.285313)
					(end -1.083663 -1.279127)
					(width 0.2)
				)
				(gr_line
					(start 1.279127 0.250195)
					(end 1.279127 1.083663)
					(width 0.2)
				)
				(gr_line
					(start -0.250195 -1.279127)
					(end -1.083663 -1.279127)
					(width 0.2)
				)
			)
		)
		(pad "" smd custom
			(at 1.7 -1.7)
			(size 0.62 0.62)
			(layers "B.Paste")
			(thermal_bridge_angle 90)
			(options
				(clearance outline)
				(anchor circle)
			)
			(primitives
				(gr_arc
					(start 1.266786 0.24747)
					(mid 0.285453 -0.29439)
					(end -0.250195 -1.279127)
					(width 0.2)
				)
				(gr_arc
					(start 1.259603 0.339191)
					(mid 0.218448 -0.232561)
					(end -0.34334 -1.279127)
					(width 0.2)
				)
				(gr_arc
					(start 1.255279 0.431435)
					(mid 0.152481 -0.169693)
					(end -0.436309 -1.279127)
					(width 0.2)
				)
				(gr_arc
					(start 1.253811 0.524161)
					(mid 0.087542 -0.105784)
					(end -0.529126 -1.279127)
					(width 0.2)
				)
				(gr_arc
					(start 1.275473 0.621136)
					(mid 0.0309 -0.033527)
					(end -0.621807 -1.279127)
					(width 0.2)
				)
				(gr_arc
					(start 1.263664 0.711602)
					(mid -0.037759 0.026651)
					(end -0.71437 -1.279127)
					(width 0.2)
				)
				(gr_arc
					(start 1.253435 0.802342)
					(mid -0.105837 0.087395)
					(end -0.806826 -1.279127)
					(width 0.2)
				)
				(gr_arc
					(start 1.267475 0.897258)
					(mid -0.165236 0.156885)
					(end -0.899187 -1.279127)
					(width 0.2)
				)
				(gr_arc
					(start 1.270645 0.990112)
					(mid -0.228522 0.222449)
					(end -0.991463 -1.279127)
					(width 0.2)
				)
				(gr_arc
					(start 1.266278 1.081674)
					(mid -0.294507 0.285313)
					(end -1.083663 -1.279127)
					(width 0.2)
				)
				(gr_line
					(start 1.279127 0.250195)
					(end 1.279127 1.083663)
					(width 0.2)
				)
				(gr_line
					(start -0.250195 -1.279127)
					(end -1.083663 -1.279127)
					(width 0.2)
				)
			)
		)
		(pad "" smd custom
			(at 1.7 1.7 270)
			(size 0.62 0.62)
			(layers "B.Paste")
			(thermal_bridge_angle 90)
			(options
				(clearance outline)
				(anchor circle)
			)
			(primitives
				(gr_arc
					(start 1.266786 0.24747)
					(mid 0.285453 -0.29439)
					(end -0.250195 -1.279127)
					(width 0.2)
				)
				(gr_arc
					(start 1.259603 0.339191)
					(mid 0.218448 -0.232561)
					(end -0.34334 -1.279127)
					(width 0.2)
				)
				(gr_arc
					(start 1.255279 0.431435)
					(mid 0.152481 -0.169693)
					(end -0.436309 -1.279127)
					(width 0.2)
				)
				(gr_arc
					(start 1.253811 0.524161)
					(mid 0.087542 -0.105784)
					(end -0.529126 -1.279127)
					(width 0.2)
				)
				(gr_arc
					(start 1.275473 0.621136)
					(mid 0.0309 -0.033527)
					(end -0.621807 -1.279127)
					(width 0.2)
				)
				(gr_arc
					(start 1.263664 0.711602)
					(mid -0.037759 0.026651)
					(end -0.71437 -1.279127)
					(width 0.2)
				)
				(gr_arc
					(start 1.253435 0.802342)
					(mid -0.105837 0.087395)
					(end -0.806826 -1.279127)
					(width 0.2)
				)
				(gr_arc
					(start 1.267475 0.897258)
					(mid -0.165236 0.156885)
					(end -0.899187 -1.279127)
					(width 0.2)
				)
				(gr_arc
					(start 1.270645 0.990112)
					(mid -0.228522 0.222449)
					(end -0.991463 -1.279127)
					(width 0.2)
				)
				(gr_arc
					(start 1.266278 1.081674)
					(mid -0.294507 0.285313)
					(end -1.083663 -1.279127)
					(width 0.2)
				)
				(gr_line
					(start 1.279127 0.250195)
					(end 1.279127 1.083663)
					(width 0.2)
				)
				(gr_line
					(start -0.250195 -1.279127)
					(end -1.083663 -1.279127)
					(width 0.2)
				)
			)
		)
		(pad "1" thru_hole circle
			(at 0 0 180)
			(size 6 6)
			(drill 3.7)
			(layers "*.Cu" "*.Mask")
			(remove_unused_layers no)
			(net 1 "GND")
			(pintype "passive")
		)
	)
	(gr_line
		(start 190.246 99.162)
		(end 115.748 99.162)
		(stroke
			(width 0.1)
			(type solid)
		)
		(layer "Edge.Cuts")
	)
	(gr_arc
		(start 190.246 39.162)
		(mid 190.422777 39.235223)
		(end 190.496 39.412)
		(stroke
			(width 0.1)
			(type solid)
		)
		(layer "Edge.Cuts")
	)
	(gr_line
		(start 115.696 39.162)
		(end 190.246 39.162)
		(stroke
			(width 0.1)
			(type solid)
		)
		(layer "Edge.Cuts")
	)
	(gr_line
		(start 115.498 98.912)
		(end 115.496 39.362)
		(stroke
			(width 0.1)
			(type solid)
		)
		(layer "Edge.Cuts")
	)
	(gr_arc
		(start 190.496 98.912)
		(mid 190.422777 99.088777)
		(end 190.246 99.162)
		(stroke
			(width 0.1)
			(type solid)
		)
		(layer "Edge.Cuts")
	)
	(gr_arc
		(start 115.496 39.362)
		(mid 115.554579 39.220579)
		(end 115.696 39.162)
		(stroke
			(width 0.1)
			(type solid)
		)
		(layer "Edge.Cuts")
	)
	(gr_line
		(start 190.496 39.412)
		(end 190.496 98.912)
		(stroke
			(width 0.1)
			(type solid)
		)
		(layer "Edge.Cuts")
	)
	(gr_arc
		(start 115.748 99.162)
		(mid 115.571223 99.088777)
		(end 115.498 98.912)
		(stroke
			(width 0.1)
			(type solid)
		)
		(layer "Edge.Cuts")
	)
	(gr_text "GMSL Deserializer\nRev. ${REVISION}	10/2025"
		(at 164.973 96.012 0)
		(layer "F.Cu")
		(effects
			(font
				(size 0.5 0.5)
				(thickness 0.125)
			)
			(justify left)
		)
	)
	(segment
		(start 149.668 72.582)
		(end 148.349 72.582)
		(width 0.187)
		(layer "F.Cu")
		(net 1)
	)
	(segment
		(start 175.768 69.088)
		(end 175.514 68.834)
		(width 0.187)
		(layer "F.Cu")
		(net 1)
	)
	(segment
		(start 126.703 83.866)
		(end 126.703 84.478347)
		(width 0.5)
		(layer "F.Cu")
		(net 1)
	)
	(segment
		(start 124.956 85.129)
		(end 126.543 85.129)
		(width 0.5)
		(layer "F.Cu")
		(net 1)
	)
	(segment
		(start 176.484 47.752)
		(end 175.514 47.752)
		(width 0.5)
		(layer "F.Cu")
		(net 1)
	)
	(segment
		(start 129.797 74.743)
		(end 129.797 74.292)
		(width 0.5)
		(layer "F.Cu")
		(net 1)
	)
	(segment
		(start 127.465 85.222)
		(end 126.9 85.222)
		(width 0.5)
		(layer "F.Cu")
		(net 1)
	)
	(segment
		(start 180.514 61.87)
		(end 180.514 61.06)
		(width 0.187)
		(layer "F.Cu")
		(net 1)
	)
	(segment
		(start 149.7598 72.136)
		(end 149.733 72.1628)
		(width 0.187)
		(layer "F.Cu")
		(net 1)
	)
	(segment
		(start 126.9 85.222)
		(end 126.448 85.222)
		(width 0.5)
		(layer "F.Cu")
		(net 1)
	)
	(segment
		(start 176.435 51.308)
		(end 175.26 51.308)
		(width 0.5)
		(layer "F.Cu")
		(net 1)
	)
	(segment
		(start 142.755747 97.782253)
		(end 142.748 97.79)
		(width 0.187)
		(layer "F.Cu")
		(net 1)
	)
	(segment
		(start 181.864 62.23)
		(end 181.864 61.6525)
		(width 0.187)
		(layer "F.Cu")
		(net 1)
	)
	(segment
		(start 185.1602 72.435)
		(end 185.2168 72.4916)
		(width 0.187)
		(layer "F.Cu")
		(net 1)
	)
	(segment
		(start 185.137 76.933)
		(end 185.166 76.962)
		(width 0.187)
		(layer "F.Cu")
		(net 1)
	)
	(segment
		(start 131.725 93.815)
		(end 131.725 93.759)
		(width 0.5)
		(layer "F.Cu")
		(net 1)
	)
	(segment
		(start 175.514 68.834)
		(end 175.514 68.326)
		(width 0.187)
		(layer "F.Cu")
		(net 1)
	)
	(segment
		(start 128.198 75.034)
		(end 129.506 75.034)
		(width 0.5)
		(layer "F.Cu")
		(net 1)
	)
	(segment
		(start 180.317 59.205)
		(end 180.317 58.674)
		(width 0.187)
		(layer "F.Cu")
		(net 1)
	)
	(segment
		(start 179.6914 59.8306)
		(end 180.317 59.205)
		(width 0.187)
		(layer "F.Cu")
		(net 1)
	)
	(segment
		(start 175.26 53.34)
		(end 175.514 53.594)
		(width 0.5)
		(layer "F.Cu")
		(net 1)
	)
	(segment
		(start 131.528 93.562)
		(end 131.98 93.562)
		(width 0.5)
		(layer "F.Cu")
		(net 1)
	)
	(segment
		(start 139.5476 78.496)
		(end 139.5476 78.8416)
		(width 0.187)
		(layer "F.Cu")
		(net 1)
	)
	(segment
		(start 133.472 93.655)
		(end 131.885 93.655)
		(width 0.5)
		(layer "F.Cu")
		(net 1)
	)
	(segment
		(start 186.497 56.261)
		(end 185.801 56.261)
		(width 0.5)
		(layer "F.Cu")
		(net 1)
	)
	(segment
		(start 128.198 77.713031)
		(end 128.198 77.32)
		(width 0.5)
		(layer "F.Cu")
		(net 1)
	)
	(segment
		(start 130.152 73.937)
		(end 130.413 73.937)
		(width 0.5)
		(layer "F.Cu")
		(net 1)
	)
	(segment
		(start 146.994 67.922)
		(end 146.994 67.0325)
		(width 0.5)
		(layer "F.Cu")
		(net 1)
	)
	(segment
		(start 179.644 67.564)
		(end 179.705 67.503)
		(width 0.187)
		(layer "F.Cu")
		(net 1)
	)
	(segment
		(start 125.126 74.502)
		(end 124.896 74.272)
		(width 0.5)
		(layer "F.Cu")
		(net 1)
	)
	(segment
		(start 129.831 93.562)
		(end 129.794 93.599)
		(width 0.5)
		(layer "F.Cu")
		(net 1)
	)
	(segment
		(start 126.543 85.129)
		(end 126.703 84.969)
		(width 0.5)
		(layer "F.Cu")
		(net 1)
	)
	(segment
		(start 184.077 55.9594)
		(end 184.0992 55.9816)
		(width 0.187)
		(layer "F.Cu")
		(net 1)
	)
	(segment
		(start 158.424 67.922)
		(end 158.424 67.032)
		(width 0.5)
		(layer "F.Cu")
		(net 1)
	)
	(segment
		(start 143.692 72.4704)
		(end 143.6116 72.39)
		(width 0.187)
		(layer "F.Cu")
		(net 1)
	)
	(segment
		(start 150.85052 77.254835)
		(end 150.85052 77.24148)
		(width 0.3)
		(layer "F.Cu")
		(net 1)
	)
	(segment
		(start 128.482 83.862)
		(end 126.674 83.862)
		(width 0.5)
		(layer "F.Cu")
		(net 1)
	)
	(segment
		(start 146.049 70.783)
		(end 144.6945 70.783)
		(width 0.125)
		(layer "F.Cu")
		(net 1)
	)
	(segment
		(start 135.564 67.0404)
		(end 135.564 67.922)
		(width 0.5)
		(layer "F.Cu")
		(net 1)
	)
	(segment
		(start 178.6585 67.31)
		(end 178.6585 67.2135)
		(width 0.187)
		(layer "F.Cu")
		(net 1)
	)
	(segment
		(start 123.571 67.9205)
		(end 123.571 67.032)
		(width 0.5)
		(layer "F.Cu")
		(net 1)
	)
	(segment
		(start 130.963 93.562)
		(end 129.831 93.562)
		(width 0.5)
		(layer "F.Cu")
		(net 1)
	)
	(segment
		(start 144.6945 70.783)
		(end 144.653 70.8245)
		(width 0.125)
		(layer "F.Cu")
		(net 1)
	)
	(segment
		(start 166.183 56.3519)
		(end 166.183 55.418)
		(width 0.187)
		(layer "F.Cu")
		(net 1)
	)
	(segment
		(start 178.9125 67.564)
		(end 179.644 67.564)
		(width 0.187)
		(layer "F.Cu")
		(net 1)
	)
	(segment
		(start 131.725 93.759)
		(end 131.528 93.562)
		(width 0.5)
		(layer "F.Cu")
		(net 1)
	)
	(segment
		(start 178.9176 59.8306)
		(end 179.6914 59.8306)
		(width 0.187)
		(layer "F.Cu")
		(net 1)
	)
	(segment
		(start 170.307 56.515)
		(end 170.307 56.896)
		(width 0.187)
		(layer "F.Cu")
		(net 1)
	)
	(segment
		(start 143.692 73.175)
		(end 143.692 72.4704)
		(width 0.187)
		(layer "F.Cu")
		(net 1)
	)
	(segment
		(start 178.375 51.732)
		(end 177.9192 51.732)
		(width 0.187)
		(layer "F.Cu")
		(net 1)
	)
	(segment
		(start 157.154 67.922)
		(end 157.154 67.032)
		(width 0.5)
		(layer "F.Cu")
		(net 1)
	)
	(segment
		(start 125.658 74.502)
		(end 125.126 74.502)
		(width 0.5)
		(layer "F.Cu")
		(net 1)
	)
	(segment
		(start 144.296 71.501)
		(end 144.653 71.144)
		(width 0.187)
		(layer "F.Cu")
		(net 1)
	)
	(segment
		(start 128.198 75.034)
		(end 126.19 75.034)
		(width 0.5)
		(layer "F.Cu")
		(net 1)
	)
	(segment
		(start 178.6585 67.31)
		(end 178.9125 67.564)
		(width 0.187)
		(layer "F.Cu")
		(net 1)
	)
	(segment
		(start 188.386 51.5)
		(end 188.976 51.5)
		(width 0.5)
		(layer "F.Cu")
		(net 1)
	)
	(segment
		(start 171.854 60.556)
		(end 171.2976 61.1124)
		(width 0.187)
		(layer "F.Cu")
		(net 1)
	)
	(segment
		(start 183.886 72.435)
		(end 185.1602 72.435)
		(width 0.187)
		(layer "F.Cu")
		(net 1)
	)
	(segment
		(start 128.474978 77.990009)
		(end 128.198 77.713031)
		(width 0.5)
		(layer "F.Cu")
		(net 1)
	)
	(segment
		(start 178.816 49.784)
		(end 178.816 50.542)
		(width 0.187)
		(layer "F.Cu")
		(net 1)
	)
	(segment
		(start 182.132 59.7135)
		(end 183.1105 59.7135)
		(width 0.187)
		(layer "F.Cu")
		(net 1)
	)
	(segment
		(start 176.45 61.568)
		(end 176.509 61.509)
		(width 0.187)
		(layer "F.Cu")
		(net 1)
	)
	(segment
		(start 169.902 57.301)
		(end 169.431 57.301)
		(width 0.187)
		(layer "F.Cu")
		(net 1)
	)
	(segment
		(start 143.891 71.501)
		(end 144.296 71.501)
		(width 0.187)
		(layer "F.Cu")
		(net 1)
	)
	(segment
		(start 149.733 72.1628)
		(end 149.733 72.517)
		(width 0.187)
		(layer "F.Cu")
		(net 1)
	)
	(segment
		(start 150.5712 72.136)
		(end 149.7598 72.136)
		(width 0.187)
		(layer "F.Cu")
		(net 1)
	)
	(segment
		(start 153.454147 79.209853)
		(end 153.906156 78.757844)
		(width 0.187)
		(layer "F.Cu")
		(net 1)
	)
	(segment
		(start 168.977 59.736)
		(end 168.977 60.639)
		(width 0.187)
		(layer "F.Cu")
		(net 1)
	)
	(segment
		(start 126.703 84.969)
		(end 126.703 85.025)
		(width 0.5)
		(layer "F.Cu")
		(net 1)
	)
	(segment
		(start 134.294 67.032)
		(end 134.294 67.922)
		(width 0.5)
		(layer "F.Cu")
		(net 1)
	)
	(segment
		(start 187.888 52.252)
		(end 187.888 51.998)
		(width 0.5)
		(layer "F.Cu")
		(net 1)
	)
	(segment
		(start 186.36 51.1778)
		(end 186.36 51.74)
		(width 0.187)
		(layer "F.Cu")
		(net 1)
	)
	(segment
		(start 129.506 75.034)
		(end 129.797 74.743)
		(width 0.5)
		(layer "F.Cu")
		(net 1)
	)
	(segment
		(start 179.498 61.846)
		(end 179.498 61.06)
		(width 0.187)
		(layer "F.Cu")
		(net 1)
	)
	(segment
		(start 183.886 81.433)
		(end 185.2162 81.433)
		(width 0.187)
		(layer "F.Cu")
		(net 1)
	)
	(segment
		(start 186.69 55.499)
		(end 186.841 55.499)
		(width 0.5)
		(layer "F.Cu")
		(net 1)
	)
	(segment
		(start 185.166 55.626)
		(end 185.166 54.864)
		(width 0.187)
		(layer "F.Cu")
		(net 1)
	)
	(segment
		(start 138.722053 73.952053)
		(end 138.010947 73.240947)
		(width 0.2)
		(layer "F.Cu")
		(net 1)
	)
	(segment
		(start 178.285 59.198)
		(end 178.285 58.674)
		(width 0.187)
		(layer "F.Cu")
		(net 1)
	)
	(segment
		(start 153.906156 78.757844)
		(end 153.906156 78.618453)
		(width 0.187)
		(layer "F.Cu")
		(net 1)
	)
	(segment
		(start 178.9176 60.3504)
		(end 178.9176 59.8306)
		(width 0.187)
		(layer "F.Cu")
		(net 1)
	)
	(segment
		(start 139.5476 78.8416)
		(end 139.865053 79.159053)
		(width 0.187)
		(layer "F.Cu")
		(net 1)
	)
	(segment
		(start 178.6585 67.2135)
		(end 178.054 66.609)
		(width 0.187)
		(layer "F.Cu")
		(net 1)
	)
	(segment
		(start 121.087 81.153)
		(end 121.087 80.32)
		(width 0.5)
		(layer "F.Cu")
		(net 1)
	)
	(segment
		(start 150.85052 77.254835)
		(end 150.24948 77.855875)
		(width 0.125)
		(layer "F.Cu")
		(net 1)
	)
	(segment
		(start 144.653 70.8245)
		(end 144.653 71.144)
		(width 0.125)
		(layer "F.Cu")
		(net 1)
	)
	(segment
		(start 186.841 55.499)
		(end 187.222 55.118)
		(width 0.5)
		(layer "F.Cu")
		(net 1)
	)
	(segment
		(start 183.886 76.933)
		(end 185.137 76.933)
		(width 0.187)
		(layer "F.Cu")
		(net 1)
	)
	(segment
		(start 118.664 83.612)
		(end 118.11 83.058)
		(width 0.5)
		(layer "F.Cu")
		(net 1)
	)
	(segment
		(start 145.724 67.922)
		(end 145.724 67.0325)
		(width 0.5)
		(layer "F.Cu")
		(net 1)
	)
	(segment
		(start 171.2976 61.1124)
		(end 171.8042 61.619)
		(width 0.187)
		(layer "F.Cu")
		(net 1)
	)
	(segment
		(start 179.705 64.135)
		(end 179.705 63.815)
		(width 0.187)
		(layer "F.Cu")
		(net 1)
	)
	(segment
		(start 176.484 47.752)
		(end 176.484 48.589)
		(width 0.5)
		(layer "F.Cu")
		(net 1)
	)
	(segment
		(start 177.546 47.752)
		(end 176.484 47.752)
		(width 0.5)
		(layer "F.Cu")
		(net 1)
	)
	(segment
		(start 131.885 93.655)
		(end 131.725 93.815)
		(width 0.5)
		(layer "F.Cu")
		(net 1)
	)
	(segment
		(start 137.414 98.298)
		(end 137.414 97.728)
		(width 0.5)
		(layer "F.Cu")
		(net 1)
	)
	(segment
		(start 188.523 52.252)
		(end 188.649 52.378)
		(width 0.187)
		(layer "F.Cu")
		(net 1)
	)
	(segment
		(start 185.1638 78.433)
		(end 185.2168 78.486)
		(width 0.187)
		(layer "F.Cu")
		(net 1)
	)
	(segment
		(start 136.318 76.3)
		(end 136.318 77.316)
		(width 0.5)
		(layer "F.Cu")
		(net 1)
	)
	(segment
		(start 174.461 62.206)
		(end 173.91 62.206)
		(width 0.187)
		(layer "F.Cu")
		(net 1)
	)
	(segment
		(start 121.087 80.32)
		(end 121.031 80.264)
		(width 0.5)
		(layer "F.Cu")
		(net 1)
	)
	(segment
		(start 188.649 52.378)
		(end 188.649 52.8248)
		(width 0.187)
		(layer "F.Cu")
		(net 1)
	)
	(segment
		(start 176.509 61.509)
		(end 176.509 60.436)
		(width 0.187)
		(layer "F.Cu")
		(net 1)
	)
	(segment
		(start 179.324 64.516)
		(end 179.705 64.135)
		(width 0.187)
		(layer "F.Cu")
		(net 1)
	)
	(segment
		(start 176.337 69.088)
		(end 175.768 69.088)
		(width 0.187)
		(layer "F.Cu")
		(net 1)
	)
	(segment
		(start 128.198 76.385)
		(end 128.198 75.034)
		(width 0.5)
		(layer "F.Cu")
		(net 1)
	)
	(segment
		(start 126.178 75.022)
		(end 125.658 74.502)
		(width 0.5)
		(layer "F.Cu")
		(net 1)
	)
	(segment
		(start 166.243 56.4119)
		(end 166.183 56.3519)
		(width 0.187)
		(layer "F.Cu")
		(net 1)
	)
	(segment
		(start 178.9176 59.8306)
		(end 178.285 59.198)
		(width 0.187)
		(layer "F.Cu")
		(net 1)
	)
	(segment
		(start 186.36 51.74)
		(end 186.872 52.252)
		(width 0.187)
		(layer "F.Cu")
		(net 1)
	)
	(segment
		(start 130.48 78.16)
		(end 128.644969 78.16)
		(width 0.5)
		(layer "F.Cu")
		(net 1)
	)
	(segment
		(start 126.703 84.478347)
		(end 126.703 84.969)
		(width 0.5)
		(layer "F.Cu")
		(net 1)
	)
	(segment
		(start 118.664 84.328)
		(end 118.664 83.612)
		(width 0.5)
		(layer "F.Cu")
		(net 1)
	)
	(segment
		(start 187.888 51.998)
		(end 188.386 51.5)
		(width 0.5)
		(layer "F.Cu")
		(net 1)
	)
	(segment
		(start 185.2162 81.433)
		(end 185.2168 81.4324)
		(width 0.187)
		(layer "F.Cu")
		(net 1)
	)
	(segment
		(start 129.797 74.292)
		(end 130.152 73.937)
		(width 0.5)
		(layer "F.Cu")
		(net 1)
	)
	(segment
		(start 126.19 75.034)
		(end 126.178 75.022)
		(width 0.5)
		(layer "F.Cu")
		(net 1)
	)
	(segment
		(start 183.1105 59.7135)
		(end 183.134 59.69)
		(width 0.187)
		(layer "F.Cu")
		(net 1)
	)
	(segment
		(start 174.69 53.34)
		(end 175.26 53.34)
		(width 0.5)
		(layer "F.Cu")
		(net 1)
	)
	(segment
		(start 142.757748 97.782253)
		(end 142.755747 97.782253)
		(width 0.187)
		(layer "F.Cu")
		(net 1)
	)
	(segment
		(start 183.886 79.933)
		(end 185.1906 79.933)
		(width 0.187)
		(layer "F.Cu")
		(net 1)
	)
	(segment
		(start 178.816 60.452)
		(end 178.9176 60.3504)
		(width 0.187)
		(layer "F.Cu")
		(net 1)
	)
	(segment
		(start 122.301 67.9205)
		(end 122.301 67.032)
		(width 0.5)
		(layer "F.Cu")
		(net 1)
	)
	(segment
		(start 183.886 70.934)
		(end 185.1324 70.934)
		(width 0.187)
		(layer "F.Cu")
		(net 1)
	)
	(segment
		(start 170.966 50.496)
		(end 170.97 50.5)
		(width 0.5)
		(layer "F.Cu")
		(net 1)
	)
	(segment
		(start 175.4898 48.589)
		(end 176.484 48.589)
		(width 0.5)
		(layer "F.Cu")
		(net 1)
	)
	(segment
		(start 130.963 93.562)
		(end 131.528 93.562)
		(width 0.5)
		(layer "F.Cu")
		(net 1)
	)
	(segment
		(start 177.5194 48.589)
		(end 176.484 48.589)
		(width 0.5)
		(layer "F.Cu")
		(net 1)
	)
	(segment
		(start 128.198 77.32)
		(end 128.198 76.385)
		(width 0.5)
		(layer "F.Cu")
		(net 1)
	)
	(segment
		(start 126.703 85.025)
		(end 126.9 85.222)
		(width 0.5)
		(layer "F.Cu")
		(net 1)
	)
	(segment
		(start 183.886 78.433)
		(end 185.1638 78.433)
		(width 0.187)
		(layer "F.Cu")
		(net 1)
	)
	(segment
		(start 154.520947 74.333053)
		(end 155.194 73.66)
		(width 0.2)
		(layer "F.Cu")
		(net 1)
	)
	(segment
		(start 177.9192 51.732)
		(end 177.546 51.3588)
		(width 0.187)
		(layer "F.Cu")
		(net 1)
	)
	(segment
		(start 153.758947 73.571053)
		(end 154.432 72.898)
		(width 0.2)
		(layer "F.Cu")
		(net 1)
	)
	(segment
		(start 139.484053 73.190053)
		(end 138.772947 72.478947)
		(width 0.2)
		(layer "F.Cu")
		(net 1)
	)
	(segment
		(start 141.764272 76.242272)
		(end 142.89852 77.37652)
		(width 0.125)
		(layer "F.Cu")
		(net 1)
	)
	(segment
		(start 170.307 56.515)
		(end 170.03 56.238)
		(width 0.187)
		(layer "F.Cu")
		(net 1)
	)
	(segment
		(start 170.03 56.238)
		(end 169.418 56.238)
		(width 0.187)
		(layer "F.Cu")
		(net 1)
	)
	(segment
		(start 150.85052 77.24148)
		(end 151.384 76.708)
		(width 0.3)
		(layer "F.Cu")
		(net 1)
	)
	(segment
		(start 141.754736 76.242272)
		(end 141.764272 76.242272)
		(width 0.125)
		(layer "F.Cu")
		(net 1)
	)
	(segment
		(start 186.872 52.252)
		(end 188.523 52.252)
		(width 0.187)
		(layer "F.Cu")
		(net 1)
	)
	(segment
		(start 168.977 60.639)
		(end 168.656 60.96)
		(width 0.187)
		(layer "F.Cu")
		(net 1)
	)
	(segment
		(start 170.966 49.808)
		(end 170.966 50.496)
		(width 0.5)
		(layer "F.Cu")
		(net 1)
	)
	(segment
		(start 137.414 97.728)
		(end 137.313 97.627)
		(width 0.5)
		(layer "F.Cu")
		(net 1)
	)
	(segment
		(start 175.515 49.403)
		(end 177.547 49.403)
		(width 0.5)
		(layer "F.Cu")
		(net 1)
	)
	(segment
		(start 184.077 55.2498)
		(end 184.077 55.9594)
		(width 0.187)
		(layer "F.Cu")
		(net 1)
	)
	(segment
		(start 185.1906 79.933)
		(end 185.2168 79.9592)
		(width 0.187)
		(layer "F.Cu")
		(net 1)
	)
	(segment
		(start 172.212 60.556)
		(end 171.854 60.556)
		(width 0.187)
		(layer "F.Cu")
		(net 1)
	)
	(segment
		(start 171.8042 61.619)
		(end 172.212 61.619)
		(width 0.187)
		(layer "F.Cu")
		(net 1)
	)
	(segment
		(start 128.644969 78.16)
		(end 128.474978 77.990009)
		(width 0.5)
		(layer "F.Cu")
		(net 1)
	)
	(segment
		(start 131.725 94.918)
		(end 131.725 93.815)
		(width 0.5)
		(layer "F.Cu")
		(net 1)
	)
	(segment
		(start 149.733 72.517)
		(end 149.668 72.582)
		(width 0.187)
		(layer "F.Cu")
		(net 1)
	)
	(segment
		(start 170.307 56.896)
		(end 169.902 57.301)
		(width 0.187)
		(layer "F.Cu")
		(net 1)
	)
	(segment
		(start 174.691 61.976)
		(end 174.461 62.206)
		(width 0.187)
		(layer "F.Cu")
		(net 1)
	)
	(segment
		(start 128.524 83.82)
		(end 128.482 83.862)
		(width 0.5)
		(layer "F.Cu")
		(net 1)
	)
	(segment
		(start 185.1324 70.934)
		(end 185.166 70.9676)
		(width 0.187)
		(layer "F.Cu")
		(net 1)
	)
	(segment
		(start 140.716 94.488)
		(end 139.677 94.488)
		(width 0.5)
		(layer "F.Cu")
		(net 1)
	)
	(via
		(at 146.486 80.876)
		(size 0.6)
		(drill 0.35)
		(layers "F.Cu" "B.Cu")
		(net 1)
	)
	(via
		(at 151.12 86.57)
		(size 0.6)
		(drill 0.35)
		(layers "F.Cu" "B.Cu")
		(free yes)
		(net 1)
	)
	(via
		(at 144.39 92.75)
		(size 0.6)
		(drill 0.35)
		(layers "F.Cu" "B.Cu")
		(free yes)
		(net 1)
	)
	(via
		(at 182.626 40.386)
		(size 0.6)
		(drill 0.35)
		(layers "F.Cu" "B.Cu")
		(free yes)
		(net 1)
	)
	(via
		(at 145.796 52.832)
		(size 0.6)
		(drill 0.35)
		(layers "F.Cu" "B.Cu")
		(free yes)
		(net 1)
	)
	(via
		(at 145.442314 73.882393)
		(size 0.6)
		(drill 0.35)
		(layers "F.Cu" "B.Cu")
		(free yes)
		(net 1)
	)
	(via
		(at 138.829 83.929)
		(size 0.6)
		(drill 0.35)
		(layers "F.Cu" "B.Cu")
		(free yes)
		(net 1)
	)
	(via
		(at 186.7916 58.1152)
		(size 0.6)
		(drill 0.35)
		(layers "F.Cu" "B.Cu")
		(net 1)
	)
	(via
		(at 148.772 81.638)
		(size 0.6)
		(drill 0.35)
		(layers "F.Cu" "B.Cu")
		(net 1)
	)
	(via
		(at 189.65 98.36)
		(size 0.6)
		(drill 0.35)
		(layers "F.Cu" "B.Cu")
		(free yes)
		(net 1)
	)
	(via
		(at 146.56 79.3)
		(size 0.6)
		(drill 0.35)
		(layers "F.Cu" "B.Cu")
		(net 1)
	)
	(via
		(at 129.54 89.662)
		(size 0.6)
		(drill 0.35)
		(layers "F.Cu" "B.Cu")
		(free yes)
		(net 1)
	)
	(via
		(at 184.7088 86.5124)
		(size 0.6)
		(drill 0.35)
		(layers "F.Cu" "B.Cu")
		(net 1)
	)
	(via
		(at 117.094 61.722)
		(size 0.6)
		(drill 0.35)
		(layers "F.Cu" "B.Cu")
		(free yes)
		(net 1)
	)
	(via
		(at 170.67 90.31)
		(size 0.6)
		(drill 0.35)
		(layers "F.Cu" "B.Cu")
		(free yes)
		(net 1)
	)
	(via
		(at 177.8 44.45)
		(size 0.6)
		(drill 0.35)
		(layers "F.Cu" "B.Cu")
		(free yes)
		(net 1)
	)
	(via
		(at 185.166 55.626)
		(size 0.6)
		(drill 0.35)
		(layers "F.Cu" "B.Cu")
		(free yes)
		(net 1)
	)
	(via
		(at 155.194 73.66)
		(size 0.6)
		(drill 0.35)
		(layers "F.Cu" "B.Cu")
		(net 1)
	)
	(via
		(at 171.2976 61.1124)
		(size 0.6)
		(drill 0.35)
		(layers "F.Cu" "B.Cu")
		(net 1)
	)
	(via
		(at 174.05 69.66)
		(size 0.6)
		(drill 0.35)
		(layers "F.Cu" "B.Cu")
		(free yes)
		(net 1)
	)
	(via
		(at 145.724 81.638)
		(size 0.6)
		(drill 0.35)
		(layers "F.Cu" "B.Cu")
		(net 1)
	)
	(via
		(at 145.724 83.162)
		(size 0.6)
		(drill 0.35)
		(layers "F.Cu" "B.Cu")
		(net 1)
	)
	(via
		(at 118.872 88.138)
		(size 0.6)
		(drill 0.35)
		(layers "F.Cu" "B.Cu")
		(free yes)
		(net 1)
	)
	(via
		(at 122.301 67.9205)
		(size 0.6)
		(drill 0.35)
		(layers "F.Cu" "B.Cu")
		(free yes)
		(net 1)
	)
	(via
		(at 177.547 49.403)
		(size 0.6)
		(drill 0.35)
		(layers "F.Cu" "B.Cu")
		(net 1)
	)
	(via
		(at 172.46 71.37)
		(size 0.6)
		(drill 0.35)
		(layers "F.Cu" "B.Cu")
		(free yes)
		(net 1)
	)
	(via
		(at 118.11 79.502)
		(size 0.6)
		(drill 0.35)
		(layers "F.Cu" "B.Cu")
		(free yes)
		(net 1)
	)
	(via
		(at 117.094 66.294)
		(size 0.6)
		(drill 0.35)
		(layers "F.Cu" "B.Cu")
		(free yes)
		(net 1)
	)
	(via
		(at 162.02 76.6)
		(size 0.6)
		(drill 0.35)
		(layers "F.Cu" "B.Cu")
		(free yes)
		(net 1)
	)
	(via
		(at 151.384 76.708)
		(size 0.6)
		(drill 0.35)
		(layers "F.Cu" "B.Cu")
		(net 1)
	)
	(via
		(at 175.91 81.54)
		(size 0.6)
		(drill 0.35)
		(layers "F.Cu" "B.Cu")
		(free yes)
		(net 1)
	)
	(via
		(at 175.4898 48.589)
		(size 0.6)
		(drill 0.35)
		(layers "F.Cu" "B.Cu")
		(free yes)
		(net 1)
	)
	(via
		(at 147.248 83.162)
		(size 0.6)
		(drill 0.35)
		(layers "F.Cu" "B.Cu")
		(net 1)
	)
	(via
		(at 186.944 84.582)
		(size 0.6)
		(drill 0.35)
		(layers "F.Cu" "B.Cu")
		(free yes)
		(net 1)
	)
	(via
		(at 189.95 75.23)
		(size 0.6)
		(drill 0.35)
		(layers "F.Cu" "B.Cu")
		(free yes)
		(net 1)
	)
	(via
		(at 124.896 74.272)
		(size 0.6)
		(drill 0.35)
		(layers "F.Cu" "B.Cu")
		(free yes)
		(net 1)
	)
	(via
		(at 174.75 79.73)
		(size 0.6)
		(drill 0.35)
		(layers "F.Cu" "B.Cu")
		(free yes)
		(net 1)
	)
	(via
		(at 130.48 78.16)
		(size 0.6)
		(drill 0.35)
		(layers "F.Cu" "B.Cu")
		(free yes)
		(net 1)
	)
	(via
		(at 128.524 83.82)
		(size 0.6)
		(drill 0.35)
		(layers "F.Cu" "B.Cu")
		(free yes)
		(net 1)
	)
	(via
		(at 175.26 51.308)
		(size 0.6)
		(drill 0.35)
		(layers "F.Cu" "B.Cu")
		(net 1)
	)
	(via
		(at 145.724 67.922)
		(size 0.6)
		(drill 0.35)
		(layers "F.Cu" "B.Cu")
		(free yes)
		(net 1)
	)
	(via
		(at 172.51 85.09)
		(size 0.6)
		(drill 0.35)
		(layers "F.Cu" "B.Cu")
		(free yes)
		(net 1)
	)
	(via
		(at 135.564 67.922)
		(size 0.6)
		(drill 0.35)
		(layers "F.Cu" "B.Cu")
		(free yes)
		(net 1)
	)
	(via
		(at 186.7408 88.2396)
		(size 0.6)
		(drill 0.35)
		(layers "F.Cu" "B.Cu")
		(net 1)
	)
	(via
		(at 159.3 79.4)
		(size 0.6)
		(drill 0.35)
		(layers "F.Cu" "B.Cu")
		(free yes)
		(net 1)
	)
	(via
		(at 172.12 78.84)
		(size 0.6)
		(drill 0.35)
		(layers "F.Cu" "B.Cu")
		(free yes)
		(net 1)
	)
	(via
		(at 178.6585 67.31)
		(size 0.6)
		(drill 0.35)
		(layers "F.Cu" "B.Cu")
		(net 1)
	)
	(via
		(at 166.36 73.79)
		(size 0.6)
		(drill 0.35)
		(layers "F.Cu" "B.Cu")
		(free yes)
		(net 1)
	)
	(via
		(at 165.48 86.16)
		(size 0.6)
		(drill 0.35)
		(layers "F.Cu" "B.Cu")
		(free yes)
		(net 1)
	)
	(via
		(at 186.7408 59.7916)
		(size 0.6)
		(drill 0.35)
		(layers "F.Cu" "B.Cu")
		(net 1)
	)
	(via
		(at 166.243 56.4119)
		(size 0.6)
		(drill 0.35)
		(layers "F.Cu" "B.Cu")
		(free yes)
		(net 1)
	)
	(via
		(at 187.198 89.916)
		(size 0.6)
		(drill 0.35)
		(layers "F.Cu" "B.Cu")
		(free yes)
		(net 1)
	)
	(via
		(at 167.32 73.98)
		(size 0.6)
		(drill 0.35)
		(layers "F.Cu" "B.Cu")
		(free yes)
		(net 1)
	)
	(via
		(at 139.090922 84.691012)
		(size 0.6)
		(drill 0.35)
		(layers "F.Cu" "B.Cu")
		(free yes)
		(net 1)
	)
	(via
		(at 148.01 82.4)
		(size 0.6)
		(drill 0.35)
		(layers "F.Cu" "B.Cu")
		(net 1)
	)
	(via
		(at 157.154 67.922)
		(size 0.6)
		(drill 0.35)
		(layers "F.Cu" "B.Cu")
		(free yes)
		(net 1)
	)
	(via
		(at 140.57 95.69)
		(size 0.6)
		(drill 0.35)
		(layers "F.Cu" "B.Cu")
		(free yes)
		(net 1)
	)
	(via
		(at 179.07 40.0812)
		(size 0.6)
		(drill 0.35)
		(layers "F.Cu" "B.Cu")
		(net 1)
	)
	(via
		(at 167.16 78.47)
		(size 0.6)
		(drill 0.35)
		(layers "F.Cu" "B.Cu")
		(free yes)
		(net 1)
	)
	(via
		(at 121.92 62.738)
		(size 0.6)
		(drill 0.35)
		(layers "F.Cu" "B.Cu")
		(free yes)
		(net 1)
	)
	(via
		(at 116.84 97.79)
		(size 0.6)
		(drill 0.35)
		(layers "F.Cu" "B.Cu")
		(free yes)
		(net 1)
	)
	(via
		(at 138.938 79.1464)
		(size 0.6)
		(drill 0.35)
		(layers "F.Cu" "B.Cu")
		(free yes)
		(net 1)
	)
	(via
		(at 186.69 55.499)
		(size 0.6)
		(drill 0.35)
		(layers "F.Cu" "B.Cu")
		(net 1)
	)
	(via
		(at 188.214 48.514)
		(size 0.6)
		(drill 0.35)
		(layers "F.Cu" "B.Cu")
		(free yes)
		(net 1)
	)
	(via
		(at 147.94 88.45)
		(size 0.6)
		(drill 0.35)
		(layers "F.Cu" "B.Cu")
		(free yes)
		(net 1)
	)
	(via
		(at 135.54 86.65)
		(size 0.6)
		(drill 0.35)
		(layers "F.Cu" "B.Cu")
		(free yes)
		(net 1)
	)
	(via
		(at 184.0992 55.9816)
		(size 0.6)
		(drill 0.35)
		(layers "F.Cu" "B.Cu")
		(free yes)
		(net 1)
	)
	(via
		(at 146.486 82.4)
		(size 0.6)
		(drill 0.35)
		(layers "F.Cu" "B.Cu")
		(net 1)
	)
	(via
		(at 144.962 80.876)
		(size 0.6)
		(drill 0.35)
		(layers "F.Cu" "B.Cu")
		(net 1)
	)
	(via
		(at 133.24 88.21)
		(size 0.6)
		(drill 0.35)
		(layers "F.Cu" "B.Cu")
		(net 1)
	)
	(via
		(at 119.126 93.726)
		(size 0.6)
		(drill 0.35)
		(layers "F.Cu" "B.Cu")
		(free yes)
		(net 1)
	)
	(via
		(at 185.166 76.962)
		(size 0.6)
		(drill 0.35)
		(layers "F.Cu" "B.Cu")
		(net 1)
	)
	(via
		(at 168.78 89.02)
		(size 0.6)
		(drill 0.35)
		(layers "F.Cu" "B.Cu")
		(free yes)
		(net 1)
	)
	(via
		(at 176.42 78.1)
		(size 0.6)
		(drill 0.35)
		(layers "F.Cu" "B.Cu")
		(free yes)
		(net 1)
	)
	(via
		(at 183.134 59.69)
		(size 0.6)
		(drill 0.35)
		(layers "F.Cu" "B.Cu")
		(net 1)
	)
	(via
		(at 169.78 78.9)
		(size 0.6)
		(drill 0.35)
		(layers "F.Cu" "B.Cu")
		(free yes)
		(net 1)
	)
	(via
		(at 185.801 56.261)
		(size 0.6)
		(drill 0.35)
		(layers "F.Cu" "B.Cu")
		(net 1)
	)
	(via
		(at 159.3 77.06)
		(size 0.6)
		(drill 0.35)
		(layers "F.Cu" "B.Cu")
		(free yes)
		(net 1)
	)
	(via
		(at 165.5 84)
		(size 0.6)
		(drill 0.35)
		(layers "F.Cu" "B.Cu")
		(free yes)
		(net 1)
	)
	(via
		(at 143.8 95.06)
		(size 0.6)
		(drill 0.35)
		(layers "F.Cu" "B.Cu")
		(free yes)
		(net 1)
	)
	(via
		(at 154.813 57.404)
		(size 0.6)
		(drill 0.35)
		(layers "F.Cu" "B.Cu")
		(free yes)
		(net 1)
	)
	(via
		(at 128.198 77.32)
		(size 0.6)
		(drill 0.35)
		(layers "F.Cu" "B.Cu")
		(net 1)
	)
	(via
		(at 138.010947 73.240947)
		(size 0.6)
		(drill 0.35)
		(layers "F.Cu" "B.Cu")
		(net 1)
	)
	(via
		(at 123.571 67.9205)
		(size 0.6)
		(drill 0.35)
		(layers "F.Cu" "B.Cu")
		(free yes)
		(net 1)
	)
	(via
		(at 187.888 52.252)
		(size 0.6)
		(drill 0.35)
		(layers "F.Cu" "B.Cu")
		(free yes)
		(net 1)
	)
	(via
		(at 139.9 97.1)
		(size 0.6)
		(drill 0.35)
		(layers "F.Cu" "B.Cu")
		(free yes)
		(net 1)
	)
	(via
		(at 138.772947 72.478947)
		(size 0.6)
		(drill 0.35)
		(layers "F.Cu" "B.Cu")
		(net 1)
	)
	(via
		(at 134.239 52.832)
		(size 0.6)
		(drill 0.35)
		(layers "F.Cu" "B.Cu")
		(free yes)
		(net 1)
	)
	(via
		(at 135.636 70.104)
		(size 0.6)
		(drill 0.35)
		(layers "F.Cu" "B.Cu")
		(free yes)
		(net 1)
	)
	(via
		(at 174.6 83.4)
		(size 0.6)
		(drill 0.35)
		(layers "F.Cu" "B.Cu")
		(free yes)
		(net 1)
	)
	(via
		(at 181.356 96.012)
		(size 0.6)
		(drill 0.35)
		(layers "F.Cu" "B.Cu")
		(free yes)
		(net 1)
	)
	(via
		(at 144.962 82.4)
		(size 0.6)
		(drill 0.35)
		(layers "F.Cu" "B.Cu")
		(net 1)
	)
	(via
		(at 154.432 72.898)
		(size 0.6)
		(drill 0.35)
		(layers "F.Cu" "B.Cu")
		(net 1)
	)
	(via
		(at 161.544 66.04)
		(size 0.6)
		(drill 0.35)
		(layers "F.Cu" "B.Cu")
		(free yes)
		(net 1)
	)
	(via
		(at 157.226 52.832)
		(size 0.6)
		(drill 0.35)
		(layers "F.Cu" "B.Cu")
		(free yes)
		(net 1)
	)
	(via
		(at 140.05 88.86)
		(size 0.6)
		(drill 0.35)
		(layers "F.Cu" "B.Cu")
		(free yes)
		(net 1)
	)
	(via
		(at 143.6116 72.39)
		(size 0.6)
		(drill 0.35)
		(layers "F.Cu" "B.Cu")
		(free yes)
		(net 1)
	)
	(via
		(at 188.976 40.386)
		(size 0.6)
		(drill 0.35)
		(layers "F.Cu" "B.Cu")
		(free yes)
		(net 1)
	)
	(via
		(at 161.18 96.88)
		(size 0.6)
		(drill 0.35)
		(layers "F.Cu" "B.Cu")
		(net 1)
	)
	(via
		(at 181.356 49.276)
		(size 0.6)
		(drill 0.35)
		(layers "F.Cu" "B.Cu")
		(free yes)
		(net 1)
	)
	(via
		(at 175.514 47.752)
		(size 0.6)
		(drill 0.35)
		(layers "F.Cu" "B.Cu")
		(net 1)
	)
	(via
		(at 165.78 88.3)
		(size 0.6)
		(drill 0.35)
		(layers "F.Cu" "B.Cu")
		(free yes)
		(net 1)
	)
	(via
		(at 175.515 49.403)
		(size 0.6)
		(drill 0.35)
		(layers "F.Cu" "B.Cu")
		(net 1)
	)
	(via
		(at 186.944 71.882)
		(size 0.6)
		(drill 0.35)
		(layers "F.Cu" "B.Cu")
		(free yes)
		(net 1)
	)
	(via
		(at 128.27 95.504)
		(size 0.6)
		(drill 0.35)
		(layers "F.Cu" "B.Cu")
		(free yes)
		(net 1)
	)
	(via
		(at 141.6 88.86)
		(size 0.6)
		(drill 0.35)
		(layers "F.Cu" "B.Cu")
		(free yes)
		(net 1)
	)
	(via
		(at 180.848 55.372)
		(size 0.6)
		(drill 0.35)
		(layers "F.Cu" "B.Cu")
		(free yes)
		(net 1)
	)
	(via
		(at 129.794 93.599)
		(size 0.6)
		(drill 0.35)
		(layers "F.Cu" "B.Cu")
		(net 1)
	)
	(via
		(at 148.01 80.876)
		(size 0.6)
		(drill 0.35)
		(layers "F.Cu" "B.Cu")
		(net 1)
	)
	(via
		(at 179.324 64.516)
		(size 0.6)
		(drill 0.35)
		(layers "F.Cu" "B.Cu")
		(net 1)
	)
	(via
		(at 146.63 89.77)
		(size 0.6)
		(drill 0.35)
		(layers "F.Cu" "B.Cu")
		(free yes)
		(net 1)
	)
	(via
		(at 176.63 82.16)
		(size 0.6)
		(drill 0.35)
		(layers "F.Cu" "B.Cu")
		(free yes)
		(net 1)
	)
	(via
		(at 154.22 86.37)
		(size 0.6)
		(drill 0.35)
		(layers "F.Cu" "B.Cu")
		(free yes)
		(net 1)
	)
	(via
		(at 143.129 57.531)
		(size 0.6)
		(drill 0.35)
		(layers "F.Cu" "B.Cu")
		(free yes)
		(net 1)
	)
	(via
		(at 187.05 96.48)
		(size 0.6)
		(drill 0.35)
		(layers "F.Cu" "B.Cu")
		(free yes)
		(net 1)
	)
	(via
		(at 181.864 62.23)
		(size 0.6)
		(drill 0.35)
		(layers "F.Cu" "B.Cu")
		(net 1)
	)
	(via
		(at 174.691 61.976)
		(size 0.6)
		(drill 0.35)
		(layers "F.Cu" "B.Cu")
		(free yes)
		(net 1)
	)
	(via
		(at 146.994 67.922)
		(size 0.6)
		(drill 0.35)
		(layers "F.Cu" "B.Cu")
		(free yes)
		(net 1)
	)
	(via
		(at 125.769 85.129)
		(size 0.6)
		(drill 0.35)
		(layers "F.Cu" "B.Cu")
		(net 1)
	)
	(via
		(at 156.182582 79.880982)
		(size 0.6)
		(drill 0.35)
		(layers "F.Cu" "B.Cu")
		(net 1)
	)
	(via
		(at 175.514 53.594)
		(size 0.6)
		(drill 0.35)
		(layers "F.Cu" "B.Cu")
		(net 1)
	)
	(via
		(at 138.2776 79.756)
		(size 0.6)
		(drill 0.35)
		(layers "F.Cu" "B.Cu")
		(free yes)
		(net 1)
	)
	(via
		(at 132.715 93.599)
		(size 0.6)
		(drill 0.35)
		(layers "F.Cu" "B.Cu")
		(net 1)
	)
	(via
		(at 178.816 60.452)
		(size 0.6)
		(drill 0.35)
		(layers "F.Cu" "B.Cu")
		(free yes)
		(net 1)
	)
	(via
		(at 151.65 98.2)
		(size 0.6)
		(drill 0.35)
		(layers "F.Cu" "B.Cu")
		(free yes)
		(net 1)
	)
	(via
		(at 184.7088 88.2396)
		(size 0.6)
		(drill 0.35)
		(layers "F.Cu" "B.Cu")
		(net 1)
	)
	(via
		(at 170.966 49.808)
		(size 0.6)
		(drill 0.35)
		(layers "F.Cu" "B.Cu")
		(net 1)
	)
	(via
		(at 144.2 81.638)
		(size 0.6)
		(drill 0.35)
		(layers "F.Cu" "B.Cu")
		(net 1)
	)
	(via
		(at 174.45 94.05)
		(size 0.6)
		(drill 0.35)
		(layers "F.Cu" "B.Cu")
		(free yes)
		(net 1)
	)
	(via
		(at 172.0088 47.244)
		(size 0.6)
		(drill 0.35)
		(layers "F.Cu" "B.Cu")
		(net 1)
	)
	(via
		(at 168.94 72.28)
		(size 0.6)
		(drill 0.35)
		(layers "F.Cu" "B.Cu")
		(free yes)
		(net 1)
	)
	(via
		(at 185.2168 72.4916)
		(size 0.6)
		(drill 0.35)
		(layers "F.Cu" "B.Cu")
		(net 1)
	)
	(via
		(at 168.42 79.64)
		(size 0.6)
		(drill 0.35)
		(layers "F.Cu" "B.Cu")
		(free yes)
		(net 1)
	)
	(via
		(at 164.79 75.5)
		(size 0.6)
		(drill 0.35)
		(layers "F.Cu" "B.Cu")
		(free yes)
		(net 1)
	)
	(via
		(at 184.7088 58.166)
		(size 0.6)
		(drill 0.35)
		(layers "F.Cu" "B.Cu")
		(net 1)
	)
	(via
		(at 134.294 67.922)
		(size 0.6)
		(drill 0.35)
		(layers "F.Cu" "B.Cu")
		(free yes)
		(net 1)
	)
	(via
		(at 146.486 83.924)
		(size 0.6)
		(drill 0.35)
		(layers "F.Cu" "B.Cu")
		(net 1)
	)
	(via
		(at 179.498 61.06)
		(size 0.6)
		(drill 0.35)
		(layers "F.Cu" "B.Cu")
		(free yes)
		(net 1)
	)
	(via
		(at 129.794 98.552)
		(size 0.6)
		(drill 0.35)
		(layers "F.Cu" "B.Cu")
		(free yes)
		(net 1)
	)
	(via
		(at 135.128 79.756)
		(size 0.6)
		(drill 0.35)
		(layers "F.Cu" "B.Cu")
		(free yes)
		(net 1)
	)
	(via
		(at 139.5476 78.496)
		(size 0.6)
		(drill 0.35)
		(layers "F.Cu" "B.Cu")
		(net 1)
	)
	(via
		(at 178.816 49.784)
		(size 0.6)
		(drill 0.35)
		(layers "F.Cu" "B.Cu")
		(free yes)
		(net 1)
	)
	(via
		(at 118.11 83.058)
		(size 0.6)
		(drill 0.35)
		(layers "F.Cu" "B.Cu")
		(net 1)
	)
	(via
		(at 121.031 80.264)
		(size 0.6)
		(drill 0.35)
		(layers "F.Cu" "B.Cu")
		(net 1)
	)
	(via
		(at 176.45 61.568)
		(size 0.6)
		(drill 0.35)
		(layers "F.Cu" "B.Cu")
		(free yes)
		(net 1)
	)
	(via
		(at 185.2168 81.4324)
		(size 0.6)
		(drill 0.35)
		(layers "F.Cu" "B.Cu")
		(net 1)
	)
	(via
		(at 140.716 94.488)
		(size 0.6)
		(drill 0.35)
		(layers "F.Cu" "B.Cu")
		(net 1)
	)
	(via
		(at 163.43 88.32)
		(size 0.6)
		(drill 0.35)
		(layers "F.Cu" "B.Cu")
		(free yes)
		(net 1)
	)
	(via
		(at 131.318 57.531)
		(size 0.6)
		(drill 0.35)
		(layers "F.Cu" "B.Cu")
		(free yes)
		(net 1)
	)
	(via
		(at 148.521088 74.901088)
		(size 0.6)
		(drill 0.35)
		(layers "F.Cu" "B.Cu")
		(net 1)
	)
	(via
		(at 163.24 75.4)
		(size 0.6)
		(drill 0.35)
		(layers "F.Cu" "B.Cu")
		(free yes)
		(net 1)
	)
	(via
		(at 190.02 87.2)
		(size 0.6)
		(drill 0.35)
		(layers "F.Cu" "B.Cu")
		(free yes)
		(net 1)
	)
	(via
		(at 145.59 91.48)
		(size 0.6)
		(drill 0.35)
		(layers "F.Cu" "B.Cu")
		(free yes)
		(net 1)
	)
	(via
		(at 189.91 58.19)
		(size 0.6)
		(drill 0.35)
		(layers "F.Cu" "B.Cu")
		(free yes)
		(net 1)
	)
	(via
		(at 177.546 47.752)
		(size 0.6)
		(drill 0.35)
		(layers "F.Cu" "B.Cu")
		(net 1)
	)
	(via
		(at 171.23 71.26)
		(size 0.6)
		(drill 0.35)
		(layers "F.Cu" "B.Cu")
		(free yes)
		(net 1)
	)
	(via
		(at 179.1208 47.1932)
		(size 0.6)
		(drill 0.35)
		(layers "F.Cu" "B.Cu")
		(net 1)
	)
	(via
		(at 180.514 61.06)
		(size 0.6)
		(drill 0.35)
		(layers "F.Cu" "B.Cu")
		(free yes)
		(net 1)
	)
	(via
		(at 178.01 80.36)
		(size 0.6)
		(drill 0.35)
		(layers "F.Cu" "B.Cu")
		(free yes)
		(net 1)
	)
	(via
		(at 154.051 62.992)
		(size 0.6)
		(drill 0.35)
		(layers "F.Cu" "B.Cu")
		(free yes)
		(net 1)
	)
	(via
		(at 134.747 62.611)
		(size 0.6)
		(drill 0.35)
		(layers "F.Cu" "B.Cu")
		(free yes)
		(net 1)
	)
	(via
		(at 168.656 52.832)
		(size 0.6)
		(drill 0.35)
		(layers "F.Cu" "B.Cu")
		(free yes)
		(net 1)
	)
	(via
		(at 169.64 72.97)
		(size 0.6)
		(drill 0.35)
		(layers "F.Cu" "B.Cu")
		(free yes)
		(net 1)
	)
	(via
		(at 158.424 67.922)
		(size 0.6)
		(drill 0.35)
		(layers "F.Cu" "B.Cu")
		(free yes)
		(net 1)
	)
	(via
		(at 154.2 84.58)
		(size 0.6)
		(drill 0.35)
		(layers "F.Cu" "B.Cu")
		(free yes)
		(net 1)
	)
	(via
		(at 128.474978 77.990009)
		(size 0.6)
		(drill 0.35)
		(layers "F.Cu" "B.Cu")
		(net 1)
	)
	(via
		(at 170.307 56.515)
		(size 0.6)
		(drill 0.35)
		(layers "F.Cu" "B.Cu")
		(free yes)
		(net 1)
	)
	(via
		(at 172.0088 40.0812)
		(size 0.6)
		(drill 0.35)
		(layers "F.Cu" "B.Cu")
		(net 1)
	)
	(via
		(at 185.166 70.9676)
		(size 0.6)
		(drill 0.35)
		(layers "F.Cu" "B.Cu")
		(net 1)
	)
	(via
		(at 136.54 88.17)
		(size 0.6)
		(drill 0.35)
		(layers "F.Cu" "B.Cu")
		(free yes)
		(net 1)
	)
	(via
		(at 142.757748 97.782253)
		(size 0.6)
		(drill 0.35)
		(layers "F.Cu" "B.Cu")
		(free yes)
		(net 1)
	)
	(via
		(at 124.714 80.518)
		(size 0.6)
		(drill 0.35)
		(layers "F.Cu" "B.Cu")
		(free yes)
		(net 1)
	)
	(via
		(at 139.65 85.2)
		(size 0.6)
		(drill 0.35)
		(layers "F.Cu" "B.Cu")
		(free yes)
		(net 1)
	)
	(via
		(at 159.52 95.12)
		(size 0.6)
		(drill 0.35)
		(layers "F.Cu" "B.Cu")
		(free yes)
		(net 1)
	)
	(via
		(at 146.177 62.484)
		(size 0.6)
		(drill 0.35)
		(layers "F.Cu" "B.Cu")
		(free yes)
		(net 1)
	)
	(via
		(at 149.82 87.9)
		(size 0.6)
		(drill 0.35)
		(layers "F.Cu" "B.Cu")
		(free yes)
		(net 1)
	)
	(via
		(at 177.5194 48.589)
		(size 0.6)
		(drill 0.35)
		(layers "F.Cu" "B.Cu")
		(free yes)
		(net 1)
	)
	(via
		(at 147.248 81.638)
		(size 0.6)
		(drill 0.35)
		(layers "F.Cu" "B.Cu")
		(net 1)
	)
	(via
		(at 137.414 98.298)
		(size 0.6)
		(drill 0.35)
		(layers "F.Cu" "B.Cu")
		(net 1)
	)
	(via
		(at 174.72 85.13)
		(size 0.6)
		(drill 0.35)
		(layers "F.Cu" "B.Cu")
		(free yes)
		(net 1)
	)
	(via
		(at 185.2168 78.486)
		(size 0.6)
		(drill 0.35)
		(layers "F.Cu" "B.Cu")
		(net 1)
	)
	(via
		(at 180.086 90.17)
		(size 0.6)
		(drill 0.35)
		(layers "F.Cu" "B.Cu")
		(free yes)
		(net 1)
	)
	(via
		(at 186.944 65.532)
		(size 0.6)
		(drill 0.35)
		(layers "F.Cu" "B.Cu")
		(free yes)
		(net 1)
	)
	(via
		(at 126.703 84.478347)
		(size 0.6)
		(drill 0.35)
		(layers "F.Cu" "B.Cu")
		(net 1)
	)
	(via
		(at 136.318 77.316)
		(size 0.6)
		(drill 0.35)
		(layers "F.Cu" "B.Cu")
		(net 1)
	)
	(via
		(at 143.637 69.977)
		(size 0.6)
		(drill 0.35)
		(layers "F.Cu" "B.Cu")
		(free yes)
		(net 1)
	)
	(via
		(at 121.92 73.152)
		(size 0.6)
		(drill 0.35)
		(layers "F.Cu" "B.Cu")
		(free yes)
		(net 1)
	)
	(via
		(at 139.415234 89.00589)
		(size 0.6)
		(drill 0.35)
		(layers "F.Cu" "B.Cu")
		(net 1)
	)
	(via
		(at 130.302 67.818)
		(size 0.6)
		(drill 0.35)
		(layers "F.Cu" "B.Cu")
		(free yes)
		(net 1)
	)
	(via
		(at 117.094 40.386)
		(size 0.6)
		(drill 0.35)
		(layers "F.Cu" "B.Cu")
		(free yes)
		(net 1)
	)
	(via
		(at 168.656 60.96)
		(size 0.6)
		(drill 0.35)
		(layers "F.Cu" "B.Cu")
		(free yes)
		(net 1)
	)
	(via
		(at 150.5712 72.136)
		(size 0.6)
		(drill 0.35)
		(layers "F.Cu" "B.Cu")
		(free yes)
		(net 1)
	)
	(via
		(at 184.7088 59.7916)
		(size 0.6)
		(drill 0.35)
		(layers "F.Cu" "B.Cu")
		(net 1)
	)
	(via
		(at 117.094 52.578)
		(size 0.6)
		(drill 0.35)
		(layers "F.Cu" "B.Cu")
		(free yes)
		(net 1)
	)
	(via
		(at 175.514 68.326)
		(size 0.6)
		(drill 0.35)
		(layers "F.Cu" "B.Cu")
		(net 1)
	)
	(via
		(at 186.7408 86.5124)
		(size 0.6)
		(drill 0.35)
		(layers "F.Cu" "B.Cu")
		(net 1)
	)
	(via
		(at 117.094 48.006)
		(size 0.6)
		(drill 0.35)
		(layers "F.Cu" "B.Cu")
		(free yes)
		(net 1)
	)
	(via
		(at 141.754736 76.242272)
		(size 0.6)
		(drill 0.35)
		(layers "F.Cu" "B.Cu")
		(net 1)
	)
	(via
		(at 131.699 94.234)
		(size 0.6)
		(drill 0.35)
		(layers "F.Cu" "B.Cu")
		(net 1)
	)
	(via
		(at 177.546 51.3588)
		(size 0.6)
		(drill 0.35)
		(layers "F.Cu" "B.Cu")
		(free yes)
		(net 1)
	)
	(via
		(at 126.178 75.022)
		(size 0.6)
		(drill 0.35)
		(layers "F.Cu" "B.Cu")
		(net 1)
	)
	(via
		(at 143.891 71.501)
		(size 0.6)
		(drill 0.35)
		(layers "F.Cu" "B.Cu")
		(free yes)
		(net 1)
	)
	(via
		(at 185.2168 79.9592)
		(size 0.6)
		(drill 0.35)
		(layers "F.Cu" "B.Cu")
		(net 1)
	)
	(via
		(at 135.38 88.26)
		(size 0.6)
		(drill 0.35)
		(layers "F.Cu" "B.Cu")
		(free yes)
		(net 1)
	)
	(via
		(at 153.906156 78.618453)
		(size 0.6)
		(drill 0.35)
		(layers "F.Cu" "B.Cu")
		(net 1)
	)
	(via
		(at 188.214 43.434)
		(size 0.6)
		(drill 0.35)
		(layers "F.Cu" "B.Cu")
		(free yes)
		(net 1)
	)
	(via
		(at 186.944 78.232)
		(size 0.6)
		(drill 0.35)
		(layers "F.Cu" "B.Cu")
		(free yes)
		(net 1)
	)
	(via
		(at 117.094 57.15)
		(size 0.6)
		(drill 0.35)
		(layers "F.Cu" "B.Cu")
		(free yes)
		(net 1)
	)
	(segment
		(start 151.723411 78.134329)
		(end 152.207535 78.618453)
		(width 0.3)
		(layer "B.Cu")
		(net 1)
	)
	(segment
		(start 133.25 88.22)
		(end 133.24 88.21)
		(width 0.187)
		(layer "B.Cu")
		(net 1)
	)
	(segment
		(start 139.964 78.496)
		(end 139.5476 78.496)
		(width 0.3)
		(layer "B.Cu")
		(net 1)
	)
	(segment
		(start 145.442314 73.882393)
		(end 145.397127 73.882393)
		(width 0.5)
		(layer "B.Cu")
		(net 1)
	)
	(segment
		(start 156.21 79.9084)
		(end 156.182582 79.880982)
		(width 0.5)
		(layer "B.Cu")
		(net 1)
	)
	(segment
		(start 138.84976 80.42976)
		(end 138.2776 79.8576)
		(width 0.3)
		(layer "B.Cu")
		(net 1)
	)
	(segment
		(start 139.090922 84.691012)
		(end 139.556988 84.691012)
		(width 0.3)
		(layer "B.Cu")
		(net 1)
	)
	(segment
		(start 139.65 85.2)
		(end 139.68 85.23)
		(width 0.3)
		(layer "B.Cu")
		(net 1)
	)
	(segment
		(start 142.862589 76.422589)
		(end 143.170589 76.114589)
		(width 0.3)
		(layer "B.Cu")
		(net 1)
	)
	(segment
		(start 161.952 96.85)
		(end 161.21 96.85)
		(width 0.187)
		(layer "B.Cu")
		(net 1)
	)
	(segment
		(start 151.66 96.855897)
		(end 156.972494 96.855897)
		(width 0.187)
		(layer "B.Cu")
		(net 1)
	)
	(segment
		(start 141.95 77.015178)
		(end 142.248589 76.716589)
		(width 0.3)
		(layer "B.Cu")
		(net 1)
	)
	(segment
		(start 151.65 98.2)
		(end 151.65 96.865897)
		(width 0.187)
		(layer "B.Cu")
		(net 1)
	)
	(segment
		(start 151.65 96.865897)
		(end 151.66 96.855897)
		(width 0.187)
		(layer "B.Cu")
		(net 1)
	)
	(segment
		(start 141.774272 76.242272)
		(end 142.248589 76.716589)
		(width 0.5)
		(layer "B.Cu")
		(net 1)
	)
	(segment
		(start 139.68 85.23)
		(end 140.576 85.23)
		(width 0.3)
		(layer "B.Cu")
		(net 1)
	)
	(segment
		(start 142.248589 76.716589)
		(end 142.542589 76.422589)
		(width 0.3)
		(layer "B.Cu")
		(net 1)
	)
	(segment
		(start 151.384 76.708)
		(end 151.384 76.962)
		(width 0.5)
		(layer "B.Cu")
		(net 1)
	)
	(segment
		(start 133.25 88.97)
		(end 133.25 88.22)
		(width 0.187)
		(layer "B.Cu")
		(net 1)
	)
	(segment
		(start 149.437411 75.817411)
		(end 148.521088 74.901088)
		(width 0.3)
		(layer "B.Cu")
		(net 1)
	)
	(segment
		(start 139.0904 79.1464)
		(end 138.938 79.1464)
		(width 0.3)
		(layer "B.Cu")
		(net 1)
	)
	(segment
		(start 149.437411 75.860589)
		(end 149.437411 75.817411)
		(width 0.3)
		(layer "B.Cu")
		(net 1)
	)
	(segment
		(start 138.2776 79.8576)
		(end 138.2776 79.756)
		(width 0.3)
		(layer "B.Cu")
		(net 1)
	)
	(segment
		(start 161.21 96.85)
		(end 161.18 96.88)
		(width 0.187)
		(layer "B.Cu")
		(net 1)
	)
	(segment
		(start 145.397127 73.882393)
		(end 144.69176 74.58776)
		(width 0.5)
		(layer "B.Cu")
		(net 1)
	)
	(segment
		(start 138.70389 89.00589)
		(end 138.698 89)
		(width 0.187)
		(layer "B.Cu")
		(net 1)
	)
	(segment
		(start 142.542589 76.422589)
		(end 142.862589 76.422589)
		(width 0.3)
		(layer "B.Cu")
		(net 1)
	)
	(segment
		(start 151.384 76.962)
		(end 150.96424 77.38176)
		(width 0.5)
		(layer "B.Cu")
		(net 1)
	)
	(segment
		(start 136.54 88.96)
		(end 136.55 88.97)
		(width 0.187)
		(layer "B.Cu")
		(net 1)
	)
	(segment
		(start 139.556988 84.691012)
		(end 139.912589 84.335411)
		(width 0.3)
		(layer "B.Cu")
		(net 1)
	)
	(segment
		(start 139.61176 79.66776)
		(end 139.0904 79.1464)
		(width 0.3)
		(layer "B.Cu")
		(net 1)
	)
	(segment
		(start 141.646589 77.638589)
		(end 141.95 77.335178)
		(width 0.3)
		(layer "B.Cu")
		(net 1)
	)
	(segment
		(start 156.21 80.69448)
		(end 156.21 79.9084)
		(width 0.5)
		(layer "B.Cu")
		(net 1)
	)
	(segment
		(start 140.576 85.23)
		(end 140.884589 84.921411)
		(width 0.3)
		(layer "B.Cu")
		(net 1)
	)
	(segment
		(start 151.72624 85.17824)
		(end 154.77424 82.13024)
		(width 0.5)
		(layer "B.Cu")
		(net 1)
	)
	(segment
		(start 136.54 88.17)
		(end 136.54 88.96)
		(width 0.187)
		(layer "B.Cu")
		(net 1)
	)
	(segment
		(start 138.829 83.929)
		(end 139.360589 83.397411)
		(width 0.3)
		(layer "B.Cu")
		(net 1)
	)
	(segment
		(start 140.37376 78.90576)
		(end 139.964 78.496)
		(width 0.3)
		(layer "B.Cu")
		(net 1)
	)
	(segment
		(start 143.170589 76.114589)
		(end 144.694589 74.590589)
		(width 0.5)
		(layer "B.Cu")
		(net 1)
	)
	(segment
		(start 152.207535 78.618453)
		(end 153.906156 78.618453)
		(width 0.3)
		(layer "B.Cu")
		(net 1)
	)
	(segment
		(start 141.754736 76.242272)
		(end 141.774272 76.242272)
		(width 0.5)
		(layer "B.Cu")
		(net 1)
	)
	(segment
		(start 154.77424 82.13024)
		(end 156.21 80.69448)
		(width 0.5)
		(layer "B.Cu")
		(net 1)
	)
	(segment
		(start 135.38 88.26)
		(end 135.38 88.982)
		(width 0.187)
		(layer "B.Cu")
		(net 1)
	)
	(segment
		(start 139.415234 89.00589)
		(end 138.70389 89.00589)
		(width 0.187)
		(layer "B.Cu")
		(net 1)
	)
	(segment
		(start 135.38 88.982)
		(end 135.398 89)
		(width 0.187)
		(layer "B.Cu")
		(net 1)
	)
	(segment
		(start 141.95 77.335178)
		(end 141.95 77.015178)
		(width 0.3)
		(layer "B.Cu")
		(net 1)
	)
	(segment
		(start 149.4525 75.85776)
		(end 151.72624 78.1315)
		(width 0.5)
		(layer "B.Cu")
		(net 1)
	)
	(segment
		(start 149.44024 75.85776)
		(end 149.4525 75.85776)
		(width 0.5)
		(layer "B.Cu")
		(net 1)
	)
	(segment
		(start 147.867621 96.855897)
		(end 151.66 96.855897)
		(width 0.187)
		(layer "B.Cu")
		(net 1)
	)
	(segment
		(start 152.4 96.81)
		(end 152.4 97.89)
		(width 0.5)
		(layer "F.Cu")
		(net 2)
	)
	(via
		(at 152.4 97.89)
		(size 0.6)
		(drill 0.35)
		(layers "F.Cu" "B.Cu")
		(net 2)
	)
	(via
		(at 172.212 49.784)
		(size 0.6)
		(drill 0.35)
		(layers "F.Cu" "B.Cu")
		(net 2)
	)
	(segment
		(start 187.204002 98.8)
		(end 189.092 96.912002)
		(width 0.187)
		(layer "In2.Cu")
		(net 2)
	)
	(segment
		(start 189.092 50.475926)
		(end 189.3985 50.169426)
		(width 0.187)
		(layer "In2.Cu")
		(net 2)
	)
	(segment
		(start 189.3985 43.027265)
		(end 187.651235 41.28)
		(width 0.187)
		(layer "In2.Cu")
		(net 2)
	)
	(segment
		(start 189.3985 50.169426)
		(end 189.3985 43.027265)
		(width 0.187)
		(layer "In2.Cu")
		(net 2)
	)
	(segment
		(start 189.092 96.912002)
		(end 189.092 50.475926)
		(width 0.187)
		(layer "In2.Cu")
		(net 2)
	)
	(segment
		(start 152.4 97.79)
		(end 153.41 98.8)
		(width 0.187)
		(layer "In2.Cu")
		(net 2)
	)
	(segment
		(start 153.41 98.8)
		(end 187.204002 98.8)
		(width 0.187)
		(layer "In2.Cu")
		(net 2)
	)
	(segment
		(start 172.212 48.514)
		(end 172.212 49.784)
		(width 0.187)
		(layer "In2.Cu")
		(net 2)
	)
	(segment
		(start 187.651235 41.28)
		(end 179.446 41.28)
		(width 0.187)
		(layer "In2.Cu")
		(net 2)
	)
	(segment
		(start 179.446 41.28)
		(end 172.212 48.514)
		(width 0.187)
		(layer "In2.Cu")
		(net 2)
	)
	(segment
		(start 172.617 62.587)
		(end 173.101 62.103)
		(width 0.187)
		(layer "F.Cu")
		(net 3)
	)
	(segment
		(start 168.083 58.119)
		(end 169.281 58.119)
		(width 0.187)
		(layer "F.Cu")
		(net 3)
	)
	(segment
		(start 173.429 59.309)
		(end 173.101 59.309)
		(width 0.187)
		(layer "F.Cu")
		(net 3)
	)
	(segment
		(start 173.656 64.385)
		(end 173.656 63.854)
		(width 0.187)
		(layer "F.Cu")
		(net 3)
	)
	(segment
		(start 171.027 62.587)
		(end 172.212 62.587)
		(width 0.187)
		(layer "F.Cu")
		(net 3)
	)
	(segment
		(start 172.132 63.854)
		(end 171.878 63.6)
		(width 0.187)
		(layer "F.Cu")
		(net 3)
	)
	(segment
		(start 175.858 60.436)
		(end 175.858 59.452)
		(width 0.187)
		(layer "F.Cu")
		(net 3)
	)
	(segment
		(start 174.192 61.238)
		(end 173.91 61.238)
		(width 0.187)
		(layer "F.Cu")
		(net 3)
	)
	(segment
		(start 169.431 58.28)
		(end 168.783 58.928)
		(width 0.187)
		(layer "F.Cu")
		(net 3)
	)
	(segment
		(start 169.431 58.269)
		(end 169.431 58.28)
		(width 0.187)
		(layer "F.Cu")
		(net 3)
	)
	(segment
		(start 174.244 68.072)
		(end 174.498 68.072)
		(width 0.187)
		(layer "F.Cu")
		(net 3)
	)
	(segment
		(start 175.688 59.282)
		(end 174.672 59.282)
		(width 0.187)
		(layer "F.Cu")
		(net 3)
	)
	(segment
		(start 172.212 62.587)
		(end 172.617 62.587)
		(width 0.187)
		(layer "F.Cu")
		(net 3)
	)
	(segment
		(start 174.498 68.072)
		(end 174.71 67.86)
		(width 0.187)
		(layer "F.Cu")
		(net 3)
	)
	(segment
		(start 184.658 51.816)
		(end 184.658 51.308)
		(width 0.187)
		(layer "F.Cu")
		(net 3)
	)
	(segment
		(start 174.498 60.932)
		(end 174.192 61.238)
		(width 0.187)
		(layer "F.Cu")
		(net 3)
	)
	(segment
		(start 172.132 64.385)
		(end 172.132 63.854)
		(width 0.187)
		(layer "F.Cu")
		(net 3)
	)
	(segment
		(start 184.912 52.07)
		(end 184.658 51.816)
		(width 0.187)
		(layer "F.Cu")
		(net 3)
	)
	(segment
		(start 173.101 62.103)
		(end 173.101 59.309)
		(width 0.187)
		(layer "F.Cu")
		(net 3)
	)
	(segment
		(start 174.672 59.282)
		(end 174.498 59.456)
		(width 0.187)
		(layer "F.Cu")
		(net 3)
	)
	(segment
		(start 170.877 62.437)
		(end 171.027 62.587)
		(width 0.187)
		(layer "F.Cu")
		(net 3)
	)
	(segment
		(start 184.5358 51.1858)
		(end 184.079 51.1858)
		(width 0.187)
		(layer "F.Cu")
		(net 3)
	)
	(segment
		(start 174.498 59.456)
		(end 174.498 60.932)
		(width 0.187)
		(layer "F.Cu")
		(net 3)
	)
	(segment
		(start 185.928 52.07)
		(end 184.912 52.07)
		(width 0.187)
		(layer "F.Cu")
		(net 3)
	)
	(segment
		(start 169.281 58.119)
		(end 169.431 58.269)
		(width 0.187)
		(layer "F.Cu")
		(net 3)
	)
	(segment
		(start 175.858 59.452)
		(end 175.688 59.282)
		(width 0.187)
		(layer "F.Cu")
		(net 3)
	)
	(segment
		(start 184.658 51.308)
		(end 184.5358 51.1858)
		(width 0.187)
		(layer "F.Cu")
		(net 3)
	)
	(segment
		(start 173.91 59.79)
		(end 173.429 59.309)
		(width 0.187)
		(layer "F.Cu")
		(net 3)
	)
	(segment
		(start 168.529 58.928)
		(end 168.148 59.309)
		(width 0.187)
		(layer "F.Cu")
		(net 3)
	)
	(segment
		(start 174.71 67.86)
		(end 174.71 66.418)
		(width 0.187)
		(layer "F.Cu")
		(net 3)
	)
	(segment
		(start 173.656 63.854)
		(end 173.91 63.6)
		(width 0.187)
		(layer "F.Cu")
		(net 3)
	)
	(segment
		(start 173.91 61.238)
		(end 173.91 59.79)
		(width 0.187)
		(layer "F.Cu")
		(net 3)
	)
	(segment
		(start 168.783 58.928)
		(end 168.529 58.928)
		(width 0.187)
		(layer "F.Cu")
		(net 3)
	)
	(via
		(at 174.244 68.072)
		(size 0.6)
		(drill 0.35)
		(layers "F.Cu" "B.Cu")
		(net 3)
	)
	(via
		(at 132.207 82.931)
		(size 0.6)
		(drill 0.35)
		(layers "F.Cu" "B.Cu")
		(net 3)
	)
	(via
		(at 168.148 59.309)
		(size 0.6)
		(drill 0.35)
		(layers "F.Cu" "B.Cu")
		(net 3)
	)
	(via
		(at 173.101 59.309)
		(size 0.6)
		(drill 0.35)
		(layers "F.Cu" "B.Cu")
		(net 3)
	)
	(via
		(at 132.207 83.82)
		(size 0.6)
		(drill 0.35)
		(layers "F.Cu" "B.Cu")
		(net 3)
	)
	(via
		(at 131.445 82.931)
		(size 0.6)
		(drill 0.35)
		(layers "F.Cu" "B.Cu")
		(net 3)
	)
	(via
		(at 171.878 63.6)
		(size 0.6)
		(drill 0.35)
		(layers "F.Cu" "B.Cu")
		(net 3)
	)
	(via
		(at 131.445 83.82)
		(size 0.6)
		(drill 0.35)
		(layers "F.Cu" "B.Cu")
		(free yes)
		(net 3)
	)
	(via
		(at 173.91 63.6)
		(size 0.6)
		(drill 0.35)
		(layers "F.Cu" "B.Cu")
		(net 3)
	)
	(via
		(at 185.928 52.07)
		(size 0.6)
		(drill 0.35)
		(layers "F.Cu" "B.Cu")
		(net 3)
	)
	(segment
		(start 132.944 82.702)
		(end 132.715 82.931)
		(width 0.5)
		(layer "B.Cu")
		(net 3)
	)
	(segment
		(start 132.715 82.931)
		(end 132.207 82.931)
		(width 0.5)
		(layer "B.Cu")
		(net 3)
	)
	(segment
		(start 132.207 82.931)
		(end 131.445 82.931)
		(width 0.5)
		(layer "B.Cu")
		(net 3)
	)
	(segment
		(start 132.207 83.82)
		(end 131.445 83.82)
		(width 0.5)
		(layer "B.Cu")
		(net 3)
	)
	(segment
		(start 132.207 84.793)
		(end 132.2 84.8)
		(width 0.5)
		(layer "B.Cu")
		(net 3)
	)
	(segment
		(start 133.373 82.702)
		(end 132.944 82.702)
		(width 0.5)
		(layer "B.Cu")
		(net 3)
	)
	(segment
		(start 132.207 83.82)
		(end 132.207 84.793)
		(width 0.5)
		(layer "B.Cu")
		(net 3)
	)
	(segment
		(start 132.207 83.82)
		(end 133.373 83.82)
		(width 0.5)
		(layer "B.Cu")
		(net 3)
	)
	(segment
		(start 168.275 59.436)
		(end 172.974 59.436)
		(width 0.5)
		(layer "In2.Cu")
		(net 3)
	)
	(segment
		(start 133.985 81.788)
		(end 133.985 69.723)
		(width 0.5)
		(layer "In2.Cu")
		(net 3)
	)
	(segment
		(start 171.878 62.945)
		(end 172.192 62.631)
		(width 0.187)
		(layer "In2.Cu")
		(net 3)
	)
	(segment
		(start 132.207 82.931)
		(end 132.207 83.058)
		(width 0.5)
		(layer "In2.Cu")
		(net 3)
	)
	(segment
		(start 132.842 82.931)
		(end 133.985 81.788)
		(width 0.5)
		(layer "In2.Cu")
		(net 3)
	)
	(segment
		(start 173.629 62.631)
		(end 173.101 62.631)
		(width 0.187)
		(layer "In2.Cu")
		(net 3)
	)
	(segment
		(start 182.118 58.547)
		(end 181.356 59.309)
		(width 0.5)
		(layer "In2.Cu")
		(net 3)
	)
	(segment
		(start 173.91 63.6)
		(end 173.91 62.912)
		(width 0.187)
		(layer "In2.Cu")
		(net 3)
	)
	(segment
		(start 173.101 64.4155)
		(end 173.101 62.631)
		(width 0.187)
		(layer "In2.Cu")
		(net 3)
	)
	(segment
		(start 164.512 61.802)
		(end 167.005 59.309)
		(width 0.5)
		(layer "In2.Cu")
		(net 3)
	)
	(segment
		(start 174.244 68.072)
		(end 174.244 65.5585)
		(width 0.187)
		(layer "In2.Cu")
		(net 3)
	)
	(segment
		(start 133.985 69.723)
		(end 134.62 69.088)
		(width 0.5)
		(layer "In2.Cu")
		(net 3)
	)
	(segment
		(start 172.192 62.631)
		(end 173.101 62.631)
		(width 0.187)
		(layer "In2.Cu")
		(net 3)
	)
	(segment
		(start 134.62 69.088)
		(end 160.909 69.088)
		(width 0.5)
		(layer "In2.Cu")
		(net 3)
	)
	(segment
		(start 132.207 82.931)
		(end 132.842 82.931)
		(width 0.5)
		(layer "In2.Cu")
		(net 3)
	)
	(segment
		(start 181.356 59.309)
		(end 173.101 59.309)
		(width 0.5)
		(layer "In2.Cu")
		(net 3)
	)
	(segment
		(start 168.148 59.309)
		(end 168.275 59.436)
		(width 0.5)
		(layer "In2.Cu")
		(net 3)
	)
	(segment
		(start 167.005 59.309)
		(end 168.148 59.309)
		(width 0.5)
		(layer "In2.Cu")
		(net 3)
	)
	(segment
		(start 173.91 62.912)
		(end 173.629 62.631)
		(width 0.187)
		(layer "In2.Cu")
		(net 3)
	)
	(segment
		(start 173.101 62.631)
		(end 173.101 59.309)
		(width 0.3)
		(layer "In2.Cu")
		(net 3)
	)
	(segment
		(start 171.878 63.6)
		(end 171.878 62.945)
		(width 0.187)
		(layer "In2.Cu")
		(net 3)
	)
	(segment
		(start 160.909 69.088)
		(end 164.512 65.485)
		(width 0.5)
		(layer "In2.Cu")
		(net 3)
	)
	(segment
		(start 182.118 55.88)
		(end 182.118 58.547)
		(width 0.5)
		(layer "In2.Cu")
		(net 3)
	)
	(segment
		(start 132.207 83.058)
		(end 131.445 83.82)
		(width 0.5)
		(layer "In2.Cu")
		(net 3)
	)
	(segment
		(start 164.512 65.485)
		(end 164.512 61.802)
		(width 0.5)
		(layer "In2.Cu")
		(net 3)
	)
	(segment
		(start 172.974 59.436)
		(end 173.101 59.309)
		(width 0.5)
		(layer "In2.Cu")
		(net 3)
	)
	(segment
		(start 185.928 52.07)
		(end 182.118 55.88)
		(width 0.5)
		(layer "In2.Cu")
		(net 3)
	)
	(segment
		(start 174.244 65.5585)
		(end 173.101 64.4155)
		(width 0.187)
		(layer "In2.Cu")
		(net 3)
	)
	(segment
		(start 161.374 64.686)
		(end 157.988 64.686)
		(width 0.5)
		(layer "F.Cu")
		(net 4)
	)
	(segment
		(start 124.46 66.063)
		(end 123.572 66.063)
		(width 0.5)
		(layer "F.Cu")
		(net 4)
	)
	(segment
		(start 157.6275 64.686)
		(end 157.988 64.686)
		(width 0.5)
		(layer "F.Cu")
		(net 4)
	)
	(segment
		(start 139.677 93.127)
		(end 139.677 93.472)
		(width 0.5)
		(layer "F.Cu")
		(net 4)
	)
	(segment
		(start 139.192 62.484)
		(end 139.192 64.008)
		(width 0.5)
		(layer "F.Cu")
		(net 4)
	)
	(segment
		(start 118.618 86.36)
		(end 118.664 86.314)
		(width 0.5)
		(layer "F.Cu")
		(net 4)
	)
	(segment
		(start 144.931 66.087)
		(end 145.724 66.087)
		(width 0.5)
		(layer "F.Cu")
		(net 4)
	)
	(segment
		(start 127.723 82.462)
		(end 127.762 82.423)
		(width 0.5)
		(layer "F.Cu")
		(net 4)
	)
	(segment
		(start 162.052 62.461)
		(end 162.052 64.008)
		(width 0.5)
		(layer "F.Cu")
		(net 4)
	)
	(segment
		(start 149.352 97.79)
		(end 149.352 97.796)
		(width 0.187)
		(layer "F.Cu")
		(net 4)
	)
	(segment
		(start 138.85 92.3)
		(end 139.677 93.127)
		(width 0.5)
		(layer "F.Cu")
		(net 4)
	)
	(segment
		(start 159.234 66.064)
		(end 159.258 66.04)
		(width 0.5)
		(layer "F.Cu")
		(net 4)
	)
	(segment
		(start 133.472 96.084984)
		(end 133.472 95.556)
		(width 0.5)
		(layer "F.Cu")
		(net 4)
	)
	(segment
		(start 156.361 66.064)
		(end 157.154 66.064)
		(width 0.5)
		(layer "F.Cu")
		(net 4)
	)
	(segment
		(start 118.664 86.314)
		(end 118.664 85.344)
		(width 0.5)
		(layer "F.Cu")
		(net 4)
	)
	(segment
		(start 136.374 66.087)
		(end 136.398 66.063)
		(width 0.5)
		(layer "F.Cu")
		(net 4)
	)
	(segment
		(start 126.674 82.462)
		(end 127.723 82.462)
		(width 0.5)
		(layer "F.Cu")
		(net 4)
	)
	(segment
		(start 133.238984 96.318)
		(end 133.472 96.084984)
		(width 0.5)
		(layer "F.Cu")
		(net 4)
	)
	(segment
		(start 126.703 82.466)
		(end 125.718 82.466)
		(width 0.5)
		(layer "F.Cu")
		(net 4)
	)
	(segment
		(start 123.571 66.064)
		(end 123.571 64.709)
		(width 0.5)
		(layer "F.Cu")
		(net 4)
	)
	(segment
		(start 122.356 66.087)
		(end 122.356 64.709)
		(width 0.5)
		(layer "F.Cu")
		(net 4)
	)
	(segment
		(start 131.725 96.318)
		(end 130.481 96.318)
		(width 0.5)
		(layer "F.Cu")
		(net 4)
	)
	(segment
		(start 123.572 66.063)
		(end 123.571 66.064)
		(width 0.5)
		(layer "F.Cu")
		(net 4)
	)
	(segment
		(start 150.622 64.008)
		(end 149.921 64.709)
		(width 0.5)
		(layer "F.Cu")
		(net 4)
	)
	(segment
		(start 158.424 66.064)
		(end 158.424 64.709)
		(width 0.5)
		(layer "F.Cu")
		(net 4)
	)
	(segment
		(start 138.491 64.709)
		(end 134.7675 64.709)
		(width 0.5)
		(layer "F.Cu")
		(net 4)
	)
	(segment
		(start 121.563 66.087)
		(end 122.356 66.087)
		(width 0.5)
		(layer "F.Cu")
		(net 4)
	)
	(segment
		(start 131.725 96.318)
		(end 133.238984 96.318)
		(width 0.5)
		(layer "F.Cu")
		(net 4)
	)
	(segment
		(start 158.424 66.064)
		(end 159.234 66.064)
		(width 0.5)
		(layer "F.Cu")
		(net 4)
	)
	(segment
		(start 157.154 66.064)
		(end 157.154 64.709)
		(width 0.5)
		(layer "F.Cu")
		(net 4)
	)
	(segment
		(start 129.921 80.964)
		(end 131.953 80.964)
		(width 0.5)
		(layer "F.Cu")
		(net 4)
	)
	(segment
		(start 127.254 62.484)
		(end 127.254 64.008)
		(width 0.5)
		(layer "F.Cu")
		(net 4)
	)
	(segment
		(start 146.994 66.087)
		(end 146.994 64.709)
		(width 0.5)
		(layer "F.Cu")
		(net 4)
	)
	(segment
		(start 134.294 66.087)
		(end 134.294 64.709)
		(width 0.5)
		(layer "F.Cu")
		(net 4)
	)
	(segment
		(start 147.804 66.087)
		(end 147.828 66.063)
		(width 0.5)
		(layer "F.Cu")
		(net 4)
	)
	(segment
		(start 130.481 96.318)
		(end 130.429 96.266)
		(width 0.5)
		(layer "F.Cu")
		(net 4)
	)
	(segment
		(start 139.192 64.008)
		(end 138.491 64.709)
		(width 0.5)
		(layer "F.Cu")
		(net 4)
	)
	(segment
		(start 180.2642 57.3282)
		(end 180.2054 57.387)
		(width 0.5)
		(layer "F.Cu")
		(net 4)
	)
	(segment
		(start 149.921 64.709)
		(end 146.1975 64.709)
		(width 0.5)
		(layer "F.Cu")
		(net 4)
	)
	(segment
		(start 162.052 64.008)
		(end 161.374 64.686)
		(width 0.5)
		(layer "F.Cu")
		(net 4)
	)
	(segment
		(start 180.2054 57.387)
		(end 179.259 57.387)
		(width 0.5)
		(layer "F.Cu")
		(net 4)
	)
	(segment
		(start 135.564 66.087)
		(end 135.564 64.709)
		(width 0.5)
		(layer "F.Cu")
		(net 4)
	)
	(segment
		(start 125.718 82.466)
		(end 124.956 83.228)
		(width 0.5)
		(layer "F.Cu")
		(net 4)
	)
	(segment
		(start 146.994 66.087)
		(end 147.804 66.087)
		(width 0.5)
		(layer "F.Cu")
		(net 4)
	)
	(segment
		(start 150.622 62.484)
		(end 150.622 64.008)
		(width 0.5)
		(layer "F.Cu")
		(net 4)
	)
	(segment
		(start 127.254 64.008)
		(end 126.553 64.709)
		(width 0.5)
		(layer "F.Cu")
		(net 4)
	)
	(segment
		(start 133.501 66.087)
		(end 134.294 66.087)
		(width 0.5)
		(layer "F.Cu")
		(net 4)
	)
	(segment
		(start 149.352 96.8)
		(end 149.352 97.89)
		(width 0.5)
		(layer "F.Cu")
		(net 4)
	)
	(segment
		(start 135.564 66.087)
		(end 136.374 66.087)
		(width 0.5)
		(layer "F.Cu")
		(net 4)
	)
	(segment
		(start 126.553 64.709)
		(end 122.8295 64.709)
		(width 0.5)
		(layer "F.Cu")
		(net 4)
	)
	(segment
		(start 145.724 66.087)
		(end 145.724 64.709)
		(width 0.5)
		(layer "F.Cu")
		(net 4)
	)
	(via
		(at 149.352 97.89)
		(size 0.6)
		(drill 0.35)
		(layers "F.Cu" "B.Cu")
		(net 4)
	)
	(via
		(at 147.828 66.063)
		(size 0.6)
		(drill 0.35)
		(layers "F.Cu" "B.Cu")
		(net 4)
	)
	(via
		(at 156.361 66.064)
		(size 0.6)
		(drill 0.35)
		(layers "F.Cu" "B.Cu")
		(net 4)
	)
	(via
		(at 136.398 66.063)
		(size 0.6)
		(drill 0.35)
		(layers "F.Cu" "B.Cu")
		(net 4)
	)
	(via
		(at 170.942 57.404)
		(size 0.6)
		(drill 0.35)
		(layers "F.Cu" "B.Cu")
		(free yes)
		(net 4)
	)
	(via
		(at 172.466 58.674)
		(size 0.6)
		(drill 0.35)
		(layers "F.Cu" "B.Cu")
		(free yes)
		(net 4)
	)
	(via
		(at 118.618 86.36)
		(size 0.6)
		(drill 0.35)
		(layers "F.Cu" "B.Cu")
		(net 4)
	)
	(via
		(at 180.2642 57.3282)
		(size 0.6)
		(drill 0.35)
		(layers "F.Cu" "B.Cu")
		(net 4)
	)
	(via
		(at 138.85 92.3)
		(size 0.6)
		(drill 0.35)
		(layers "F.Cu" "B.Cu")
		(net 4)
	)
	(via
		(at 130.429 96.266)
		(size 0.6)
		(drill 0.35)
		(layers "F.Cu" "B.Cu")
		(net 4)
	)
	(via
		(at 172.974 58.166)
		(size 0.6)
		(drill 0.35)
		(layers "F.Cu" "B.Cu")
		(free yes)
		(net 4)
	)
	(via
		(at 144.931 66.087)
		(size 0.6)
		(drill 0.35)
		(layers "F.Cu" "B.Cu")
		(net 4)
	)
	(via
		(at 171.45 58.674)
		(size 0.6)
		(drill 0.35)
		(layers "F.Cu" "B.Cu")
		(free yes)
		(net 4)
	)
	(via
		(at 170.942 58.166)
		(size 0.6)
		(drill 0.35)
		(layers "F.Cu" "B.Cu")
		(free yes)
		(net 4)
	)
	(via
		(at 129.921 80.964)
		(size 0.6)
		(drill 0.35)
		(layers "F.Cu" "B.Cu")
		(net 4)
	)
	(via
		(at 173.99 58.42)
		(size 0.6)
		(drill 0.35)
		(layers "F.Cu" "B.Cu")
		(free yes)
		(net 4)
	)
	(via
		(at 174.752 58.42)
		(size 0.6)
		(drill 0.35)
		(layers "F.Cu" "B.Cu")
		(free yes)
		(net 4)
	)
	(via
		(at 124.46 66.063)
		(size 0.6)
		(drill 0.35)
		(layers "F.Cu" "B.Cu")
		(net 4)
	)
	(via
		(at 172.974 57.404)
		(size 0.6)
		(drill 0.35)
		(layers "F.Cu" "B.Cu")
		(free yes)
		(net 4)
	)
	(via
		(at 131.953 80.964)
		(size 0.6)
		(drill 0.35)
		(layers "F.Cu" "B.Cu")
		(net 4)
	)
	(via
		(at 121.563 66.087)
		(size 0.6)
		(drill 0.35)
		(layers "F.Cu" "B.Cu")
		(net 4)
	)
	(via
		(at 159.258 66.04)
		(size 0.6)
		(drill 0.35)
		(layers "F.Cu" "B.Cu")
		(net 4)
	)
	(via
		(at 171.95 58.25)
		(size 0.6)
		(drill 0.35)
		(layers "F.Cu" "B.Cu")
		(free yes)
		(net 4)
	)
	(via
		(at 127.762 82.423)
		(size 0.6)
		(drill 0.35)
		(layers "F.Cu" "B.Cu")
		(net 4)
	)
	(via
		(at 133.501 66.087)
		(size 0.6)
		(drill 0.35)
		(layers "F.Cu" "B.Cu")
		(net 4)
	)
	(segment
		(start 138.4491 92.7009)
		(end 138.85 92.3)
		(width 0.187)
		(layer "In2.Cu")
		(net 4)
	)
	(segment
		(start 149.33 97.79)
		(end 148.67 98.45)
		(width 0.187)
		(layer "In2.Cu")
		(net 4)
	)
	(segment
		(start 118.618 86.36)
		(end 118.618 85.852)
		(width 0.5)
		(layer "In2.Cu")
		(net 4)
	)
	(segment
		(start 118.618 85.852)
		(end 120.396 84.074)
		(width 0.5)
		(layer "In2.Cu")
		(net 4)
	)
	(segment
		(start 138.4491 96.63557)
		(end 138.4491 92.7009)
		(width 0.187)
		(layer "In2.Cu")
		(net 4)
	)
	(segment
		(start 140.26353 98.45)
		(end 138.4491 96.63557)
		(width 0.187)
		(layer "In2.Cu")
		(net 4)
	)
	(segment
		(start 120.396 84.074)
		(end 125.476 84.074)
		(width 0.5)
		(layer "In2.Cu")
		(net 4)
	)
	(segment
		(start 127.127 82.423)
		(end 127.762 82.423)
		(width 0.5)
		(layer "In2.Cu")
		(net 4)
	)
	(segment
		(start 149.352 97.79)
		(end 149.33 97.79)
		(width 0.187)
		(layer "In2.Cu")
		(net 4)
	)
	(segment
		(start 148.67 98.45)
		(end 140.26353 98.45)
		(width 0.187)
		(layer "In2.Cu")
		(net 4)
	)
	(segment
		(start 125.476 84.074)
		(end 127.127 82.423)
		(width 0.5)
		(layer "In2.Cu")
		(net 4)
	)
	(segment
		(start 127.097 73.534)
		(end 125.658 73.534)
		(width 0.8)
		(layer "F.Cu")
		(net 5)
	)
	(segment
		(start 150.876 96.81)
		(end 150.876 97.89)
		(width 0.5)
		(layer "F.Cu")
		(net 5)
	)
	(segment
		(start 127.247 73.684)
		(end 127.097 73.534)
		(width 0.8)
		(layer "F.Cu")
		(net 5)
	)
	(segment
		(start 127.713 72.24)
		(end 127.247 72.706)
		(width 0.8)
		(layer "F.Cu")
		(net 5)
	)
	(segment
		(start 125.658 71.827)
		(end 125.658 70.358)
		(width 0.8)
		(layer "F.Cu")
		(net 5)
	)
	(segment
		(start 125.658 72.748)
		(end 125.658 72.589)
		(width 0.8)
		(layer "F.Cu")
		(net 5)
	)
	(segment
		(start 127.247 72.706)
		(end 127.247 73.684)
		(width 0.8)
		(layer "F.Cu")
		(net 5)
	)
	(segment
		(start 187.311 49.798)
		(end 187.311 51.1778)
		(width 0.8)
		(layer "F.Cu")
		(net 5)
	)
	(segment
		(start 187.325 49.784)
		(end 185.928 49.784)
		(width 0.8)
		(layer "F.Cu")
		(net 5)
	)
	(segment
		(start 120.578 70.964)
		(end 123.874 70.964)
		(width 0.8)
		(layer "F.Cu")
		(net 5)
	)
	(segment
		(start 123.874 70.964)
		(end 125.658 72.748)
		(width 0.8)
		(layer "F.Cu")
		(net 5)
	)
	(segment
		(start 188.66 49.784)
		(end 188.976 50.1)
		(width 0.8)
		(layer "F.Cu")
		(net 5)
	)
	(segment
		(start 125.658 72.748)
		(end 125.658 73.534)
		(width 0.8)
		(layer "F.Cu")
		(net 5)
	)
	(segment
		(start 187.325 49.784)
		(end 188.66 49.784)
		(width 0.8)
		(layer "F.Cu")
		(net 5)
	)
	(segment
		(start 150.876 97.8)
		(end 150.876 97.79)
		(width 0.187)
		(layer "F.Cu")
		(net 5)
	)
	(segment
		(start 125.658 72.589)
		(end 125.658 71.827)
		(width 0.8)
		(layer "F.Cu")
		(net 5)
	)
	(segment
		(start 187.325 49.784)
		(end 187.311 49.798)
		(width 0.8)
		(layer "F.Cu")
		(net 5)
	)
	(via
		(at 150.876 97.9)
		(size 0.6)
		(drill 0.35)
		(layers "F.Cu" "B.Cu")
		(net 5)
	)
	(via
		(at 125.658 70.358)
		(size 0.6)
		(drill 0.35)
		(layers "F.Cu" "B.Cu")
		(net 5)
	)
	(via
		(at 125.658 71.12)
		(size 0.6)
		(drill 0.35)
		(layers "F.Cu" "B.Cu")
		(net 5)
	)
	(via
		(at 188.087 49.784)
		(size 0.6)
		(drill 0.35)
		(layers "F.Cu" "B.Cu")
		(net 5)
	)
	(via
		(at 125.658 72.589)
		(size 0.6)
		(drill 0.35)
		(layers "F.Cu" "B.Cu")
		(net 5)
	)
	(via
		(at 186.647666 49.784)
		(size 0.6)
		(drill 0.35)
		(layers "F.Cu" "B.Cu")
		(net 5)
	)
	(via
		(at 125.658 71.827)
		(size 0.6)
		(drill 0.35)
		(layers "F.Cu" "B.Cu")
		(net 5)
	)
	(via
		(at 160.14 96.24)
		(size 0.6)
		(drill 0.35)
		(layers "F.Cu" "B.Cu")
		(net 5)
	)
	(via
		(at 187.367332 49.784)
		(size 0.6)
		(drill 0.35)
		(layers "F.Cu" "B.Cu")
		(net 5)
	)
	(via
		(at 185.928 49.784)
		(size 0.6)
		(drill 0.35)
		(layers "F.Cu" "B.Cu")
		(net 5)
	)
	(via
		(at 147.073777 97.434046)
		(size 0.6)
		(drill 0.35)
		(layers "F.Cu" "B.Cu")
		(net 5)
	)
	(segment
		(start 146.291605 96.865897)
		(end 146.321605 96.835897)
		(width 0.187)
		(layer "B.Cu")
		(net 5)
	)
	(segment
		(start 159.524103 96.855897)
		(end 158.500124 96.855897)
		(width 0.187)
		(layer "B.Cu")
		(net 5)
	)
	(segment
		(start 144.766904 96.865897)
		(end 146.291605 96.865897)
		(width 0.187)
		(layer "B.Cu")
		(net 5)
	)
	(segment
		(start 160.14 96.24)
		(end 159.524103 96.855897)
		(width 0.187)
		(layer "B.Cu")
		(net 5)
	)
	(segment
		(start 147.073777 97.434046)
		(end 147.073777 97.063777)
		(width 0.187)
		(layer "B.Cu")
		(net 5)
	)
	(segment
		(start 147.073777 97.063777)
		(end 146.845897 96.835897)
		(width 0.187)
		(layer "B.Cu")
		(net 5)
	)
	(segment
		(start 146.845897 96.835897)
		(end 146.321605 96.835897)
		(width 0.187)
		(layer "B.Cu")
		(net 5)
	)
	(segment
		(start 125.078 68.961)
		(end 125.658 69.541)
		(width 0.8)
		(layer "In2.Cu")
		(net 5)
	)
	(segment
		(start 120.206 97.6)
		(end 116.84 94.234)
		(width 0.3)
		(layer "In2.Cu")
		(net 5)
	)
	(segment
		(start 157.736505 97.38)
		(end 157.316005 96.9595)
		(width 0.187)
		(layer "In2.Cu")
		(net 5)
	)
	(segment
		(start 160.14 96.24)
		(end 159 97.38)
		(width 0.187)
		(layer "In2.Cu")
		(net 5)
	)
	(segment
		(start 151.4045 97.2715)
		(end 150.876 97.8)
		(width 0.187)
		(layer "In2.Cu")
		(net 5)
	)
	(segment
		(start 118.745 67.691)
		(end 120.015 68.961)
		(width 0.8)
		(layer "In2.Cu")
		(net 5)
	)
	(segment
		(start 184.15 49.784)
		(end 178.3466 55.5874)
		(width 0.8)
		(layer "In2.Cu")
		(net 5)
	)
	(segment
		(start 185.928 49.784)
		(end 184.15 49.784)
		(width 0.8)
		(layer "In2.Cu")
		(net 5)
	)
	(segment
		(start 164.6306 55.5874)
		(end 161.417 58.801)
		(width 0.8)
		(layer "In2.Cu")
		(net 5)
	)
	(segment
		(start 157.316005 96.9595)
		(end 155.837265 96.9595)
		(width 0.187)
		(layer "In2.Cu")
		(net 5)
	)
	(segment
		(start 159 97.38)
		(end 157.736505 97.38)
		(width 0.187)
		(layer "In2.Cu")
		(net 5)
	)
	(segment
		(start 123.88 71.12)
		(end 125.658 71.12)
		(width 0.3)
		(layer "In2.Cu")
		(net 5)
	)
	(segment
		(start 123.3 72.8)
		(end 123.3 71.7)
		(width 0.3)
		(layer "In2.Cu")
		(net 5)
	)
	(segment
		(start 116.84 79.26)
		(end 123.3 72.8)
		(width 0.3)
		(layer "In2.Cu")
		(net 5)
	)
	(segment
		(start 178.3466 55.5874)
		(end 164.6306 55.5874)
		(width 0.8)
		(layer "In2.Cu")
		(net 5)
	)
	(segment
		(start 118.745 59.817)
		(end 118.745 67.691)
		(width 0.8)
		(layer "In2.Cu")
		(net 5)
	)
	(segment
		(start 188.468 49.784)
		(end 185.928 49.784)
		(width 0.8)
		(layer "In2.Cu")
		(net 5)
	)
	(segment
		(start 150.876 97.8)
		(end 150.326 97.25)
		(width 0.187)
		(layer "In2.Cu")
		(net 5)
	)
	(segment
		(start 155.525265 97.2715)
		(end 151.4045 97.2715)
		(width 0.187)
		(layer "In2.Cu")
		(net 5)
	)
	(segment
		(start 161.417 58.801)
		(end 119.761 58.801)
		(width 0.8)
		(layer "In2.Cu")
		(net 5)
	)
	(segment
		(start 155.837265 96.9595)
		(end 155.525265 97.2715)
		(width 0.187)
		(layer "In2.Cu")
		(net 5)
	)
	(segment
		(start 120.015 68.961)
		(end 125.078 68.961)
		(width 0.8)
		(layer "In2.Cu")
		(net 5)
	)
	(segment
		(start 123.3 71.7)
		(end 123.88 71.12)
		(width 0.3)
		(layer "In2.Cu")
		(net 5)
	)
	(segment
		(start 139.926846 98.8195)
		(end 138.707346 97.6)
		(width 0.3)
		(layer "In2.Cu")
		(net 5)
	)
	(segment
		(start 138.707346 97.6)
		(end 120.206 97.6)
		(width 0.3)
		(layer "In2.Cu")
		(net 5)
	)
	(segment
		(start 150.876 97.8)
		(end 150.7 97.8)
		(width 0.3)
		(layer "In2.Cu")
		(net 5)
	)
	(segment
		(start 125.658 69.541)
		(end 125.658 72.589)
		(width 0.8)
		(layer "In2.Cu")
		(net 5)
	)
	(segment
		(start 119.761 58.801)
		(end 118.745 59.817)
		(width 0.8)
		(layer "In2.Cu")
		(net 5)
	)
	(segment
		(start 149.6805 98.8195)
		(end 139.926846 98.8195)
		(width 0.3)
		(layer "In2.Cu")
		(net 5)
	)
	(segment
		(start 150.326 97.25)
		(end 147.257823 97.25)
		(width 0.187)
		(layer "In2.Cu")
		(net 5)
	)
	(segment
		(start 147.257823 97.25)
		(end 147.073777 97.434046)
		(width 0.187)
		(layer "In2.Cu")
		(net 5)
	)
	(segment
		(start 150.7 97.8)
		(end 149.6805 98.8195)
		(width 0.3)
		(layer "In2.Cu")
		(net 5)
	)
	(segment
		(start 116.84 94.234)
		(end 116.84 79.26)
		(width 0.3)
		(layer "In2.Cu")
		(net 5)
	)
	(segment
		(start 137.22 93.655)
		(end 137.567 93.308)
		(width 0.5)
		(layer "F.Cu")
		(net 6)
	)
	(segment
		(start 136.072 93.655)
		(end 137.22 93.655)
		(width 0.5)
		(layer "F.Cu")
		(net 6)
	)
	(segment
		(start 135.62 91.554)
		(end 135.619 91.555)
		(width 0.5)
		(layer "F.Cu")
		(net 7)
	)
	(segment
		(start 133.472 94.606)
		(end 134.294 94.606)
		(width 0.5)
		(layer "F.Cu")
		(net 7)
	)
	(segment
		(start 134.294 94.606)
		(end 134.802 94.098)
		(width 0.5)
		(layer "F.Cu")
		(net 7)
	)
	(segment
		(start 134.802 94.098)
		(end 134.802 92.372)
		(width 0.5)
		(layer "F.Cu")
		(net 7)
	)
	(segment
		(start 134.802 92.372)
		(end 135.619 91.555)
		(width 0.5)
		(layer "F.Cu")
		(net 7)
	)
	(segment
		(start 137.059 91.554)
		(end 135.62 91.554)
		(width 0.5)
		(layer "F.Cu")
		(net 7)
	)
	(segment
		(start 137.567 92.062)
		(end 137.059 91.554)
		(width 0.5)
		(layer "F.Cu")
		(net 7)
	)
	(segment
		(start 137.567 92.34)
		(end 137.567 92.062)
		(width 0.5)
		(layer "F.Cu")
		(net 7)
	)
	(segment
		(start 120.832 85.472)
		(end 121.205233 85.472)
		(width 0.5)
		(layer "F.Cu")
		(net 8)
	)
	(segment
		(start 121.205233 85.472)
		(end 121.552233 85.125)
		(width 0.5)
		(layer "F.Cu")
		(net 8)
	)
	(segment
		(start 121.552233 85.125)
		(end 122.327 85.125)
		(width 0.5)
		(layer "F.Cu")
		(net 8)
	)
	(segment
		(start 123.626 86.412)
		(end 122.809 87.229)
		(width 0.5)
		(layer "F.Cu")
		(net 9)
	)
	(segment
		(start 120.832 86.44)
		(end 120.832 86.718)
		(width 0.5)
		(layer "F.Cu")
		(net 9)
	)
	(segment
		(start 121.339 87.225)
		(end 122.78 87.225)
		(width 0.5)
		(layer "F.Cu")
		(net 9)
	)
	(segment
		(start 123.626 84.686)
		(end 123.626 86.412)
		(width 0.5)
		(layer "F.Cu")
		(net 9)
	)
	(segment
		(start 124.956 84.178)
		(end 124.134 84.178)
		(width 0.5)
		(layer "F.Cu")
		(net 9)
	)
	(segment
		(start 124.134 84.178)
		(end 123.626 84.686)
		(width 0.5)
		(layer "F.Cu")
		(net 9)
	)
	(segment
		(start 120.832 86.718)
		(end 121.339 87.225)
		(width 0.5)
		(layer "F.Cu")
		(net 9)
	)
	(segment
		(start 133.027 91.555)
		(end 133.419 91.555)
		(width 0.5)
		(layer "F.Cu")
		(net 10)
	)
	(segment
		(start 130.963 92.594)
		(end 131.52 92.594)
		(width 0.5)
		(layer "F.Cu")
		(net 10)
	)
	(segment
		(start 131.5 92.574)
		(end 131.52 92.594)
		(width 0.5)
		(layer "F.Cu")
		(net 10)
	)
	(segment
		(start 132.042 91.555)
		(end 133.027 91.555)
		(width 0.5)
		(layer "F.Cu")
		(net 10)
	)
	(segment
		(start 133.027 91.555)
		(end 131.725 91.555)
		(width 0.5)
		(layer "F.Cu")
		(net 10)
	)
	(segment
		(start 138.8388 96.4208)
		(end 138.5594 96.1414)
		(width 0.5)
		(layer "F.Cu")
		(net 10)
	)
	(segment
		(start 131.52 92.594)
		(end 131.98 92.594)
		(width 0.5)
		(layer "F.Cu")
		(net 10)
	)
	(segment
		(start 138.5594 96.1414)
		(end 138.5594 95.6056)
		(width 0.5)
		(layer "F.Cu")
		(net 10)
	)
	(segment
		(start 131.725 91.555)
		(end 131.5 91.78)
		(width 0.5)
		(layer "F.Cu")
		(net 10)
	)
	(segment
		(start 131.5 91.78)
		(end 131.5 92.574)
		(width 0.5)
		(layer "F.Cu")
		(net 10)
	)
	(segment
		(start 138.9676 96.4208)
		(end 138.8388 96.4208)
		(width 0.5)
		(layer "F.Cu")
		(net 10)
	)
	(segment
		(start 131.725 91.238)
		(end 132.042 91.555)
		(width 0.5)
		(layer "F.Cu")
		(net 10)
	)
	(via
		(at 131.4704 92.0496)
		(size 0.6)
		(drill 0.35)
		(layers "F.Cu" "B.Cu")
		(net 10)
	)
	(via
		(at 138.9676 96.4208)
		(size 0.6)
		(drill 0.35)
		(layers "F.Cu" "B.Cu")
		(net 10)
	)
	(via
		(at 144.78 97.89)
		(size 0.6)
		(drill 0.35)
		(layers "F.Cu" "B.Cu")
		(net 10)
	)
	(segment
		(start 134.651234 89.7)
		(end 133.735617 90.615617)
		(width 0.187)
		(layer "B.Cu")
		(net 10)
	)
	(segment
		(start 138.9676 96.4208)
		(end 136.9338 96.4208)
		(width 0.5)
		(layer "B.Cu")
		(net 10)
	)
	(segment
		(start 137.26 89.93)
		(end 137.7 89.49)
		(width 0.187)
		(layer "B.Cu")
		(net 10)
	)
	(segment
		(start 136.9338 96.4208)
		(end 132.5626 92.0496)
		(width 0.5)
		(layer "B.Cu")
		(net 10)
	)
	(segment
		(start 136.55 89.93)
		(end 135.84 89.93)
		(width 0.187)
		(layer "B.Cu")
		(net 10)
	)
	(segment
		(start 137.7 89.49)
		(end 137.7 89)
		(width 0.187)
		(layer "B.Cu")
		(net 10)
	)
	(segment
		(start 135.84 89.93)
		(end 135.61 89.7)
		(width 0.187)
		(layer "B.Cu")
		(net 10)
	)
	(segment
		(start 131.4704 92.0496)
		(end 132.5626 92.0496)
		(width 0.5)
		(layer "B.Cu")
		(net 10)
	)
	(segment
		(start 135.61 89.7)
		(end 134.651234 89.7)
		(width 0.187)
		(layer "B.Cu")
		(net 10)
	)
	(segment
		(start 133.735617 90.615617)
		(end 133.735617 90.876583)
		(width 0.187)
		(layer "B.Cu")
		(net 10)
	)
	(segment
		(start 133.735617 90.876583)
		(end 132.5626 92.0496)
		(width 0.187)
		(layer "B.Cu")
		(net 10)
	)
	(segment
		(start 136.55 89.93)
		(end 137.26 89.93)
		(width 0.187)
		(layer "B.Cu")
		(net 10)
	)
	(segment
		(start 138.9676 96.4208)
		(end 142.2208 96.4208)
		(width 0.187)
		(layer "In2.Cu")
		(net 10)
	)
	(segment
		(start 143.69 97.89)
		(end 144.78 97.89)
		(width 0.187)
		(layer "In2.Cu")
		(net 10)
	)
	(segment
		(start 142.2208 96.4208)
		(end 143.69 97.89)
		(width 0.187)
		(layer "In2.Cu")
		(net 10)
	)
	(segment
		(start 128.651 86.233)
		(end 128.166 86.718)
		(width 0.187)
		(layer "F.Cu")
		(net 11)
	)
	(segment
		(start 119.839 83.162)
		(end 119.839 82.501)
		(width 0.5)
		(layer "F.Cu")
		(net 11)
	)
	(segment
		(start 128.651 85.598)
		(end 128.651 86.233)
		(width 0.187)
		(layer "F.Cu")
		(net 11)
	)
	(segment
		(start 142.481234 98.5)
		(end 145.694 98.5)
		(width 0.187)
		(layer "F.Cu")
		(net 11)
	)
	(segment
		(start 128.166 86.718)
		(end 126.928 86.718)
		(width 0.187)
		(layer "F.Cu")
		(net 11)
	)
	(segment
		(start 141.884 97.902766)
		(end 142.481234 98.5)
		(width 0.187)
		(layer "F.Cu")
		(net 11)
	)
	(segment
		(start 126.908 86.19)
		(end 126.448 86.19)
		(width 0.5)
		(layer "F.Cu")
		(net 11)
	)
	(segment
		(start 126.928 86.718)
		(end 126.928 86.21)
		(width 0.5)
		(layer "F.Cu")
		(net 11)
	)
	(segment
		(start 125.401 87.229)
		(end 126.417 87.229)
		(width 0.5)
		(layer "F.Cu")
		(net 11)
	)
	(segment
		(start 126.417 87.229)
		(end 126.928 86.718)
		(width 0.5)
		(layer "F.Cu")
		(net 11)
	)
	(segment
		(start 126.386 87.229)
		(end 125.401 87.229)
		(width 0.5)
		(layer "F.Cu")
		(net 11)
	)
	(segment
		(start 119.839 82.501)
		(end 119.6848 82.3468)
		(width 0.5)
		(layer "F.Cu")
		(net 11)
	)
	(segment
		(start 119.6848 82.3468)
		(end 119.4308 82.3468)
		(width 0.5)
		(layer "F.Cu")
		(net 11)
	)
	(segment
		(start 125.401 87.229)
		(end 125.009 87.229)
		(width 0.5)
		(layer "F.Cu")
		(net 11)
	)
	(segment
		(start 141.884 95.2265)
		(end 141.884 97.902766)
		(width 0.187)
		(layer "F.Cu")
		(net 11)
	)
	(segment
		(start 145.694 98.5)
		(end 146.304 97.89)
		(width 0.187)
		(layer "F.Cu")
		(net 11)
	)
	(segment
		(start 126.703 87.546)
		(end 126.386 87.229)
		(width 0.5)
		(layer "F.Cu")
		(net 11)
	)
	(segment
		(start 127.465 86.19)
		(end 126.908 86.19)
		(width 0.5)
		(layer "F.Cu")
		(net 11)
	)
	(segment
		(start 129.286 84.963)
		(end 128.651 85.598)
		(width 0.187)
		(layer "F.Cu")
		(net 11)
	)
	(segment
		(start 126.928 86.21)
		(end 126.908 86.19)
		(width 0.5)
		(layer "F.Cu")
		(net 11)
	)
	(segment
		(start 142.0905 95.02)
		(end 141.884 95.2265)
		(width 0.187)
		(layer "F.Cu")
		(net 11)
	)
	(via
		(at 126.928 86.718)
		(size 0.6)
		(drill 0.35)
		(layers "F.Cu" "B.Cu")
		(net 11)
	)
	(via
		(at 142.0905 95.02)
		(size 0.6)
		(drill 0.35)
		(layers "F.Cu" "B.Cu")
		(net 11)
	)
	(via
		(at 129.286 84.963)
		(size 0.6)
		(drill 0.35)
		(layers "F.Cu" "B.Cu")
		(net 11)
	)
	(via
		(at 146.304 97.89)
		(size 0.6)
		(drill 0.35)
		(layers "F.Cu" "B.Cu")
		(net 11)
	)
	(via
		(at 119.4308 82.3468)
		(size 0.6)
		(drill 0.35)
		(layers "F.Cu" "B.Cu")
		(net 11)
	)
	(segment
		(start 134.4 89.51)
		(end 134.4 89)
		(width 0.187)
		(layer "B.Cu")
		(net 11)
	)
	(segment
		(start 128.91 88.7)
		(end 126.928 86.718)
		(width 0.187)
		(layer "B.Cu")
		(net 11)
	)
	(segment
		(start 123.6472 85.852)
		(end 120.142 82.3468)
		(width 0.5)
		(layer "B.Cu")
		(net 11)
	)
	(segment
		(start 133.98 89.93)
		(end 134.4 89.51)
		(width 0.187)
		(layer "B.Cu")
		(net 11)
	)
	(segment
		(start 133.25 89.93)
		(end 131.48 89.93)
		(width 0.187)
		(layer "B.Cu")
		(net 11)
	)
	(segment
		(start 126.062 85.852)
		(end 123.6472 85.852)
		(width 0.5)
		(layer "B.Cu")
		(net 11)
	)
	(segment
		(start 133.25 89.93)
		(end 133.98 89.93)
		(width 0.187)
		(layer "B.Cu")
		(net 11)
	)
	(segment
		(start 120.142 82.3468)
		(end 119.4308 82.3468)
		(width 0.5)
		(layer "B.Cu")
		(net 11)
	)
	(segment
		(start 131.48 89.93)
		(end 130.25 88.7)
		(width 0.187)
		(layer "B.Cu")
		(net 11)
	)
	(segment
		(start 130.25 88.7)
		(end 128.91 88.7)
		(width 0.187)
		(layer "B.Cu")
		(net 11)
	)
	(segment
		(start 126.928 86.718)
		(end 126.062 85.852)
		(width 0.5)
		(layer "B.Cu")
		(net 11)
	)
	(segment
		(start 139.954 94.742)
		(end 139.954 91.8845)
		(width 0.187)
		(layer "In2.Cu")
		(net 11)
	)
	(segment
		(start 128.651 90.297)
		(end 128.651 85.598)
		(width 0.187)
		(layer "In2.Cu")
		(net 11)
	)
	(segment
		(start 128.651 85.598)
		(end 129.286 84.963)
		(width 0.187)
		(layer "In2.Cu")
		(net 11)
	)
	(segment
		(start 139.1285 91.059)
		(end 129.413 91.059)
		(width 0.187)
		(layer "In2.Cu")
		(net 11)
	)
	(segment
		(start 139.954 91.8845)
		(end 139.1285 91.059)
		(width 0.187)
		(layer "In2.Cu")
		(net 11)
	)
	(segment
		(start 129.413 91.059)
		(end 128.651 90.297)
		(width 0.187)
		(layer "In2.Cu")
		(net 11)
	)
	(segment
		(start 142.0905 95.02)
		(end 140.232 95.02)
		(width 0.187)
		(layer "In2.Cu")
		(net 11)
	)
	(segment
		(start 140.232 95.02)
		(end 139.954 94.742)
		(width 0.187)
		(layer "In2.Cu")
		(net 11)
	)
	(segment
		(start 149.733 70.863976)
		(end 149.652024 70.783)
		(width 0.187)
		(layer "F.Cu")
		(net 12)
	)
	(segment
		(start 149.652024 70.783)
		(end 148.349 70.783)
		(width 0.187)
		(layer "F.Cu")
		(net 12)
	)
	(segment
		(start 149.733 71.1948)
		(end 149.733 70.863976)
		(width 0.187)
		(layer "F.Cu")
		(net 12)
	)
	(segment
		(start 147.248 71.884)
		(end 147.248 73.002)
		(width 0.125)
		(layer "F.Cu")
		(net 12)
	)
	(segment
		(start 147.248 73.002)
		(end 145.655052 74.594948)
		(width 0.125)
		(layer "F.Cu")
		(net 12)
	)
	(segment
		(start 145.655052 76.121386)
		(end 146.072218 76.538552)
		(width 0.125)
		(layer "F.Cu")
		(net 12)
	)
	(segment
		(start 145.655052 74.594948)
		(end 145.655052 76.121386)
		(width 0.125)
		(layer "F.Cu")
		(net 12)
	)
	(segment
		(start 148.349 70.783)
		(end 147.248 71.884)
		(width 0.125)
		(layer "F.Cu")
		(net 12)
	)
	(segment
		(start 140.446 77.2)
		(end 140.16924 76.92324)
		(width 0.2)
		(layer "F.Cu")
		(net 13)
	)
	(segment
		(start 141.307787 77.2)
		(end 140.446 77.2)
		(width 0.2)
		(layer "F.Cu")
		(net 13)
	)
	(segment
		(start 142.51 78.631774)
		(end 142.51 78.402213)
		(width 0.2)
		(layer "F.Cu")
		(net 13)
	)
	(segment
		(start 143.244498 79.366272)
		(end 142.51 78.631774)
		(width 0.2)
		(layer "F.Cu")
		(net 13)
	)
	(segment
		(start 141.590373 77.482586)
		(end 141.307787 77.2)
		(width 0.2)
		(layer "F.Cu")
		(net 13)
	)
	(segment
		(start 142.51 78.402213)
		(end 141.590373 77.482586)
		(width 0.2)
		(layer "F.Cu")
		(net 13)
	)
	(segment
		(start 145.011557 77.599212)
		(end 144.372345 76.96)
		(width 0.2)
		(layer "F.Cu")
		(net 14)
	)
	(segment
		(start 144.372345 76.96)
		(end 143.896213 76.96)
		(width 0.2)
		(layer "F.Cu")
		(net 14)
	)
	(segment
		(start 143.004586 76.068373)
		(end 142.75 75.813787)
		(width 0.2)
		(layer "F.Cu")
		(net 14)
	)
	(segment
		(start 143.605627 76.669414)
		(end 143.004586 76.068373)
		(width 0.2)
		(layer "F.Cu")
		(net 14)
	)
	(segment
		(start 142.75 75.813787)
		(end 142.75 74.932)
		(width 0.2)
		(layer "F.Cu")
		(net 14)
	)
	(segment
		(start 143.896213 76.96)
		(end 143.605627 76.669414)
		(width 0.2)
		(layer "F.Cu")
		(net 14)
	)
	(segment
		(start 142.75 74.932)
		(end 142.45524 74.63724)
		(width 0.2)
		(layer "F.Cu")
		(net 14)
	)
	(segment
		(start 150.143414 76.547728)
		(end 150.495 76.196142)
		(width 0.2)
		(layer "F.Cu")
		(net 15)
	)
	(segment
		(start 148.942175 77.47)
		(end 149.221142 77.47)
		(width 0.2)
		(layer "F.Cu")
		(net 15)
	)
	(segment
		(start 149.221142 77.47)
		(end 149.542373 77.148769)
		(width 0.2)
		(layer "F.Cu")
		(net 15)
	)
	(segment
		(start 148.45941 77.952765)
		(end 148.942175 77.47)
		(width 0.2)
		(layer "F.Cu")
		(net 15)
	)
	(segment
		(start 150.495 75.311)
		(end 150.78776 75.01824)
		(width 0.2)
		(layer "F.Cu")
		(net 15)
	)
	(segment
		(start 150.495 76.196142)
		(end 150.495 75.311)
		(width 0.2)
		(layer "F.Cu")
		(net 15)
	)
	(segment
		(start 149.542373 77.148769)
		(end 150.143414 76.547728)
		(width 0.2)
		(layer "F.Cu")
		(net 15)
	)
	(segment
		(start 150.22647 79.719825)
		(end 150.622 79.324295)
		(width 0.2)
		(layer "F.Cu")
		(net 16)
	)
	(segment
		(start 152.781 77.597)
		(end 153.07376 77.30424)
		(width 0.2)
		(layer "F.Cu")
		(net 16)
	)
	(segment
		(start 150.956586 78.562982)
		(end 151.557627 77.961941)
		(width 0.2)
		(layer "F.Cu")
		(net 16)
	)
	(segment
		(start 151.922568 77.597)
		(end 152.781 77.597)
		(width 0.2)
		(layer "F.Cu")
		(net 16)
	)
	(segment
		(start 151.557627 77.961941)
		(end 151.922568 77.597)
		(width 0.2)
		(layer "F.Cu")
		(net 16)
	)
	(segment
		(start 150.622 79.324295)
		(end 150.622 78.897568)
		(width 0.2)
		(layer "F.Cu")
		(net 16)
	)
	(segment
		(start 150.622 78.897568)
		(end 150.956586 78.562982)
		(width 0.2)
		(layer "F.Cu")
		(net 16)
	)
	(segment
		(start 144.708 73.175)
		(end 144.708 72.582)
		(width 0.125)
		(layer "F.Cu")
		(net 17)
	)
	(segment
		(start 144.653 72.112)
		(end 144.653 72.517)
		(width 0.125)
		(layer "F.Cu")
		(net 17)
	)
	(segment
		(start 144.653 72.517)
		(end 144.718 72.582)
		(width 0.125)
		(layer "F.Cu")
		(net 17)
	)
	(segment
		(start 144.708 72.582)
		(end 145.123 72.582)
		(width 0.125)
		(layer "F.Cu")
		(net 17)
	)
	(segment
		(start 144.718 72.582)
		(end 145.123 72.582)
		(width 0.125)
		(layer "F.Cu")
		(net 17)
	)
	(segment
		(start 145.123 72.582)
		(end 146.049 72.582)
		(width 0.125)
		(layer "F.Cu")
		(net 17)
	)
	(segment
		(start 142.865333 78.28)
		(end 142.84 78.28)
		(width 0.2)
		(layer "F.Cu")
		(net 18)
	)
	(segment
		(start 141.649893 76.835)
		(end 141.605 76.835)
		(width 0.2)
		(layer "F.Cu")
		(net 18)
	)
	(segment
		(start 141.943926 77.129033)
		(end 141.649893 76.835)
		(width 0.2)
		(layer "F.Cu")
		(net 18)
	)
	(segment
		(start 143.598051 79.012718)
		(end 142.865333 78.28)
		(width 0.2)
		(layer "F.Cu")
		(net 18)
	)
	(segment
		(start 142.84 78.28)
		(end 142.84 78.025107)
		(width 0.2)
		(layer "F.Cu")
		(net 18)
	)
	(segment
		(start 142.544967 77.730074)
		(end 141.943926 77.129033)
		(width 0.2)
		(layer "F.Cu")
		(net 18)
	)
	(segment
		(start 141.605 76.835)
		(end 140.93124 76.16124)
		(width 0.2)
		(layer "F.Cu")
		(net 18)
	)
	(segment
		(start 142.84 78.025107)
		(end 142.544967 77.730074)
		(width 0.2)
		(layer "F.Cu")
		(net 18)
	)
	(segment
		(start 139.407947 74.637947)
		(end 140.24676 75.47676)
		(width 0.2)
		(layer "F.Cu")
		(net 19)
	)
	(segment
		(start 144.658004 77.952765)
		(end 144.005239 77.3)
		(width 0.2)
		(layer "F.Cu")
		(net 20)
	)
	(segment
		(start 142.367 76.137893)
		(end 142.367 76.073)
		(width 0.2)
		(layer "F.Cu")
		(net 20)
	)
	(segment
		(start 143.529107 77.3)
		(end 143.252074 77.022967)
		(width 0.2)
		(layer "F.Cu")
		(net 20)
	)
	(segment
		(start 142.651033 76.421926)
		(end 142.367 76.137893)
		(width 0.2)
		(layer "F.Cu")
		(net 20)
	)
	(segment
		(start 144.005239 77.3)
		(end 143.529107 77.3)
		(width 0.2)
		(layer "F.Cu")
		(net 20)
	)
	(segment
		(start 143.252074 77.022967)
		(end 142.651033 76.421926)
		(width 0.2)
		(layer "F.Cu")
		(net 20)
	)
	(segment
		(start 142.367 76.073)
		(end 141.69324 75.39924)
		(width 0.2)
		(layer "F.Cu")
		(net 20)
	)
	(segment
		(start 141.00876 74.71476)
		(end 140.169947 73.875947)
		(width 0.2)
		(layer "F.Cu")
		(net 21)
	)
	(segment
		(start 150.876 76.522248)
		(end 150.876 76.454)
		(width 0.2)
		(layer "F.Cu")
		(net 22)
	)
	(segment
		(start 150.496967 76.901281)
		(end 150.876 76.522248)
		(width 0.2)
		(layer "F.Cu")
		(net 22)
	)
	(segment
		(start 149.547248 77.851)
		(end 150.496967 76.901281)
		(width 0.2)
		(layer "F.Cu")
		(net 22)
	)
	(segment
		(start 149.268283 77.851)
		(end 149.547248 77.851)
		(width 0.2)
		(layer "F.Cu")
		(net 22)
	)
	(segment
		(start 148.812964 78.306319)
		(end 149.268283 77.851)
		(width 0.2)
		(layer "F.Cu")
		(net 22)
	)
	(segment
		(start 150.876 76.454)
		(end 151.54976 75.78024)
		(width 0.2)
		(layer "F.Cu")
		(net 22)
	)
	(segment
		(start 152.23424 75.09576)
		(end 153.073053 74.256947)
		(width 0.2)
		(layer "F.Cu")
		(net 23)
	)
	(segment
		(start 150.241 78.571462)
		(end 150.603033 78.209429)
		(width 0.2)
		(layer "F.Cu")
		(net 24)
	)
	(segment
		(start 150.603033 78.209429)
		(end 151.204074 77.608388)
		(width 0.2)
		(layer "F.Cu")
		(net 24)
	)
	(segment
		(start 151.596462 77.216)
		(end 151.638 77.216)
		(width 0.2)
		(layer "F.Cu")
		(net 24)
	)
	(segment
		(start 151.204074 77.608388)
		(end 151.596462 77.216)
		(width 0.2)
		(layer "F.Cu")
		(net 24)
	)
	(segment
		(start 151.638 77.216)
		(end 152.31176 76.54224)
		(width 0.2)
		(layer "F.Cu")
		(net 24)
	)
	(segment
		(start 149.872917 79.366272)
		(end 149.872917 79.362083)
		(width 0.2)
		(layer "F.Cu")
		(net 24)
	)
	(segment
		(start 149.872917 79.362083)
		(end 150.241 78.994)
		(width 0.2)
		(layer "F.Cu")
		(net 24)
	)
	(segment
		(start 150.241 78.994)
		(end 150.241 78.571462)
		(width 0.2)
		(layer "F.Cu")
		(net 24)
	)
	(segment
		(start 152.99624 75.85776)
		(end 153.835053 75.018947)
		(width 0.2)
		(layer "F.Cu")
		(net 25)
	)
	(segment
		(start 143.441 77.909)
		(end 143.441 78.149975)
		(width 0.187)
		(layer "F.Cu")
		(net 26)
	)
	(segment
		(start 143.441 78.149975)
		(end 143.950897 78.659872)
		(width 0.187)
		(layer "F.Cu")
		(net 26)
	)
	(segment
		(start 148.96 79.572081)
		(end 149.519363 79.012718)
		(width 0.187)
		(layer "F.Cu")
		(net 26)
	)
	(segment
		(start 148.96 79.8)
		(end 148.96 79.572081)
		(width 0.187)
		(layer "F.Cu")
		(net 26)
	)
	(via
		(at 148.96 79.8)
		(size 0.6)
		(drill 0.35)
		(layers "F.Cu" "B.Cu")
		(net 26)
	)
	(via
		(at 143.441 77.909)
		(size 0.6)
		(drill 0.35)
		(layers "F.Cu" "B.Cu")
		(net 26)
	)
	(segment
		(start 151.044589 78.813151)
		(end 151.026671 78.813151)
		(width 0.3)
		(layer "B.Cu")
		(net 26)
	)
	(segment
		(start 141.118 78.38)
		(end 141.38 78.38)
		(width 0.5)
		(layer "B.Cu")
		(net 26)
	)
	(segment
		(start 140.559 77.821)
		(end 141.118 78.38)
		(width 0.5)
		(layer "B.Cu")
		(net 26)
	)
	(segment
		(start 151.04176 78.81598)
		(end 151.0295 78.81598)
		(width 0.187)
		(layer "B.Cu")
		(net 26)
	)
	(segment
		(start 135.1 82.702)
		(end 136.119 82.702)
		(width 0.5)
		(layer "B.Cu")
		(net 26)
	)
	(segment
		(start 136.119 82.702)
		(end 137.4648 81.3562)
		(width 0.5)
		(layer "B.Cu")
		(net 26)
	)
	(segment
		(start 151.0295 78.81598)
		(end 150.27976 78.06624)
		(width 0.187)
		(layer "B.Cu")
		(net 26)
	)
	(segment
		(start 151.026671 78.813151)
		(end 150.27976 78.06624)
		(width 0.3)
		(layer "B.Cu")
		(net 26)
	)
	(segment
		(start 149.115 79.225)
		(end 149.82 78.52)
		(width 0.5)
		(layer "B.Cu")
		(net 26)
	)
	(segment
		(start 150.27376 78.06624)
		(end 150.27976 78.06624)
		(width 0.3)
		(layer "B.Cu")
		(net 26)
	)
	(segment
		(start 148.96 79.8)
		(end 148.785 79.975)
		(width 0.5)
		(layer "B.Cu")
		(net 26)
	)
	(segment
		(start 134.343 82.702)
		(end 135.1 82.702)
		(width 0.3)
		(layer "B.Cu")
		(net 26)
	)
	(segment
		(start 148.96 79.8)
		(end 149.115 79.645)
		(width 0.5)
		(layer "B.Cu")
		(net 26)
	)
	(segment
		(start 141.38 78.38)
		(end 141.390253 78.390253)
		(width 0.5)
		(layer "B.Cu")
		(net 26)
	)
	(segment
		(start 143.983 79.975)
		(end 142.929 78.921)
		(width 0.5)
		(layer "B.Cu")
		(net 26)
	)
	(segment
		(start 137.4648 81.3562)
		(end 137.4648 79.614205)
		(width 0.5)
		(layer "B.Cu")
		(net 26)
	)
	(segment
		(start 149.82 78.52)
		(end 150.27376 78.06624)
		(width 0.3)
		(layer "B.Cu")
		(net 26)
	)
	(segment
		(start 148.785 79.975)
		(end 143.983 79.975)
		(width 0.5)
		(layer "B.Cu")
		(net 26)
	)
	(segment
		(start 148.96 79.8)
		(end 148.96 79.66)
		(width 0.3)
		(layer "B.Cu")
		(net 26)
	)
	(segment
		(start 141.118 78.38)
		(end 142.26848 78.38)
		(width 0.3)
		(layer "B.Cu")
		(net 26)
	)
	(segment
		(start 142.26848 78.38)
		(end 143.85224 76.79624)
		(width 0.3)
		(layer "B.Cu")
		(net 26)
	)
	(segment
		(start 137.4648 79.614205)
		(end 139.258005 77.821)
		(width 0.5)
		(layer "B.Cu")
		(net 26)
	)
	(segment
		(start 142.252569 78.390253)
		(end 141.62 78.390253)
		(width 0.3)
		(layer "B.Cu")
		(net 26)
	)
	(segment
		(start 142.929 78.921)
		(end 142.325411 78.317411)
		(width 0.3)
		(layer "B.Cu")
		(net 26)
	)
	(segment
		(start 143.441 77.909)
		(end 143.087411 77.555411)
		(width 0.3)
		(layer "B.Cu")
		(net 26)
	)
	(segment
		(start 149.115 79.645)
		(end 149.115 79.225)
		(width 0.5)
		(layer "B.Cu")
		(net 26)
	)
	(segment
		(start 141.390253 78.390253)
		(end 141.62 78.390253)
		(width 0.5)
		(layer "B.Cu")
		(net 26)
	)
	(segment
		(start 142.325411 78.317411)
		(end 142.252569 78.390253)
		(width 0.3)
		(layer "B.Cu")
		(net 26)
	)
	(segment
		(start 139.258005 77.821)
		(end 140.559 77.821)
		(width 0.5)
		(layer "B.Cu")
		(net 26)
	)
	(segment
		(start 152.273 82.677)
		(end 152.654 82.296)
		(width 0.187)
		(layer "F.Cu")
		(net 27)
	)
	(segment
		(start 152.654 81.907517)
		(end 152.544483 81.798)
		(width 0.187)
		(layer "F.Cu")
		(net 27)
	)
	(segment
		(start 151.28713 82.460571)
		(end 151.649384 82.822825)
		(width 0.187)
		(layer "F.Cu")
		(net 27)
	)
	(segment
		(start 152.210667 82.677)
		(end 152.273 82.677)
		(width 0.187)
		(layer "F.Cu")
		(net 27)
	)
	(segment
		(start 151.640684 82.107017)
		(end 152.210667 82.677)
		(width 0.187)
		(layer "F.Cu")
		(net 27)
	)
	(segment
		(start 151.649384 82.822825)
		(end 152.127175 82.822825)
		(width 0.187)
		(layer "F.Cu")
		(net 27)
	)
	(segment
		(start 152.127175 82.822825)
		(end 152.273 82.677)
		(width 0.187)
		(layer "F.Cu")
		(net 27)
	)
	(segment
		(start 152.654 82.296)
		(end 152.654 81.907517)
		(width 0.187)
		(layer "F.Cu")
		(net 27)
	)
	(via
		(at 152.544483 81.798)
		(size 0.6)
		(drill 0.35)
		(layers "F.Cu" "B.Cu")
		(net 27)
	)
	(segment
		(start 153.7716 81.1276)
		(end 154.08976 81.44576)
		(width 0.3)
		(layer "B.Cu")
		(net 27)
	)
	(segment
		(start 152.544483 81.798)
		(end 153.214883 81.1276)
		(width 0.3)
		(layer "B.Cu")
		(net 27)
	)
	(segment
		(start 153.214883 81.1276)
		(end 153.7716 81.1276)
		(width 0.3)
		(layer "B.Cu")
		(net 27)
	)
	(segment
		(start 138.684 86.868)
		(end 148.66752 86.868)
		(width 0.3)
		(layer "B.Cu")
		(net 27)
	)
	(segment
		(start 138.218 87.334)
		(end 138.684 86.868)
		(width 0.3)
		(layer "B.Cu")
		(net 27)
	)
	(segment
		(start 148.66752 86.868)
		(end 154.08976 81.44576)
		(width 0.3)
		(layer "B.Cu")
		(net 27)
	)
	(segment
		(start 134.276 87.334)
		(end 138.218 87.334)
		(width 0.3)
		(layer "B.Cu")
		(net 27)
	)
	(segment
		(start 144.908132 78.91)
		(end 144.304451 78.306319)
		(width 0.187)
		(layer "F.Cu")
		(net 28)
	)
	(segment
		(start 148.626389 79.2)
		(end 149.166517 78.659872)
		(width 0.187)
		(layer "F.Cu")
		(net 28)
	)
	(segment
		(start 148.39 79.2)
		(end 148.626389 79.2)
		(width 0.187)
		(layer "F.Cu")
		(net 28)
	)
	(via
		(at 144.908132 78.91)
		(size 0.6)
		(drill 0.35)
		(layers "F.Cu" "B.Cu")
		(net 28)
	)
	(via
		(at 148.39 79.2)
		(size 0.6)
		(drill 0.35)
		(layers "F.Cu" "B.Cu")
		(net 28)
	)
	(segment
		(start 148.39 79.2)
		(end 148.39 78.432)
		(width 0.3)
		(layer "B.Cu")
		(net 28)
	)
	(segment
		(start 144.908132 78.91)
		(end 145.415 78.403132)
		(width 0.3)
		(layer "B.Cu")
		(net 28)
	)
	(segment
		(start 148.758589 76.539411)
		(end 149.520589 77.301411)
		(width 0.5)
		(layer "B.Cu")
		(net 28)
	)
	(segment
		(start 144.611411 76.031411)
		(end 145.373411 75.269411)
		(width 0.3)
		(layer "B.Cu")
		(net 28)
	)
	(segment
		(start 145.415 76.962)
		(end 144.61424 76.16124)
		(width 0.3)
		(layer "B.Cu")
		(net 28)
	)
	(segment
		(start 145.373411 75.269411)
		(end 146.643411 76.539411)
		(width 0.5)
		(layer "B.Cu")
		(net 28)
	)
	(segment
		(start 144.61424 76.16124)
		(end 144.61424 76.03424)
		(width 0.3)
		(layer "B.Cu")
		(net 28)
	)
	(segment
		(start 145.415 78.403132)
		(end 145.415 76.962)
		(width 0.3)
		(layer "B.Cu")
		(net 28)
	)
	(segment
		(start 144.61424 76.03424)
		(end 145.40848 75.24)
		(width 0.5)
		(layer "B.Cu")
		(net 28)
	)
	(segment
		(start 146.643411 76.539411)
		(end 148.758589 76.539411)
		(width 0.5)
		(layer "B.Cu")
		(net 28)
	)
	(segment
		(start 148.39 78.432)
		(end 149.51776 77.30424)
		(width 0.3)
		(layer "B.Cu")
		(net 28)
	)
	(segment
		(start 141.486 82.804)
		(end 141.486855 82.804)
		(width 0.187)
		(layer "F.Cu")
		(net 29)
	)
	(segment
		(start 141.486855 82.804)
		(end 141.830284 82.460571)
		(width 0.187)
		(layer "F.Cu")
		(net 29)
	)
	(segment
		(start 141.17 83.12)
		(end 141.486 82.804)
		(width 0.187)
		(layer "F.Cu")
		(net 29)
	)
	(via
		(at 141.17 83.12)
		(size 0.6)
		(drill 0.35)
		(layers "F.Cu" "B.Cu")
		(net 29)
	)
	(segment
		(start 135.459 85.775)
		(end 141.333 85.775)
		(width 0.3)
		(layer "B.Cu")
		(net 29)
	)
	(segment
		(start 141.17 83.12)
		(end 140.76576 82.71576)
		(width 0.3)
		(layer "B.Cu")
		(net 29)
	)
	(segment
		(start 141.333 85.775)
		(end 141.57 85.538)
		(width 0.3)
		(layer "B.Cu")
		(net 29)
	)
	(segment
		(start 134.916 86.318)
		(end 135.459 85.775)
		(width 0.3)
		(layer "B.Cu")
		(net 29)
	)
	(segment
		(start 141.57 85.538)
		(end 141.57 83.52)
		(width 0.3)
		(layer "B.Cu")
		(net 29)
	)
	(segment
		(start 140.76576 82.71576)
		(end 140.04224 82.71576)
		(width 0.3)
		(layer "B.Cu")
		(net 29)
	)
	(segment
		(start 140.633411 83.656589)
		(end 141.17 83.12)
		(width 0.3)
		(layer "B.Cu")
		(net 29)
	)
	(segment
		(start 134.276 86.318)
		(end 134.916 86.318)
		(width 0.3)
		(layer "B.Cu")
		(net 29)
	)
	(segment
		(start 140.591411 83.656589)
		(end 140.633411 83.656589)
		(width 0.3)
		(layer "B.Cu")
		(net 29)
	)
	(segment
		(start 141.57 83.52)
		(end 141.17 83.12)
		(width 0.3)
		(layer "B.Cu")
		(net 29)
	)
	(segment
		(start 182.2982 69.192)
		(end 181.841 69.192)
		(width 0.187)
		(layer "F.Cu")
		(net 35)
	)
	(segment
		(start 183.886 69.934)
		(end 183.0402 69.934)
		(width 0.187)
		(layer "F.Cu")
		(net 35)
	)
	(segment
		(start 183.0402 69.934)
		(end 182.2982 69.192)
		(width 0.187)
		(layer "F.Cu")
		(net 35)
	)
	(segment
		(start 182.372 68.144)
		(end 183.163 68.935)
		(width 0.187)
		(layer "F.Cu")
		(net 37)
	)
	(segment
		(start 183.163 68.935)
		(end 183.886 68.935)
		(width 0.187)
		(layer "F.Cu")
		(net 37)
	)
	(segment
		(start 181.841 68.144)
		(end 182.372 68.144)
		(width 0.187)
		(layer "F.Cu")
		(net 37)
	)
	(segment
		(start 183.886 65.434)
		(end 182.8328 65.434)
		(width 0.187)
		(layer "F.Cu")
		(net 42)
	)
	(segment
		(start 182.8328 65.434)
		(end 182.4228 65.024)
		(width 0.187)
		(layer "F.Cu")
		(net 42)
	)
	(segment
		(start 182.4228 65.024)
		(end 181.841 65.024)
		(width 0.187)
		(layer "F.Cu")
		(net 42)
	)
	(segment
		(start 183.886 64.934)
		(end 183.180609 64.934)
		(width 0.187)
		(layer "F.Cu")
		(net 43)
	)
	(segment
		(start 183.180609 64.934)
		(end 182.254609 64.008)
		(width 0.187)
		(layer "F.Cu")
		(net 43)
	)
	(segment
		(start 182.254609 64.008)
		(end 181.841 64.008)
		(width 0.187)
		(layer "F.Cu")
		(net 43)
	)
	(segment
		(start 180.871 65.024)
		(end 180.34 65.024)
		(width 0.187)
		(layer "F.Cu")
		(net 44)
	)
	(segment
		(start 180.34 65.024)
		(end 180.149 65.215)
		(width 0.187)
		(layer "F.Cu")
		(net 44)
	)
	(segment
		(start 178.482 64.593)
		(end 178.482 64.944)
		(width 0.187)
		(layer "F.Cu")
		(net 44)
	)
	(segment
		(start 178.753 65.215)
		(end 179.705 65.215)
		(width 0.187)
		(layer "F.Cu")
		(net 44)
	)
	(segment
		(start 178.482 64.593)
		(end 177.3 64.593)
		(width 0.187)
		(layer "F.Cu")
		(net 44)
	)
	(segment
		(start 179.2215 65.6345)
		(end 179.582132 65.6345)
		(width 0.187)
		(layer "F.Cu")
		(net 44)
	)
	(segment
		(start 180.149 65.215)
		(end 179.705 65.215)
		(width 0.187)
		(layer "F.Cu")
		(net 44)
	)
	(segment
		(start 180.871 67.056)
		(end 180.8495 67.0345)
		(width 0.187)
		(layer "F.Cu")
		(net 44)
	)
	(segment
		(start 179.3025 67.0345)
		(end 179.07 66.802)
		(width 0.187)
		(layer "F.Cu")
		(net 44)
	)
	(segment
		(start 179.07 65.786)
		(end 179.2215 65.6345)
		(width 0.187)
		(layer "F.Cu")
		(net 44)
	)
	(segment
		(start 179.705 65.511632)
		(end 179.705 65.215)
		(width 0.187)
		(layer "F.Cu")
		(net 44)
	)
	(segment
		(start 180.8495 67.0345)
		(end 179.3025 67.0345)
		(width 0.187)
		(layer "F.Cu")
		(net 44)
	)
	(segment
		(start 179.07 66.802)
		(end 179.07 65.786)
		(width 0.187)
		(layer "F.Cu")
		(net 44)
	)
	(segment
		(start 177.3 64.593)
		(end 177.158 64.735)
		(width 0.187)
		(layer "F.Cu")
		(net 44)
	)
	(segment
		(start 178.482 64.944)
		(end 178.753 65.215)
		(width 0.187)
		(layer "F.Cu")
		(net 44)
	)
	(segment
		(start 179.582132 65.6345)
		(end 179.705 65.511632)
		(width 0.187)
		(layer "F.Cu")
		(net 44)
	)
	(segment
		(start 180.493476 66.04)
		(end 180.310242 66.223234)
		(width 0.187)
		(layer "F.Cu")
		(net 45)
	)
	(segment
		(start 180.310242 66.488022)
		(end 179.792069 66.488022)
		(width 0.187)
		(layer "F.Cu")
		(net 45)
	)
	(segment
		(start 180.871 64.008)
		(end 180.422701 64.008)
		(width 0.187)
		(layer "F.Cu")
		(net 45)
	)
	(segment
		(start 177.743 61.799)
		(end 177.743 61.591)
		(width 0.187)
		(layer "F.Cu")
		(net 45)
	)
	(segment
		(start 180.422701 64.008)
		(end 180.292991 64.13771)
		(width 0.187)
		(layer "F.Cu")
		(net 45)
	)
	(segment
		(start 180.292991 64.13771)
		(end 180.292991 64.474875)
		(width 0.187)
		(layer "F.Cu")
		(net 45)
	)
	(segment
		(start 178.482 61.591)
		(end 177.743 61.591)
		(width 0.187)
		(layer "F.Cu")
		(net 45)
	)
	(segment
		(start 177.743 61.591)
		(end 177.158 61.006)
		(width 0.187)
		(layer "F.Cu")
		(net 45)
	)
	(segment
		(start 179.705 66.400953)
		(end 179.705 65.976)
		(width 0.187)
		(layer "F.Cu")
		(net 45)
	)
	(segment
		(start 177.466 62.076)
		(end 177.743 61.799)
		(width 0.187)
		(layer "F.Cu")
		(net 45)
	)
	(segment
		(start 180.310242 66.223234)
		(end 180.310242 66.488022)
		(width 0.187)
		(layer "F.Cu")
		(net 45)
	)
	(segment
		(start 177.466 62.33)
		(end 177.466 62.076)
		(width 0.187)
		(layer "F.Cu")
		(net 45)
	)
	(segment
		(start 177.158 61.006)
		(end 177.158 60.436)
		(width 0.187)
		(layer "F.Cu")
		(net 45)
	)
	(segment
		(start 180.871 66.04)
		(end 180.493476 66.04)
		(width 0.187)
		(layer "F.Cu")
		(net 45)
	)
	(segment
		(start 179.792069 66.488022)
		(end 179.705 66.400953)
		(width 0.187)
		(layer "F.Cu")
		(net 45)
	)
	(via
		(at 180.310242 66.488022)
		(size 0.6)
		(drill 0.35)
		(layers "F.Cu" "B.Cu")
		(net 45)
	)
	(via
		(at 180.292991 64.474875)
		(size 0.6)
		(drill 0.35)
		(layers "F.Cu" "B.Cu")
		(net 45)
	)
	(via
		(at 177.466 62.33)
		(size 0.6)
		(drill 0.35)
		(layers "F.Cu" "B.Cu")
		(net 45)
	)
	(segment
		(start 180.310242 64.492126)
		(end 180.292991 64.474875)
		(width 0.187)
		(layer "B.Cu")
		(net 45)
	)
	(segment
		(start 180.310242 66.488022)
		(end 179.772022 66.488022)
		(width 0.187)
		(layer "B.Cu")
		(net 45)
	)
	(segment
		(start 179.772022 66.488022)
		(end 178.562 65.278)
		(width 0.187)
		(layer "B.Cu")
		(net 45)
	)
	(segment
		(start 178.562 65.278)
		(end 178.562 63.426)
		(width 0.187)
		(layer "B.Cu")
		(net 45)
	)
	(segment
		(start 178.562 63.426)
		(end 177.466 62.33)
		(width 0.187)
		(layer "B.Cu")
		(net 45)
	)
	(segment
		(start 180.310242 66.488022)
		(end 180.310242 64.492126)
		(width 0.187)
		(layer "B.Cu")
		(net 45)
	)
	(segment
		(start 187.81 62.15)
		(end 187.594 61.934)
		(width 0.187)
		(layer "F.Cu")
		(net 50)
	)
	(segment
		(start 178.459321 63.094679)
		(end 177.189321 63.094679)
		(width 0.187)
		(layer "F.Cu")
		(net 50)
	)
	(segment
		(start 179.121 62.814)
		(end 178.840321 63.094679)
		(width 0.187)
		(layer "F.Cu")
		(net 50)
	)
	(segment
		(start 178.482 63.072)
		(end 178.459321 63.094679)
		(width 0.187)
		(layer "F.Cu")
		(net 50)
	)
	(segment
		(start 187.594 61.934)
		(end 183.886 61.934)
		(width 0.187)
		(layer "F.Cu")
		(net 50)
	)
	(segment
		(start 178.482 62.561)
		(end 178.482 63.072)
		(width 0.187)
		(layer "F.Cu")
		(net 50)
	)
	(segment
		(start 182.95 62.434)
		(end 183.886 62.434)
		(width 0.187)
		(layer "F.Cu")
		(net 50)
	)
	(segment
		(start 183.886 61.934)
		(end 183.176 61.934)
		(width 0.187)
		(layer "F.Cu")
		(net 50)
	)
	(segment
		(start 183.176 61.934)
		(end 182.95 62.16)
		(width 0.187)
		(layer "F.Cu")
		(net 50)
	)
	(segment
		(start 178.482 63.117358)
		(end 178.459321 63.094679)
		(width 0.187)
		(layer "F.Cu")
		(net 50)
	)
	(segment
		(start 156.972 96.8)
		(end 156.972 97.89)
		(width 0.5)
		(layer "F.Cu")
		(net 50)
	)
	(segment
		(start 181.864 63.0525)
		(end 182.3315 63.0525)
		(width 0.187)
		(layer "F.Cu")
		(net 50)
	)
	(segment
		(start 182.95 62.16)
		(end 182.95 62.434)
		(width 0.187)
		(layer "F.Cu")
		(net 50)
	)
	(segment
		(start 180.961 62.814)
		(end 181.1995 63.0525)
		(width 0.187)
		(layer "F.Cu")
		(net 50)
	)
	(segment
		(start 177.189321 63.094679)
		(end 176.509 63.775)
		(width 0.187)
		(layer "F.Cu")
		(net 50)
	)
	(segment
		(start 176.509 63.775)
		(end 176.509 64.735)
		(width 0.187)
		(layer "F.Cu")
		(net 50)
	)
	(segment
		(start 182.3315 63.0525)
		(end 182.95 62.434)
		(width 0.187)
		(layer "F.Cu")
		(net 50)
	)
	(segment
		(start 178.840321 63.094679)
		(end 178.459321 63.094679)
		(width 0.187)
		(layer "F.Cu")
		(net 50)
	)
	(segment
		(start 178.482 63.623)
		(end 178.482 63.117358)
		(width 0.187)
		(layer "F.Cu")
		(net 50)
	)
	(segment
		(start 181.1995 63.0525)
		(end 181.864 63.0525)
		(width 0.187)
		(layer "F.Cu")
		(net 50)
	)
	(segment
		(start 179.498 62.814)
		(end 180.961 62.814)
		(width 0.187)
		(layer "F.Cu")
		(net 50)
	)
	(segment
		(start 179.498 62.814)
		(end 179.121 62.814)
		(width 0.187)
		(layer "F.Cu")
		(net 50)
	)
	(via
		(at 156.972 97.89)
		(size 0.6)
		(drill 0.35)
		(layers "F.Cu" "B.Cu")
		(net 50)
	)
	(via
		(at 187.81 62.15)
		(size 0.6)
		(drill 0.35)
		(layers "F.Cu" "B.Cu")
		(net 50)
	)
	(segment
		(start 188.37 62.71)
		(end 188.37 96.751532)
		(width 0.187)
		(layer "In2.Cu")
		(net 50)
	)
	(segment
		(start 187.81 62.15)
		(end 188.37 62.71)
		(width 0.187)
		(layer "In2.Cu")
		(net 50)
	)
	(segment
		(start 188.37 96.751532)
		(end 187.021532 98.1)
		(width 0.187)
		(layer "In2.Cu")
		(net 50)
	)
	(segment
		(start 157.282 98.1)
		(end 156.972 97.79)
		(width 0.187)
		(layer "In2.Cu")
		(net 50)
	)
	(segment
		(start 187.021532 98.1)
		(end 157.282 98.1)
		(width 0.187)
		(layer "In2.Cu")
		(net 50)
	)
	(segment
		(start 127.255 61.491)
		(end 127.255 59.945)
		(width 0.5)
		(layer "F.Cu")
		(net 51)
	)
	(segment
		(start 127.255 59.945)
		(end 126.576 59.266)
		(width 0.5)
		(layer "F.Cu")
		(net 51)
	)
	(segment
		(start 123.19 59.266)
		(end 123.19 58.166)
		(width 0.5)
		(layer "F.Cu")
		(net 51)
	)
	(segment
		(start 127 57.912)
		(end 124.968 57.912)
		(width 0.5)
		(layer "F.Cu")
		(net 51)
	)
	(segment
		(start 126.576 59.266)
		(end 123.19 59.266)
		(width 0.5)
		(layer "F.Cu")
		(net 51)
	)
	(segment
		(start 127.262 57.65)
		(end 127 57.912)
		(width 0.5)
		(layer "F.Cu")
		(net 51)
	)
	(segment
		(start 123.19 58.166)
		(end 123.444 57.912)
		(width 0.5)
		(layer "F.Cu")
		(net 51)
	)
	(segment
		(start 127.262 57.127)
		(end 127.262 57.65)
		(width 0.5)
		(layer "F.Cu")
		(net 51)
	)
	(segment
		(start 123.444 57.912)
		(end 124.968 57.912)
		(width 0.5)
		(layer "F.Cu")
		(net 51)
	)
	(segment
		(start 138.9102 57.9398)
		(end 139.199 57.651)
		(width 0.5)
		(layer "F.Cu")
		(net 52)
	)
	(segment
		(start 139.199 57.651)
		(end 139.199 57.1548)
		(width 0.5)
		(layer "F.Cu")
		(net 52)
	)
	(segment
		(start 136.906 57.912)
		(end 135.382 57.912)
		(width 0.5)
		(layer "F.Cu")
		(net 52)
	)
	(segment
		(start 138.5418 59.2938)
		(end 135.551 59.2938)
		(width 0.5)
		(layer "F.Cu")
		(net 52)
	)
	(segment
		(start 139.192 61.5188)
		(end 139.192 59.944)
		(width 0.5)
		(layer "F.Cu")
		(net 52)
	)
	(segment
		(start 135.128 58.166)
		(end 135.128 59.266)
		(width 0.5)
		(layer "F.Cu")
		(net 52)
	)
	(segment
		(start 135.382 57.912)
		(end 135.128 58.166)
		(width 0.5)
		(layer "F.Cu")
		(net 52)
	)
	(segment
		(start 136.905 57.9398)
		(end 138.9102 57.9398)
		(width 0.5)
		(layer "F.Cu")
		(net 52)
	)
	(segment
		(start 139.192 59.944)
		(end 138.5418 59.2938)
		(width 0.5)
		(layer "F.Cu")
		(net 52)
	)
	(segment
		(start 149.9718 59.2938)
		(end 146.981 59.2938)
		(width 0.5)
		(layer "F.Cu")
		(net 53)
	)
	(segment
		(start 150.629 57.651)
		(end 150.629 57.1548)
		(width 0.5)
		(layer "F.Cu")
		(net 53)
	)
	(segment
		(start 150.3402 57.9398)
		(end 150.629 57.651)
		(width 0.5)
		(layer "F.Cu")
		(net 53)
	)
	(segment
		(start 146.558 58.166)
		(end 146.558 59.266)
		(width 0.5)
		(layer "F.Cu")
		(net 53)
	)
	(segment
		(start 150.622 61.5188)
		(end 150.622 59.944)
		(width 0.5)
		(layer "F.Cu")
		(net 53)
	)
	(segment
		(start 148.336 57.912)
		(end 146.812 57.912)
		(width 0.5)
		(layer "F.Cu")
		(net 53)
	)
	(segment
		(start 148.335 57.9398)
		(end 150.3402 57.9398)
		(width 0.5)
		(layer "F.Cu")
		(net 53)
	)
	(segment
		(start 146.812 57.912)
		(end 146.558 58.166)
		(width 0.5)
		(layer "F.Cu")
		(net 53)
	)
	(segment
		(start 150.622 59.944)
		(end 149.9718 59.2938)
		(width 0.5)
		(layer "F.Cu")
		(net 53)
	)
	(segment
		(start 159.766 57.912)
		(end 158.242 57.912)
		(width 0.5)
		(layer "F.Cu")
		(net 54)
	)
	(segment
		(start 162.052 60.071)
		(end 161.2748 59.2938)
		(width 0.5)
		(layer "F.Cu")
		(net 54)
	)
	(segment
		(start 157.988 58.166)
		(end 157.988 59.266)
		(width 0.5)
		(layer "F.Cu")
		(net 54)
	)
	(segment
		(start 158.242 57.912)
		(end 157.988 58.166)
		(width 0.5)
		(layer "F.Cu")
		(net 54)
	)
	(segment
		(start 159.765 57.9398)
		(end 161.7702 57.9398)
		(width 0.5)
		(layer "F.Cu")
		(net 54)
	)
	(segment
		(start 161.2748 59.2938)
		(end 158.411 59.2938)
		(width 0.5)
		(layer "F.Cu")
		(net 54)
	)
	(segment
		(start 162.052 61.5188)
		(end 162.052 60.071)
		(width 0.5)
		(layer "F.Cu")
		(net 54)
	)
	(segment
		(start 162.059 57.651)
		(end 162.059 57.1548)
		(width 0.5)
		(layer "F.Cu")
		(net 54)
	)
	(segment
		(start 161.7702 57.9398)
		(end 162.059 57.651)
		(width 0.5)
		(layer "F.Cu")
		(net 54)
	)
	(segment
		(start 127.262 55.634)
		(end 127 55.372)
		(width 0.5)
		(layer "F.Cu")
		(net 55)
	)
	(segment
		(start 124.968 54.864)
		(end 124.968 55.372)
		(width 0.5)
		(layer "F.Cu")
		(net 55)
	)
	(segment
		(start 125.349 53.594)
		(end 125.349 54.483)
		(width 0.5)
		(layer "F.Cu")
		(net 55)
	)
	(segment
		(start 127.262 56.157)
		(end 127.262 55.634)
		(width 0.5)
		(layer "F.Cu")
		(net 55)
	)
	(segment
		(start 125.349 54.483)
		(end 124.968 54.864)
		(width 0.5)
		(layer "F.Cu")
		(net 55)
	)
	(segment
		(start 127 55.372)
		(end 124.968 55.372)
		(width 0.5)
		(layer "F.Cu")
		(net 55)
	)
	(segment
		(start 138.938 55.372)
		(end 136.906 55.372)
		(width 0.5)
		(layer "F.Cu")
		(net 56)
	)
	(segment
		(start 137.033 53.594)
		(end 137.033 54.483)
		(width 0.5)
		(layer "F.Cu")
		(net 56)
	)
	(segment
		(start 137.033 54.483)
		(end 136.906 54.61)
		(width 0.5)
		(layer "F.Cu")
		(net 56)
	)
	(segment
		(start 139.192 55.626)
		(end 138.938 55.372)
		(width 0.5)
		(layer "F.Cu")
		(net 56)
	)
	(segment
		(start 136.906 54.61)
		(end 136.906 55.372)
		(width 0.5)
		(layer "F.Cu")
		(net 56)
	)
	(segment
		(start 139.192 56.157)
		(end 139.192 55.626)
		(width 0.5)
		(layer "F.Cu")
		(net 56)
	)
	(segment
		(start 150.622 56.157)
		(end 150.622 55.626)
		(width 0.5)
		(layer "F.Cu")
		(net 57)
	)
	(segment
		(start 150.368 55.372)
		(end 148.336 55.372)
		(width 0.5)
		(layer "F.Cu")
		(net 57)
	)
	(segment
		(start 148.463 54.483)
		(end 148.336 54.61)
		(width 0.5)
		(layer "F.Cu")
		(net 57)
	)
	(segment
		(start 148.463 53.594)
		(end 148.463 54.483)
		(width 0.5)
		(layer "F.Cu")
		(net 57)
	)
	(segment
		(start 150.622 55.626)
		(end 150.368 55.372)
		(width 0.5)
		(layer "F.Cu")
		(net 57)
	)
	(segment
		(start 148.336 54.61)
		(end 148.336 55.372)
		(width 0.5)
		(layer "F.Cu")
		(net 57)
	)
	(segment
		(start 159.893 54.483)
		(end 159.766 54.61)
		(width 0.5)
		(layer "F.Cu")
		(net 58)
	)
	(segment
		(start 162.052 56.157)
		(end 162.052 55.626)
		(width 0.5)
		(layer "F.Cu")
		(net 58)
	)
	(segment
		(start 159.893 53.594)
		(end 159.893 54.483)
		(width 0.5)
		(layer "F.Cu")
		(net 58)
	)
	(segment
		(start 161.798 55.372)
		(end 159.766 55.372)
		(width 0.5)
		(layer "F.Cu")
		(net 58)
	)
	(segment
		(start 162.052 55.626)
		(end 161.798 55.372)
		(width 0.5)
		(layer "F.Cu")
		(net 58)
	)
	(segment
		(start 159.766 54.61)
		(end 159.766 55.372)
		(width 0.5)
		(layer "F.Cu")
		(net 58)
	)
	(segment
		(start 126.619 53.594)
		(end 127.889 53.594)
		(width 0.5)
		(layer "F.Cu")
		(net 59)
	)
	(segment
		(start 138.303 53.594)
		(end 139.545 53.594)
		(width 0.5)
		(layer "F.Cu")
		(net 60)
	)
	(segment
		(start 149.733 53.594)
		(end 151.003 53.594)
		(width 0.5)
		(layer "F.Cu")
		(net 61)
	)
	(segment
		(start 161.163 53.594)
		(end 162.385 53.594)
		(width 0.5)
		(layer "F.Cu")
		(net 62)
	)
	(segment
		(start 184.7282 54.0318)
		(end 184.7282 53.7778)
		(width 0.187)
		(layer "F.Cu")
		(net 63)
	)
	(segment
		(start 181.526 53.932)
		(end 182.2402 53.2178)
		(width 0.187)
		(layer "F.Cu")
		(net 63)
	)
	(segment
		(start 184.4802 54.2798)
		(end 184.7282 54.0318)
		(width 0.187)
		(layer "F.Cu")
		(net 63)
	)
	(segment
		(start 184.077 54.2798)
		(end 184.4802 54.2798)
		(width 0.187)
		(layer "F.Cu")
		(net 63)
	)
	(segment
		(start 184.7282 53.7778)
		(end 184.7282 53.4892)
		(width 0.187)
		(layer "F.Cu")
		(net 63)
	)
	(segment
		(start 182.2402 53.2178)
		(end 184.077 53.2178)
		(width 0.187)
		(layer "F.Cu")
		(net 63)
	)
	(segment
		(start 184.7282 53.4892)
		(end 184.5148 53.2758)
		(width 0.187)
		(layer "F.Cu")
		(net 63)
	)
	(segment
		(start 179.3245 53.932)
		(end 181.526 53.932)
		(width 0.187)
		(layer "F.Cu")
		(net 63)
	)
	(segment
		(start 185.41 53.7778)
		(end 184.7282 53.7778)
		(width 0.187)
		(layer "F.Cu")
		(net 63)
	)
	(segment
		(start 184.5148 53.2758)
		(end 184.077 53.2758)
		(width 0.187)
		(layer "F.Cu")
		(net 63)
	)
	(segment
		(start 152.48 95.41)
		(end 152.4 95.41)
		(width 0.187)
		(layer "F.Cu")
		(net 64)
	)
	(segment
		(start 153.14 96.07)
		(end 152.48 95.41)
		(width 0.187)
		(layer "F.Cu")
		(net 64)
	)
	(via
		(at 153.14 96.07)
		(size 0.6)
		(drill 0.35)
		(layers "F.Cu" "B.Cu")
		(net 64)
	)
	(segment
		(start 152.975897 95.905897)
		(end 153.14 96.07)
		(width 0.187)
		(layer "B.Cu")
		(net 64)
	)
	(segment
		(start 152.43253 95.905897)
		(end 152.975897 95.905897)
		(width 0.187)
		(layer "B.Cu")
		(net 64)
	)
	(segment
		(start 157.73 96.05)
		(end 157.08 95.4)
		(width 0.187)
		(layer "F.Cu")
		(net 65)
	)
	(segment
		(start 157.08 95.4)
		(end 156.972 95.4)
		(width 0.187)
		(layer "F.Cu")
		(net 65)
	)
	(via
		(at 157.73 96.05)
		(size 0.6)
		(drill 0.35)
		(layers "F.Cu" "B.Cu")
		(net 65)
	)
	(segment
		(start 156.972494 95.895897)
		(end 157.575897 95.895897)
		(width 0.187)
		(layer "B.Cu")
		(net 65)
	)
	(segment
		(start 157.575897 95.895897)
		(end 157.73 96.05)
		(width 0.187)
		(layer "B.Cu")
		(net 65)
	)
	(segment
		(start 178.839 68.349)
		(end 179.837 68.349)
		(width 0.187)
		(layer "F.Cu")
		(net 66)
	)
	(segment
		(start 178.054 68.009)
		(end 178.499 68.009)
		(width 0.187)
		(layer "F.Cu")
		(net 66)
	)
	(segment
		(start 167.132 56.4119)
		(end 167.132 55.418)
		(width 0.187)
		(layer "F.Cu")
		(net 66)
	)
	(segment
		(start 179.837 68.349)
		(end 180.2375 68.349)
		(width 0.187)
		(layer "F.Cu")
		(net 66)
	)
	(segment
		(start 180.2375 68.349)
		(end 180.4425 68.144)
		(width 0.187)
		(layer "F.Cu")
		(net 66)
	)
	(segment
		(start 178.499 68.009)
		(end 178.839 68.349)
		(width 0.187)
		(layer "F.Cu")
		(net 66)
	)
	(segment
		(start 177.212 67.738)
		(end 177.483 68.009)
		(width 0.187)
		(layer "F.Cu")
		(net 66)
	)
	(segment
		(start 177.212 66.294)
		(end 177.212 67.738)
		(width 0.187)
		(layer "F.Cu")
		(net 66)
	)
	(segment
		(start 177.483 68.009)
		(end 178.054 68.009)
		(width 0.187)
		(layer "F.Cu")
		(net 66)
	)
	(segment
		(start 180.4425 68.144)
		(end 180.871 68.144)
		(width 0.187)
		(layer "F.Cu")
		(net 66)
	)
	(via
		(at 177.212 66.294)
		(size 0.6)
		(drill 0.35)
		(layers "F.Cu" "B.Cu")
		(net 66)
	)
	(via
		(at 167.132 56.4119)
		(size 0.6)
		(drill 0.35)
		(layers "F.Cu" "B.Cu")
		(net 66)
	)
	(segment
		(start 168.83 58.086)
		(end 169.592 58.086)
		(width 0.187)
		(layer "B.Cu")
		(net 66)
	)
	(segment
		(start 169.592 58.086)
		(end 177.212 65.706)
		(width 0.187)
		(layer "B.Cu")
		(net 66)
	)
	(segment
		(start 177.212 65.706)
		(end 177.212 66.294)
		(width 0.187)
		(layer "B.Cu")
		(net 66)
	)
	(segment
		(start 167.1559 56.4119)
		(end 168.83 58.086)
		(width 0.187)
		(layer "B.Cu")
		(net 66)
	)
	(segment
		(start 167.132 56.4119)
		(end 167.1559 56.4119)
		(width 0.187)
		(layer "B.Cu")
		(net 66)
	)
	(segment
		(start 177.737 69.088)
		(end 177.292 69.088)
		(width 0.187)
		(layer "F.Cu")
		(net 67)
	)
	(segment
		(start 169.926 60.632)
		(end 169.926 59.736)
		(width 0.187)
		(layer "F.Cu")
		(net 67)
	)
	(segment
		(start 180.871 69.192)
		(end 180.49 69.192)
		(width 0.187)
		(layer "F.Cu")
		(net 67)
	)
	(segment
		(start 177.292 69.088)
		(end 177.038 68.834)
		(width 0.187)
		(layer "F.Cu")
		(net 67)
	)
	(segment
		(start 180.34 69.342)
		(end 179.86 69.342)
		(width 0.187)
		(layer "F.Cu")
		(net 67)
	)
	(segment
		(start 178.816 69.342)
		(end 179.814 69.342)
		(width 0.187)
		(layer "F.Cu")
		(net 67)
	)
	(segment
		(start 179.86 69.342)
		(end 179.837 69.319)
		(width 0.187)
		(layer "F.Cu")
		(net 67)
	)
	(segment
		(start 180.49 69.192)
		(end 180.34 69.342)
		(width 0.187)
		(layer "F.Cu")
		(net 67)
	)
	(segment
		(start 179.814 69.342)
		(end 179.837 69.319)
		(width 0.187)
		(layer "F.Cu")
		(net 67)
	)
	(segment
		(start 178.562 69.088)
		(end 178.816 69.342)
		(width 0.187)
		(layer "F.Cu")
		(net 67)
	)
	(segment
		(start 177.737 69.088)
		(end 178.562 69.088)
		(width 0.187)
		(layer "F.Cu")
		(net 67)
	)
	(segment
		(start 177.038 68.834)
		(end 177.038 68.506)
		(width 0.187)
		(layer "F.Cu")
		(net 67)
	)
	(segment
		(start 170.354 61.06)
		(end 169.926 60.632)
		(width 0.187)
		(layer "F.Cu")
		(net 67)
	)
	(segment
		(start 177.038 68.506)
		(end 176.694 68.162)
		(width 0.187)
		(layer "F.Cu")
		(net 67)
	)
	(via
		(at 176.694 68.162)
		(size 0.6)
		(drill 0.35)
		(layers "F.Cu" "B.Cu")
		(net 67)
	)
	(via
		(at 170.354 61.06)
		(size 0.6)
		(drill 0.35)
		(layers "F.Cu" "B.Cu")
		(net 67)
	)
	(segment
		(start 176.196 67.664)
		(end 176.196 66.902)
		(width 0.187)
		(layer "B.Cu")
		(net 67)
	)
	(segment
		(start 176.196 66.902)
		(end 170.354 61.06)
		(width 0.187)
		(layer "B.Cu")
		(net 67)
	)
	(segment
		(start 176.694 68.162)
		(end 176.196 67.664)
		(width 0.187)
		(layer "B.Cu")
		(net 67)
	)
	(segment
		(start 120.75 84.328)
		(end 119.634 84.328)
		(width 0.5)
		(layer "F.Cu")
		(net 68)
	)
	(segment
		(start 120.904 84.174)
		(end 122.327 84.174)
		(width 0.5)
		(layer "F.Cu")
		(net 68)
	)
	(segment
		(start 120.904 84.174)
		(end 120.75 84.328)
		(width 0.5)
		(layer "F.Cu")
		(net 68)
	)
	(segment
		(start 119.634 85.344)
		(end 119.634 84.328)
		(width 0.5)
		(layer "F.Cu")
		(net 68)
	)
	(segment
		(start 138.707 93.472)
		(end 138.707 94.488)
		(width 0.5)
		(layer "F.Cu")
		(net 69)
	)
	(segment
		(start 137.668 94.488)
		(end 138.707 94.488)
		(width 0.5)
		(layer "F.Cu")
		(net 69)
	)
	(segment
		(start 137.55 94.606)
		(end 137.668 94.488)
		(width 0.5)
		(layer "F.Cu")
		(net 69)
	)
	(segment
		(start 136.072 94.606)
		(end 137.55 94.606)
		(width 0.5)
		(layer "F.Cu")
		(net 69)
	)
	(segment
		(start 137.033 95.631)
		(end 137.577 95.631)
		(width 0.5)
		(layer "F.Cu")
		(net 70)
	)
	(segment
		(start 137.577 95.631)
		(end 137.59 95.618)
		(width 0.5)
		(layer "F.Cu")
		(net 70)
	)
	(segment
		(start 136.072 95.556)
		(end 136.958 95.556)
		(width 0.5)
		(layer "F.Cu")
		(net 70)
	)
	(segment
		(start 137.313 96.287018)
		(end 137.59 96.010018)
		(width 0.5)
		(layer "F.Cu")
		(net 70)
	)
	(segment
		(start 136.958 95.556)
		(end 137.033 95.631)
		(width 0.5)
		(layer "F.Cu")
		(net 70)
	)
	(segment
		(start 137.313 96.657)
		(end 137.313 96.287018)
		(width 0.5)
		(layer "F.Cu")
		(net 70)
	)
	(segment
		(start 137.59 96.010018)
		(end 137.59 95.618)
		(width 0.5)
		(layer "F.Cu")
		(net 70)
	)
	(segment
		(start 120.809 82.781935)
		(end 121.087 82.503935)
		(width 0.5)
		(layer "F.Cu")
		(net 71)
	)
	(segment
		(start 121.086 83.162)
		(end 122.265 83.162)
		(width 0.5)
		(layer "F.Cu")
		(net 71)
	)
	(segment
		(start 120.809 83.162)
		(end 120.809 82.781935)
		(width 0.5)
		(layer "F.Cu")
		(net 71)
	)
	(segment
		(start 120.809 83.162)
		(end 121.086 83.162)
		(width 0.5)
		(layer "F.Cu")
		(net 71)
	)
	(segment
		(start 122.265 83.162)
		(end 122.327 83.224)
		(width 0.5)
		(layer "F.Cu")
		(net 71)
	)
	(segment
		(start 121.087 82.503935)
		(end 121.087 82.123)
		(width 0.5)
		(layer "F.Cu")
		(net 71)
	)
	(segment
		(start 185.41 50.3328)
		(end 185.293 50.2158)
		(width 0.187)
		(layer "F.Cu")
		(net 72)
	)
	(segment
		(start 185.293 50.2158)
		(end 184.079 50.2158)
		(width 0.187)
		(layer "F.Cu")
		(net 72)
	)
	(segment
		(start 185.41 51.1778)
		(end 185.41 50.3328)
		(width 0.187)
		(layer "F.Cu")
		(net 72)
	)
	(via
		(at 130.048 87.376)
		(size 0.6)
		(drill 0.35)
		(layers "F.Cu" "B.Cu")
		(net 73)
	)
	(via
		(at 130.048 86.36)
		(size 0.6)
		(drill 0.35)
		(layers "F.Cu" "B.Cu")
		(net 73)
	)
	(via
		(at 130.81 87.376)
		(size 0.6)
		(drill 0.35)
		(layers "F.Cu" "B.Cu")
		(net 73)
	)
	(via
		(at 130.81 86.36)
		(size 0.6)
		(drill 0.35)
		(layers "F.Cu" "B.Cu")
		(net 73)
	)
	(segment
		(start 130.81 86.36)
		(end 133.269 86.36)
		(width 0.5)
		(layer "B.Cu")
		(net 73)
	)
	(segment
		(start 133.306 87.334)
		(end 130.852 87.334)
		(width 0.5)
		(layer "B.Cu")
		(net 73)
	)
	(segment
		(start 133.269 86.36)
		(end 133.311 86.318)
		(width 0.5)
		(layer "B.Cu")
		(net 73)
	)
	(segment
		(start 130.81 86.36)
		(end 130.81 84.8)
		(width 0.5)
		(layer "B.Cu")
		(net 73)
	)
	(segment
		(start 130.852 87.334)
		(end 130.81 87.376)
		(width 0.5)
		(layer "B.Cu")
		(net 73)
	)
	(segment
		(start 130.048 86.36)
		(end 130.81 86.36)
		(width 0.5)
		(layer "B.Cu")
		(net 73)
	)
	(segment
		(start 130.048 86.36)
		(end 130.09 86.318)
		(width 0.5)
		(layer "B.Cu")
		(net 73)
	)
	(segment
		(start 130.048 87.376)
		(end 130.81 87.376)
		(width 0.5)
		(layer "B.Cu")
		(net 73)
	)
	(segment
		(start 186.159 54.864)
		(end 186.159 54.482488)
		(width 0.187)
		(layer "F.Cu")
		(net 74)
	)
	(segment
		(start 186.36 54.281488)
		(end 186.36 53.623)
		(width 0.187)
		(layer "F.Cu")
		(net 74)
	)
	(segment
		(start 186.159 54.482488)
		(end 186.36 54.281488)
		(width 0.187)
		(layer "F.Cu")
		(net 74)
	)
	(segment
		(start 144.708 74.249)
		(end 144.708 75.881441)
		(width 0.125)
		(layer "F.Cu")
		(net 75)
	)
	(segment
		(start 144.708 75.881441)
		(end 145.718664 76.892105)
		(width 0.125)
		(layer "F.Cu")
		(net 75)
	)
	(segment
		(start 150.580023 80.073378)
		(end 151.151401 79.502)
		(width 0.187)
		(layer "F.Cu")
		(net 76)
	)
	(segment
		(start 151.151401 79.502)
		(end 151.688801 79.502)
		(width 0.187)
		(layer "F.Cu")
		(net 76)
	)
	(segment
		(start 151.688801 79.502)
		(end 152.007305 79.183496)
		(width 0.187)
		(layer "F.Cu")
		(net 76)
	)
	(segment
		(start 152.668756 79.844947)
		(end 152.692053 79.844947)
		(width 0.187)
		(layer "F.Cu")
		(net 76)
	)
	(segment
		(start 152.007305 79.183496)
		(end 152.668756 79.844947)
		(width 0.187)
		(layer "F.Cu")
		(net 76)
	)
	(segment
		(start 141.77 79.68)
		(end 142.144013 79.68)
		(width 0.187)
		(layer "F.Cu")
		(net 77)
	)
	(segment
		(start 142.144013 79.68)
		(end 142.537391 80.073378)
		(width 0.187)
		(layer "F.Cu")
		(net 77)
	)
	(segment
		(start 141.229411 79.166483)
		(end 141.229411 79.139411)
		(width 0.187)
		(layer "F.Cu")
		(net 77)
	)
	(segment
		(start 141.229411 79.139411)
		(end 141.77 79.68)
		(width 0.187)
		(layer "F.Cu")
		(net 77)
	)
	(segment
		(start 140.550947 79.844947)
		(end 141.229411 79.166483)
		(width 0.187)
		(layer "F.Cu")
		(net 77)
	)
	(segment
		(start 143.692 75.572547)
		(end 145.365111 77.245658)
		(width 0.187)
		(layer "F.Cu")
		(net 78)
	)
	(segment
		(start 143.692 74.145)
		(end 143.692 75.572547)
		(width 0.187)
		(layer "F.Cu")
		(net 78)
	)
	(segment
		(start 148.717 76.2)
		(end 148.882053 76.034947)
		(width 0.187)
		(layer "F.Cu")
		(net 79)
	)
	(segment
		(start 148.717 76.988069)
		(end 148.717 76.2)
		(width 0.187)
		(layer "F.Cu")
		(net 79)
	)
	(segment
		(start 148.105857 77.599212)
		(end 148.717 76.988069)
		(width 0.187)
		(layer "F.Cu")
		(net 79)
	)
	(segment
		(start 156.188 78.254)
		(end 168.148 66.294)
		(width 0.187)
		(layer "F.Cu")
		(net 80)
	)
	(segment
		(start 168.91 66.294)
		(end 170.18 65.024)
		(width 0.187)
		(layer "F.Cu")
		(net 80)
	)
	(segment
		(start 156.188 78.695234)
		(end 156.188 78.254)
		(width 0.187)
		(layer "F.Cu")
		(net 80)
	)
	(segment
		(start 151.786645 81.28)
		(end 153.603234 81.28)
		(width 0.187)
		(layer "F.Cu")
		(net 80)
	)
	(segment
		(start 168.148 66.294)
		(end 168.91 66.294)
		(width 0.187)
		(layer "F.Cu")
		(net 80)
	)
	(segment
		(start 151.640684 81.134039)
		(end 151.786645 81.28)
		(width 0.187)
		(layer "F.Cu")
		(net 80)
	)
	(segment
		(start 153.603234 81.28)
		(end 156.188 78.695234)
		(width 0.187)
		(layer "F.Cu")
		(net 80)
	)
	(segment
		(start 170.18 65.024)
		(end 170.18 64.62)
		(width 0.187)
		(layer "F.Cu")
		(net 80)
	)
	(segment
		(start 167.64 65.532)
		(end 168.656 65.532)
		(width 0.187)
		(layer "F.Cu")
		(net 81)
	)
	(segment
		(start 153.543 80.899)
		(end 155.876 78.566)
		(width 0.187)
		(layer "F.Cu")
		(net 81)
	)
	(segment
		(start 155.876 78.566)
		(end 155.876 77.296)
		(width 0.187)
		(layer "F.Cu")
		(net 81)
	)
	(segment
		(start 151.892 80.391)
		(end 152.4 80.899)
		(width 0.187)
		(layer "F.Cu")
		(net 81)
	)
	(segment
		(start 151.676615 80.391)
		(end 151.892 80.391)
		(width 0.187)
		(layer "F.Cu")
		(net 81)
	)
	(segment
		(start 152.4 80.899)
		(end 153.543 80.899)
		(width 0.187)
		(layer "F.Cu")
		(net 81)
	)
	(segment
		(start 151.28713 80.780485)
		(end 151.676615 80.391)
		(width 0.187)
		(layer "F.Cu")
		(net 81)
	)
	(segment
		(start 168.656 65.532)
		(end 168.91 65.278)
		(width 0.187)
		(layer "F.Cu")
		(net 81)
	)
	(segment
		(start 155.876 77.296)
		(end 167.64 65.532)
		(width 0.187)
		(layer "F.Cu")
		(net 81)
	)
	(segment
		(start 168.91 65.278)
		(end 168.91 64.62)
		(width 0.187)
		(layer "F.Cu")
		(net 81)
	)
	(segment
		(start 167.386 64.516)
		(end 167.386 60.302)
		(width 0.187)
		(layer "F.Cu")
		(net 82)
	)
	(segment
		(start 155.114 76.788)
		(end 167.386 64.516)
		(width 0.187)
		(layer "F.Cu")
		(net 82)
	)
	(segment
		(start 150.933577 80.426932)
		(end 151.477509 79.883)
		(width 0.187)
		(layer "F.Cu")
		(net 82)
	)
	(segment
		(start 151.892 79.883)
		(end 152.527 80.518)
		(width 0.187)
		(layer "F.Cu")
		(net 82)
	)
	(segment
		(start 151.477509 79.883)
		(end 151.892 79.883)
		(width 0.187)
		(layer "F.Cu")
		(net 82)
	)
	(segment
		(start 152.527 80.518)
		(end 153.0604 80.518)
		(width 0.187)
		(layer "F.Cu")
		(net 82)
	)
	(segment
		(start 155.114 78.4644)
		(end 155.114 76.788)
		(width 0.187)
		(layer "F.Cu")
		(net 82)
	)
	(segment
		(start 153.0604 80.518)
		(end 155.114 78.4644)
		(width 0.187)
		(layer "F.Cu")
		(net 82)
	)
	(segment
		(start 149.753 73.025)
		(end 149.24 73.538)
		(width 0.187)
		(layer "F.Cu")
		(net 83)
	)
	(segment
		(start 150.876 73.025)
		(end 149.753 73.025)
		(width 0.187)
		(layer "F.Cu")
		(net 83)
	)
	(segment
		(start 148.209 76.788961)
		(end 147.752303 77.245658)
		(width 0.187)
		(layer "F.Cu")
		(net 83)
	)
	(segment
		(start 149.24 73.538)
		(end 149.24 74.915446)
		(width 0.187)
		(layer "F.Cu")
		(net 83)
	)
	(segment
		(start 149.24 74.915446)
		(end 148.209 75.946446)
		(width 0.187)
		(layer "F.Cu")
		(net 83)
	)
	(segment
		(start 148.209 75.946446)
		(end 148.209 76.788961)
		(width 0.187)
		(layer "F.Cu")
		(net 83)
	)
	(segment
		(start 166.116 63.5)
		(end 166.116 60.302)
		(width 0.187)
		(layer "F.Cu")
		(net 83)
	)
	(via
		(at 166.116 63.5)
		(size 0.6)
		(drill 0.35)
		(layers "F.Cu" "B.Cu")
		(net 83)
	)
	(via
		(at 150.876 73.025)
		(size 0.6)
		(drill 0.35)
		(layers "F.Cu" "B.Cu")
		(net 83)
	)
	(segment
		(start 166.116 65.024)
		(end 166.116 63.5)
		(width 0.187)
		(layer "B.Cu")
		(net 83)
	)
	(segment
		(start 160.02 71.12)
		(end 166.116 65.024)
		(width 0.187)
		(layer "B.Cu")
		(net 83)
	)
	(segment
		(start 150.876 73.025)
		(end 152.781 71.12)
		(width 0.187)
		(layer "B.Cu")
		(net 83)
	)
	(segment
		(start 152.781 71.12)
		(end 160.02 71.12)
		(width 0.187)
		(layer "B.Cu")
		(net 83)
	)
	(segment
		(start 141.572 93.566)
		(end 141.572 98.013524)
		(width 0.187)
		(layer "F.Cu")
		(net 84)
	)
	(segment
		(start 142.39 98.85)
		(end 157.536 98.85)
		(width 0.187)
		(layer "F.Cu")
		(net 84)
	)
	(segment
		(start 161.71 97.89)
		(end 163.3 96.3)
		(width 0.187)
		(layer "F.Cu")
		(net 84)
	)
	(segment
		(start 138.85 88)
		(end 138.85 89.21)
		(width 0.187)
		(layer "F.Cu")
		(net 84)
	)
	(segment
		(start 141.224 93.218)
		(end 141.572 93.566)
		(width 0.187)
		(layer "F.Cu")
		(net 84)
	)
	(segment
		(start 141.572 98.013524)
		(end 141.562762 98.022762)
		(width 0.187)
		(layer "F.Cu")
		(net 84)
	)
	(segment
		(start 158.496 97.89)
		(end 161.71 97.89)
		(width 0.187)
		(layer "F.Cu")
		(net 84)
	)
	(segment
		(start 147.82 75.5)
		(end 147.82 76.470855)
		(width 0.187)
		(layer "F.Cu")
		(net 84)
	)
	(segment
		(start 141.562762 98.022762)
		(end 142.39 98.85)
		(width 0.187)
		(layer "F.Cu")
		(net 84)
	)
	(segment
		(start 147.82 76.470855)
		(end 147.39875 76.892105)
		(width 0.187)
		(layer "F.Cu")
		(net 84)
	)
	(segment
		(start 141.224 91.584)
		(end 141.224 93.218)
		(width 0.187)
		(layer "F.Cu")
		(net 84)
	)
	(segment
		(start 157.536 98.85)
		(end 158.496 97.89)
		(width 0.187)
		(layer "F.Cu")
		(net 84)
	)
	(segment
		(start 138.85 89.21)
		(end 141.224 91.584)
		(width 0.187)
		(layer "F.Cu")
		(net 84)
	)
	(via
		(at 147.82 75.5)
		(size 0.6)
		(drill 0.35)
		(layers "F.Cu" "B.Cu")
		(net 84)
	)
	(via
		(at 163.3 96.3)
		(size 0.6)
		(drill 0.35)
		(layers "F.Cu" "B.Cu")
		(net 84)
	)
	(via
		(at 138.85 88)
		(size 0.6)
		(drill 0.35)
		(layers "F.Cu" "B.Cu")
		(net 84)
	)
	(segment
		(start 163.93 96.85)
		(end 164.1 96.68)
		(width 0.187)
		(layer "B.Cu")
		(net 84)
	)
	(segment
		(start 162.95 96.85)
		(end 163.93 96.85)
		(width 0.187)
		(layer "B.Cu")
		(net 84)
	)
	(segment
		(start 162.95 96.5)
		(end 162.95 96.85)
		(width 0.187)
		(layer "B.Cu")
		(net 84)
	)
	(segment
		(start 163.15 96.3)
		(end 162.95 96.5)
		(width 0.187)
		(layer "B.Cu")
		(net 84)
	)
	(segment
		(start 163.3 96.3)
		(end 163.15 96.3)
		(width 0.187)
		(layer "B.Cu")
		(net 84)
	)
	(segment
		(start 146.7 76.62)
		(end 147.82 75.5)
		(width 0.187)
		(layer "In2.Cu")
		(net 84)
	)
	(segment
		(start 138.85 88)
		(end 138.85 87.77873)
		(width 0.187)
		(layer "In2.Cu")
		(net 84)
	)
	(segment
		(start 143.51 81.5)
		(end 146.7 78.31)
		(width 0.187)
		(layer "In2.Cu")
		(net 84)
	)
	(segment
		(start 143.51 83.11873)
		(end 143.51 81.5)
		(width 0.187)
		(layer "In2.Cu")
		(net 84)
	)
	(segment
		(start 146.7 78.31)
		(end 146.7 76.62)
		(width 0.187)
		(layer "In2.Cu")
		(net 84)
	)
	(segment
		(start 138.85 87.77873)
		(end 143.51 83.11873)
		(width 0.187)
		(layer "In2.Cu")
		(net 84)
	)
	(segment
		(start 147.385677 75.946)
		(end 146.812 75.372323)
		(width 0.187)
		(layer "F.Cu")
		(net 85)
	)
	(segment
		(start 146.812 75.372323)
		(end 146.812 74.422)
		(width 0.187)
		(layer "F.Cu")
		(net 85)
	)
	(segment
		(start 147.045197 76.538552)
		(end 147.385677 76.198072)
		(width 0.187)
		(layer "F.Cu")
		(net 85)
	)
	(segment
		(start 147.385677 76.198072)
		(end 147.385677 75.946)
		(width 0.187)
		(layer "F.Cu")
		(net 85)
	)
	(segment
		(start 136.222 84.914)
		(end 136.846 84.914)
		(width 0.187)
		(layer "F.Cu")
		(net 86)
	)
	(segment
		(start 163.83 73.152)
		(end 166.37 70.612)
		(width 0.187)
		(layer "F.Cu")
		(net 86)
	)
	(segment
		(start 136.86 84.9)
		(end 136.86 83.34)
		(width 0.187)
		(layer "F.Cu")
		(net 86)
	)
	(segment
		(start 168.148 70.612)
		(end 168.903 69.857)
		(width 0.187)
		(layer "F.Cu")
		(net 86)
	)
	(segment
		(start 136.38 86.23)
		(end 136.86 85.75)
		(width 0.187)
		(layer "F.Cu")
		(net 86)
	)
	(segment
		(start 166.37 70.612)
		(end 168.148 70.612)
		(width 0.187)
		(layer "F.Cu")
		(net 86)
	)
	(segment
		(start 136.846 84.914)
		(end 136.86 84.9)
		(width 0.187)
		(layer "F.Cu")
		(net 86)
	)
	(segment
		(start 141.14 80.01)
		(end 141.766905 80.01)
		(width 0.187)
		(layer "F.Cu")
		(net 86)
	)
	(segment
		(start 136.38 86.759)
		(end 136.38 86.23)
		(width 0.187)
		(layer "F.Cu")
		(net 86)
	)
	(segment
		(start 141.766905 80.01)
		(end 142.183837 80.426932)
		(width 0.187)
		(layer "F.Cu")
		(net 86)
	)
	(segment
		(start 168.903 69.857)
		(end 170.195 69.857)
		(width 0.187)
		(layer "F.Cu")
		(net 86)
	)
	(segment
		(start 140.713425 80.436575)
		(end 141.14 80.01)
		(width 0.187)
		(layer "F.Cu")
		(net 86)
	)
	(segment
		(start 139.763425 80.436575)
		(end 140.713425 80.436575)
		(width 0.187)
		(layer "F.Cu")
		(net 86)
	)
	(segment
		(start 136.86 85.75)
		(end 136.86 84.9)
		(width 0.187)
		(layer "F.Cu")
		(net 86)
	)
	(segment
		(start 136.86 83.34)
		(end 139.763425 80.436575)
		(width 0.187)
		(layer "F.Cu")
		(net 86)
	)
	(via
		(at 136.38 86.759)
		(size 0.6)
		(drill 0.35)
		(layers "F.Cu" "B.Cu")
		(net 86)
	)
	(via
		(at 163.83 73.152)
		(size 0.6)
		(drill 0.35)
		(layers "F.Cu" "B.Cu")
		(net 86)
	)
	(segment
		(start 156.776 77.853234)
		(end 159.953234 74.676)
		(width 0.187)
		(layer "B.Cu")
		(net 86)
	)
	(segment
		(start 137.668 86.868)
		(end 138.0365 86.4995)
		(width 0.187)
		(layer "B.Cu")
		(net 86)
	)
	(segment
		(start 159.953234 74.676)
		(end 162.306 74.676)
		(width 0.187)
		(layer "B.Cu")
		(net 86)
	)
	(segment
		(start 146.986734 86.4995)
		(end 152.727134 80.7591)
		(width 0.187)
		(layer "B.Cu")
		(net 86)
	)
	(segment
		(start 156.776 78.428)
		(end 156.776 77.853234)
		(width 0.187)
		(layer "B.Cu")
		(net 86)
	)
	(segment
		(start 154.4449 80.7591)
		(end 156.776 78.428)
		(width 0.187)
		(layer "B.Cu")
		(net 86)
	)
	(segment
		(start 138.0365 86.4995)
		(end 146.986734 86.4995)
		(width 0.187)
		(layer "B.Cu")
		(net 86)
	)
	(segment
		(start 136.489 86.868)
		(end 137.668 86.868)
		(width 0.187)
		(layer "B.Cu")
		(net 86)
	)
	(segment
		(start 162.306 74.676)
		(end 163.83 73.152)
		(width 0.187)
		(layer "B.Cu")
		(net 86)
	)
	(segment
		(start 136.38 86.759)
		(end 136.489 86.868)
		(width 0.187)
		(layer "B.Cu")
		(net 86)
	)
	(segment
		(start 152.727134 80.7591)
		(end 154.4449 80.7591)
		(width 0.187)
		(layer "B.Cu")
		(net 86)
	)
	(segment
		(start 168.148 69.342)
		(end 167.64 69.85)
		(width 0.187)
		(layer "F.Cu")
		(net 87)
	)
	(segment
		(start 165.862 69.85)
		(end 162.814 72.898)
		(width 0.187)
		(layer "F.Cu")
		(net 87)
	)
	(segment
		(start 137.2035 86.35)
		(end 137.668 85.8855)
		(width 0.187)
		(layer "F.Cu")
		(net 87)
	)
	(segment
		(start 162.814 72.898)
		(end 162.052 73.66)
		(width 0.187)
		(layer "F.Cu")
		(net 87)
	)
	(segment
		(start 140.842659 80.748575)
		(end 141.189312 80.401922)
		(width 0.187)
		(layer "F.Cu")
		(net 87)
	)
	(segment
		(start 138.33 84.938)
		(end 137.68 84.938)
		(width 0.187)
		(layer "F.Cu")
		(net 87)
	)
	(segment
		(start 137.668 84.95)
		(end 137.668 82.973234)
		(width 0.187)
		(layer "F.Cu")
		(net 87)
	)
	(segment
		(start 168.148 68.834)
		(end 168.148 69.342)
		(width 0.187)
		(layer "F.Cu")
		(net 87)
	)
	(segment
		(start 170.202 67.818)
		(end 169.164 67.818)
		(width 0.187)
		(layer "F.Cu")
		(net 87)
	)
	(segment
		(start 169.164 67.818)
		(end 168.148 68.834)
		(width 0.187)
		(layer "F.Cu")
		(net 87)
	)
	(segment
		(start 137.668 85.8855)
		(end 137.668 84.95)
		(width 0.187)
		(layer "F.Cu")
		(net 87)
	)
	(segment
		(start 141.189312 80.401922)
		(end 141.451721 80.401922)
		(width 0.187)
		(layer "F.Cu")
		(net 87)
	)
	(segment
		(start 139.892659 80.748575)
		(end 140.842659 80.748575)
		(width 0.187)
		(layer "F.Cu")
		(net 87)
	)
	(segment
		(start 167.64 69.85)
		(end 166.878 69.85)
		(width 0.187)
		(layer "F.Cu")
		(net 87)
	)
	(segment
		(start 166.878 69.85)
		(end 165.862 69.85)
		(width 0.187)
		(layer "F.Cu")
		(net 87)
	)
	(segment
		(start 141.451721 80.401922)
		(end 141.830284 80.780485)
		(width 0.187)
		(layer "F.Cu")
		(net 87)
	)
	(segment
		(start 137.668 82.973234)
		(end 139.892659 80.748575)
		(width 0.187)
		(layer "F.Cu")
		(net 87)
	)
	(segment
		(start 137.68 84.938)
		(end 137.668 84.95)
		(width 0.187)
		(layer "F.Cu")
		(net 87)
	)
	(via
		(at 162.052 73.66)
		(size 0.6)
		(drill 0.35)
		(layers "F.Cu" "B.Cu")
		(net 87)
	)
	(via
		(at 137.2035 86.35)
		(size 0.6)
		(drill 0.35)
		(layers "F.Cu" "B.Cu")
		(net 87)
	)
	(segment
		(start 137.2035 86.35)
		(end 137.366 86.1875)
		(width 0.187)
		(layer "B.Cu")
		(net 87)
	)
	(segment
		(start 160.02 74.168)
		(end 161.544 74.168)
		(width 0.187)
		(layer "B.Cu")
		(net 87)
	)
	(segment
		(start 161.544 74.168)
		(end 162.052 73.66)
		(width 0.187)
		(layer "B.Cu")
		(net 87)
	)
	(segment
		(start 146.8575 86.1875)
		(end 152.5979 80.4471)
		(width 0.187)
		(layer "B.Cu")
		(net 87)
	)
	(segment
		(start 156.464 77.724)
		(end 160.02 74.168)
		(width 0.187)
		(layer "B.Cu")
		(net 87)
	)
	(segment
		(start 137.366 86.1875)
		(end 146.8575 86.1875)
		(width 0.187)
		(layer "B.Cu")
		(net 87)
	)
	(segment
		(start 152.5979 80.4471)
		(end 154.315666 80.4471)
		(width 0.187)
		(layer "B.Cu")
		(net 87)
	)
	(segment
		(start 154.315666 80.4471)
		(end 156.464 78.298766)
		(width 0.187)
		(layer "B.Cu")
		(net 87)
	)
	(segment
		(start 156.464 78.298766)
		(end 156.464 77.724)
		(width 0.187)
		(layer "B.Cu")
		(net 87)
	)
	(segment
		(start 170.196 68.834)
		(end 170.197 68.833)
		(width 0.187)
		(layer "F.Cu")
		(net 88)
	)
	(segment
		(start 140.435969 81.419006)
		(end 141.102668 81.419006)
		(width 0.187)
		(layer "F.Cu")
		(net 88)
	)
	(segment
		(start 141.102668 81.419006)
		(end 141.431476 81.090198)
		(width 0.187)
		(layer "F.Cu")
		(net 88)
	)
	(segment
		(start 169.164 68.834)
		(end 170.196 68.834)
		(width 0.187)
		(layer "F.Cu")
		(net 88)
	)
	(via
		(at 140.435969 81.419006)
		(size 0.6)
		(drill 0.35)
		(layers "F.Cu" "B.Cu")
		(net 88)
	)
	(via
		(at 169.164 68.834)
		(size 0.6)
		(drill 0.35)
		(layers "F.Cu" "B.Cu")
		(net 88)
	)
	(segment
		(start 155.194 77.216)
		(end 164.592 67.818)
		(width 0.187)
		(layer "B.Cu")
		(net 88)
	)
	(segment
		(start 145.542 84.709)
		(end 147.066 84.709)
		(width 0.187)
		(layer "B.Cu")
		(net 88)
	)
	(segment
		(start 164.592 67.818)
		(end 167.64 67.818)
		(width 0.187)
		(layer "B.Cu")
		(net 88)
	)
	(segment
		(start 140.435969 81.419006)
		(end 142.252006 81.419006)
		(width 0.187)
		(layer "B.Cu")
		(net 88)
	)
	(segment
		(start 147.066 84.709)
		(end 152.2222 79.5528)
		(width 0.187)
		(layer "B.Cu")
		(net 88)
	)
	(segment
		(start 152.2222 79.5528)
		(end 153.705079 79.5528)
		(width 0.187)
		(layer "B.Cu")
		(net 88)
	)
	(segment
		(start 153.705079 79.5528)
		(end 155.194 78.063879)
		(width 0.187)
		(layer "B.Cu")
		(net 88)
	)
	(segment
		(start 168.656 68.834)
		(end 169.164 68.834)
		(width 0.187)
		(layer "B.Cu")
		(net 88)
	)
	(segment
		(start 155.194 78.063879)
		(end 155.194 77.216)
		(width 0.187)
		(layer "B.Cu")
		(net 88)
	)
	(segment
		(start 167.64 67.818)
		(end 168.656 68.834)
		(width 0.187)
		(layer "B.Cu")
		(net 88)
	)
	(segment
		(start 142.252006 81.419006)
		(end 145.542 84.709)
		(width 0.187)
		(layer "B.Cu")
		(net 88)
	)
	(segment
		(start 145.467 93.7)
		(end 145.467 93.666521)
		(width 0.155)
		(layer "F.Cu")
		(net 89)
	)
	(segment
		(start 167.629 90.597)
		(end 167.629 89.689591)
		(width 0.155)
		(layer "F.Cu")
		(net 89)
	)
	(segment
		(start 159.07301 93.84)
		(end 146.727 93.84)
		(width 0.155)
		(layer "F.Cu")
		(net 89)
	)
	(segment
		(start 162.75601 90.157)
		(end 159.07301 93.84)
		(width 0.155)
		(layer "F.Cu")
		(net 89)
	)
	(segment
		(start 142.634 92.14401)
		(end 142.634 85.743225)
		(width 0.155)
		(layer "F.Cu")
		(net 89)
	)
	(segment
		(start 146.307 93.666521)
		(end 146.307 93.7)
		(width 0.155)
		(layer "F.Cu")
		(net 89)
	)
	(segment
		(start 166.429 90.904409)
		(end 166.429 90.597)
		(width 0.155)
		(layer "F.Cu")
		(net 89)
	)
	(segment
		(start 142.634 85.743225)
		(end 143.796041 84.581184)
		(width 0.155)
		(layer "F.Cu")
		(net 89)
	)
	(segment
		(start 146.027 93.7)
		(end 146.027 93.666521)
		(width 0.155)
		(layer "F.Cu")
		(net 89)
	)
	(segment
		(start 144.32999 93.84)
		(end 142.634 92.14401)
		(width 0.155)
		(layer "F.Cu")
		(net 89)
	)
	(segment
		(start 143.796041 84.581184)
		(end 143.950897 84.581184)
		(width 0.155)
		(layer "F.Cu")
		(net 89)
	)
	(segment
		(start 169.542673 89.278673)
		(end 169.542673 89.593337)
		(width 0.155)
		(layer "F.Cu")
		(net 89)
	)
	(segment
		(start 145.747 93.666521)
		(end 145.747 93.7)
		(width 0.155)
		(layer "F.Cu")
		(net 89)
	)
	(segment
		(start 145.047 93.84)
		(end 144.32999 93.84)
		(width 0.155)
		(layer "F.Cu")
		(net 89)
	)
	(segment
		(start 166.749 89.689591)
		(end 166.749 90.157)
		(width 0.155)
		(layer "F.Cu")
		(net 89)
	)
	(segment
		(start 168.97901 90.157)
		(end 168.389 90.157)
		(width 0.155)
		(layer "F.Cu")
		(net 89)
	)
	(segment
		(start 167.949 90.597)
		(end 167.949 90.904409)
		(width 0.155)
		(layer "F.Cu")
		(net 89)
	)
	(segment
		(start 175.44301 82.806327)
		(end 175.128346 82.806327)
		(width 0.155)
		(layer "F.Cu")
		(net 89)
	)
	(segment
		(start 145.187 93.666521)
		(end 145.187 93.7)
		(width 0.155)
		(layer "F.Cu")
		(net 89)
	)
	(segment
		(start 169.542673 89.593337)
		(end 168.97901 90.157)
		(width 0.155)
		(layer "F.Cu")
		(net 89)
	)
	(segment
		(start 146.587 93.7)
		(end 146.587 93.666521)
		(width 0.155)
		(layer "F.Cu")
		(net 89)
	)
	(segment
		(start 183.886 83.433)
		(end 183.776 83.323)
		(width 0.155)
		(layer "F.Cu")
		(net 89)
	)
	(segment
		(start 167.629 90.904409)
		(end 167.629 90.597)
		(width 0.155)
		(layer "F.Cu")
		(net 89)
	)
	(segment
		(start 183.776 83.323)
		(end 175.959683 83.323)
		(width 0.155)
		(layer "F.Cu")
		(net 89)
	)
	(segment
		(start 166.749 90.157)
		(end 166.749 90.904409)
		(width 0.155)
		(layer "F.Cu")
		(net 89)
	)
	(segment
		(start 165.989 90.157)
		(end 162.75601 90.157)
		(width 0.155)
		(layer "F.Cu")
		(net 89)
	)
	(segment
		(start 175.959683 83.323)
		(end 175.44301 82.806327)
		(width 0.155)
		(layer "F.Cu")
		(net 89)
	)
	(via
		(at 169.542673 89.278673)
		(size 0.6)
		(drill 0.35)
		(layers "F.Cu" "B.Cu")
		(net 89)
	)
	(via
		(at 175.128346 82.806327)
		(size 0.6)
		(drill 0.35)
		(layers "F.Cu" "B.Cu")
		(net 89)
	)
	(arc
		(start 168.389 90.157)
		(mid 168.077873 90.285873)
		(end 167.949 90.597)
		(width 0.155)
		(layer "F.Cu")
		(net 89)
	)
	(arc
		(start 146.167 93.84)
		(mid 146.068005 93.798995)
		(end 146.027 93.7)
		(width 0.155)
		(layer "F.Cu")
		(net 89)
	)
	(arc
		(start 146.027 93.666521)
		(mid 145.985995 93.567526)
		(end 145.887 93.526521)
		(width 0.155)
		(layer "F.Cu")
		(net 89)
	)
	(arc
		(start 146.307 93.7)
		(mid 146.265995 93.798995)
		(end 146.167 93.84)
		(width 0.155)
		(layer "F.Cu")
		(net 89)
	)
	(arc
		(start 146.447 93.526521)
		(mid 146.348005 93.567526)
		(end 146.307 93.666521)
		(width 0.155)
		(layer "F.Cu")
		(net 89)
	)
	(arc
		(start 146.587 93.666521)
		(mid 146.545995 93.567526)
		(end 146.447 93.526521)
		(width 0.155)
		(layer "F.Cu")
		(net 89)
	)
	(arc
		(start 167.949 90.904409)
		(mid 167.902137 91.017546)
		(end 167.789 91.064409)
		(width 0.155)
		(layer "F.Cu")
		(net 89)
	)
	(arc
		(start 167.629 89.689591)
		(mid 167.500127 89.378464)
		(end 167.189 89.249591)
		(width 0.155)
		(layer "F.Cu")
		(net 89)
	)
	(arc
		(start 146.727 93.84)
		(mid 146.628005 93.798995)
		(end 146.587 93.7)
		(width 0.155)
		(layer "F.Cu")
		(net 89)
	)
	(arc
		(start 145.327 93.526521)
		(mid 145.228005 93.567526)
		(end 145.187 93.666521)
		(width 0.155)
		(layer "F.Cu")
		(net 89)
	)
	(arc
		(start 166.589 91.064409)
		(mid 166.475863 91.017546)
		(end 166.429 90.904409)
		(width 0.155)
		(layer "F.Cu")
		(net 89)
	)
	(arc
		(start 145.747 93.7)
		(mid 145.705995 93.798995)
		(end 145.607 93.84)
		(width 0.155)
		(layer "F.Cu")
		(net 89)
	)
	(arc
		(start 145.187 93.7)
		(mid 145.145995 93.798995)
		(end 145.047 93.84)
		(width 0.155)
		(layer "F.Cu")
		(net 89)
	)
	(arc
		(start 145.467 93.666521)
		(mid 145.425995 93.567526)
		(end 145.327 93.526521)
		(width 0.155)
		(layer "F.Cu")
		(net 89)
	)
	(arc
		(start 166.749 90.904409)
		(mid 166.702137 91.017546)
		(end 166.589 91.064409)
		(width 0.155)
		(layer "F.Cu")
		(net 89)
	)
	(arc
		(start 167.789 91.064409)
		(mid 167.675863 91.017546)
		(end 167.629 90.904409)
		(width 0.155)
		(layer "F.Cu")
		(net 89)
	)
	(arc
		(start 145.607 93.84)
		(mid 145.508005 93.798995)
		(end 145.467 93.7)
		(width 0.155)
		(layer "F.Cu")
		(net 89)
	)
	(arc
		(start 167.189 89.249591)
		(mid 166.877873 89.378464)
		(end 166.749 89.689591)
		(width 0.155)
		(layer "F.Cu")
		(net 89)
	)
	(arc
		(start 145.887 93.526521)
		(mid 145.788005 93.567526)
		(end 145.747 93.666521)
		(width 0.155)
		(layer "F.Cu")
		(net 89)
	)
	(arc
		(start 166.429 90.597)
		(mid 166.300127 90.285873)
		(end 165.989 90.157)
		(width 0.155)
		(layer "F.Cu")
		(net 89)
	)
	(segment
		(start 175.882 86.68301)
		(end 174.31301 88.252)
		(width 0.155)
		(layer "B.Cu")
		(net 89)
	)
	(segment
		(start 170.88401 88.252)
		(end 169.857337 89.278673)
		(width 0.155)
		(layer "B.Cu")
		(net 89)
	)
	(segment
		(start 175.128346 82.806327)
		(end 175.44301 82.806327)
		(width 0.155)
		(layer "B.Cu")
		(net 89)
	)
	(segment
		(start 175.882 83.245317)
		(end 175.882 86.68301)
		(width 0.155)
		(layer "B.Cu")
		(net 89)
	)
	(segment
		(start 175.44301 82.806327)
		(end 175.882 83.245317)
		(width 0.155)
		(layer "B.Cu")
		(net 89)
	)
	(segment
		(start 169.857337 89.278673)
		(end 169.542673 89.278673)
		(width 0.155)
		(layer "B.Cu")
		(net 89)
	)
	(segment
		(start 174.31301 88.252)
		(end 170.88401 88.252)
		(width 0.155)
		(layer "B.Cu")
		(net 89)
	)
	(segment
		(start 169.09499 90.437)
		(end 168.389 90.437)
		(width 0.155)
		(layer "F.Cu")
		(net 90)
	)
	(segment
		(start 167.029 89.689591)
		(end 167.029 90.157)
		(width 0.155)
		(layer "F.Cu")
		(net 90)
	)
	(segment
		(start 175.641 82.608337)
		(end 176.075663 83.043)
		(width 0.155)
		(layer "F.Cu")
		(net 90)
	)
	(segment
		(start 183.776 83.043)
		(end 183.886 82.933)
		(width 0.155)
		(layer "F.Cu")
		(net 90)
	)
	(segment
		(start 159.18899 94.12)
		(end 144.21401 94.12)
		(width 0.155)
		(layer "F.Cu")
		(net 90)
	)
	(segment
		(start 144.21401 94.12)
		(end 142.354 92.25999)
		(width 0.155)
		(layer "F.Cu")
		(net 90)
	)
	(segment
		(start 142.354 92.25999)
		(end 142.354 85.627245)
		(width 0.155)
		(layer "F.Cu")
		(net 90)
	)
	(segment
		(start 167.349 90.597)
		(end 167.349 89.689591)
		(width 0.155)
		(layer "F.Cu")
		(net 90)
	)
	(segment
		(start 176.075663 83.043)
		(end 183.776 83.043)
		(width 0.155)
		(layer "F.Cu")
		(net 90)
	)
	(segment
		(start 166.149 90.904409)
		(end 166.149 90.597)
		(width 0.155)
		(layer "F.Cu")
		(net 90)
	)
	(segment
		(start 143.598051 84.383194)
		(end 143.598051 84.228338)
		(width 0.155)
		(layer "F.Cu")
		(net 90)
	)
	(segment
		(start 167.029 90.157)
		(end 167.029 90.904409)
		(width 0.155)
		(layer "F.Cu")
		(net 90)
	)
	(segment
		(start 162.87199 90.437)
		(end 159.18899 94.12)
		(width 0.155)
		(layer "F.Cu")
		(net 90)
	)
	(segment
		(start 169.740663 89.791327)
		(end 169.09499 90.437)
		(width 0.155)
		(layer "F.Cu")
		(net 90)
	)
	(segment
		(start 167.349 90.904409)
		(end 167.349 90.597)
		(width 0.155)
		(layer "F.Cu")
		(net 90)
	)
	(segment
		(start 165.989 90.437)
		(end 162.87199 90.437)
		(width 0.155)
		(layer "F.Cu")
		(net 90)
	)
	(segment
		(start 175.641 82.293673)
		(end 175.641 82.608337)
		(width 0.155)
		(layer "F.Cu")
		(net 90)
	)
	(segment
		(start 168.229 90.597)
		(end 168.229 90.904409)
		(width 0.155)
		(layer "F.Cu")
		(net 90)
	)
	(segment
		(start 142.354 85.627245)
		(end 143.598051 84.383194)
		(width 0.155)
		(layer "F.Cu")
		(net 90)
	)
	(segment
		(start 170.055327 89.791327)
		(end 169.740663 89.791327)
		(width 0.155)
		(layer "F.Cu")
		(net 90)
	)
	(via
		(at 170.055327 89.791327)
		(size 0.6)
		(drill 0.35)
		(layers "F.Cu" "B.Cu")
		(net 90)
	)
	(via
		(at 175.641 82.293673)
		(size 0.6)
		(drill 0.35)
		(layers "F.Cu" "B.Cu")
		(net 90)
	)
	(arc
		(start 166.149 90.597)
		(mid 166.102137 90.483863)
		(end 165.989 90.437)
		(width 0.155)
		(layer "F.Cu")
		(net 90)
	)
	(arc
		(start 167.189 89.529591)
		(mid 167.075863 89.576454)
		(end 167.029 89.689591)
		(width 0.155)
		(layer "F.Cu")
		(net 90)
	)
	(arc
		(start 168.389 90.437)
		(mid 168.275863 90.483863)
		(end 168.229 90.597)
		(width 0.155)
		(layer "F.Cu")
		(net 90)
	)
	(arc
		(start 168.229 90.904409)
		(mid 168.100127 91.215536)
		(end 167.789 91.344409)
		(width 0.155)
		(layer "F.Cu")
		(net 90)
	)
	(arc
		(start 167.789 91.344409)
		(mid 167.477873 91.215536)
		(end 167.349 90.904409)
		(width 0.155)
		(layer "F.Cu")
		(net 90)
	)
	(arc
		(start 167.349 89.689591)
		(mid 167.302137 89.576454)
		(end 167.189 89.529591)
		(width 0.155)
		(layer "F.Cu")
		(net 90)
	)
	(arc
		(start 166.589 91.344409)
		(mid 166.277873 91.215536)
		(end 166.149 90.904409)
		(width 0.155)
		(layer "F.Cu")
		(net 90)
	)
	(arc
		(start 167.029 90.904409)
		(mid 166.900127 91.215536)
		(end 166.589 91.344409)
		(width 0.155)
		(layer "F.Cu")
		(net 90)
	)
	(segment
		(start 176.162 83.129337)
		(end 176.162 86.79899)
		(width 0.155)
		(layer "B.Cu")
		(net 90)
	)
	(segment
		(start 176.162 86.79899)
		(end 174.42899 88.532)
		(width 0.155)
		(layer "B.Cu")
		(net 90)
	)
	(segment
		(start 175.641 82.293673)
		(end 175.641 82.608337)
		(width 0.155)
		(layer "B.Cu")
		(net 90)
	)
	(segment
		(start 170.055327 89.476663)
		(end 170.055327 89.791327)
		(width 0.155)
		(layer "B.Cu")
		(net 90)
	)
	(segment
		(start 174.42899 88.532)
		(end 170.99999 88.532)
		(width 0.155)
		(layer "B.Cu")
		(net 90)
	)
	(segment
		(start 170.99999 88.532)
		(end 170.055327 89.476663)
		(width 0.155)
		(layer "B.Cu")
		(net 90)
	)
	(segment
		(start 175.641 82.608337)
		(end 176.162 83.129337)
		(width 0.155)
		(layer "B.Cu")
		(net 90)
	)
	(segment
		(start 141.2055 88.138)
		(end 140.983 87.9155)
		(width 0.155)
		(layer "F.Cu")
		(net 91)
	)
	(segment
		(start 183.776 82.323)
		(end 183.886 82.433)
		(width 0.155)
		(layer "F.Cu")
		(net 91)
	)
	(segment
		(start 140.983 87.9155)
		(end 140.983 87.617)
		(width 0.155)
		(layer "F.Cu")
		(net 91)
	)
	(segment
		(start 181.67901 81.801)
		(end 182.20101 82.323)
		(width 0.155)
		(layer "F.Cu")
		(net 91)
	)
	(segment
		(start 140.983 87.057)
		(end 140.983 84.566505)
		(width 0.155)
		(layer "F.Cu")
		(net 91)
	)
	(segment
		(start 140.983 87.113718)
		(end 140.983 87.057)
		(width 0.155)
		(layer "F.Cu")
		(net 91)
	)
	(segment
		(start 182.20101 82.323)
		(end 183.776 82.323)
		(width 0.155)
		(layer "F.Cu")
		(net 91)
	)
	(segment
		(start 141.206282 87.393718)
		(end 141.206282 87.337)
		(width 0.155)
		(layer "F.Cu")
		(net 91)
	)
	(segment
		(start 177.612683 81.801)
		(end 181.67901 81.801)
		(width 0.155)
		(layer "F.Cu")
		(net 91)
	)
	(segment
		(start 176.906346 81.409327)
		(end 177.22101 81.409327)
		(width 0.155)
		(layer "F.Cu")
		(net 91)
	)
	(segment
		(start 177.22101 81.409327)
		(end 177.612683 81.801)
		(width 0.155)
		(layer "F.Cu")
		(net 91)
	)
	(segment
		(start 142.381827 83.167678)
		(end 142.537391 83.167678)
		(width 0.155)
		(layer "F.Cu")
		(net 91)
	)
	(segment
		(start 140.983 84.566505)
		(end 142.381827 83.167678)
		(width 0.155)
		(layer "F.Cu")
		(net 91)
	)
	(via
		(at 176.906346 81.409327)
		(size 0.6)
		(drill 0.35)
		(layers "F.Cu" "B.Cu")
		(net 91)
	)
	(via
		(at 141.2055 88.138)
		(size 0.6)
		(drill 0.35)
		(layers "F.Cu" "B.Cu")
		(net 91)
	)
	(arc
		(start 141.094641 87.225359)
		(mid 141.015699 87.19266)
		(end 140.983 87.113718)
		(width 0.155)
		(layer "F.Cu")
		(net 91)
	)
	(arc
		(start 140.983 87.617)
		(mid 141.015699 87.538058)
		(end 141.094641 87.505359)
		(width 0.155)
		(layer "F.Cu")
		(net 91)
	)
	(arc
		(start 141.094641 87.505359)
		(mid 141.173583 87.47266)
		(end 141.206282 87.393718)
		(width 0.155)
		(layer "F.Cu")
		(net 91)
	)
	(arc
		(start 141.206282 87.337)
		(mid 141.173583 87.258058)
		(end 141.094641 87.225359)
		(width 0.155)
		(layer "F.Cu")
		(net 91)
	)
	(segment
		(start 177.406 83.763)
		(end 177.406 85.613)
		(width 0.155)
		(layer "B.Cu")
		(net 91)
	)
	(segment
		(start 143.44099 93.84)
		(end 140.983 91.38201)
		(width 0.155)
		(layer "B.Cu")
		(net 91)
	)
	(segment
		(start 176.906346 81.409327)
		(end 177.22101 81.409327)
		(width 0.155)
		(layer "B.Cu")
		(net 91)
	)
	(segment
		(start 140.983 88.3605)
		(end 141.2055 88.138)
		(width 0.155)
		(layer "B.Cu")
		(net 91)
	)
	(segment
		(start 177.256 82.713)
		(end 177.214949 82.713)
		(width 0.155)
		(layer "B.Cu")
		(net 91)
	)
	(segment
		(start 177.214949 83.013)
		(end 177.256 83.013)
		(width 0.155)
		(layer "B.Cu")
		(net 91)
	)
	(segment
		(start 177.406 85.613)
		(end 177.406 87.57201)
		(width 0.155)
		(layer "B.Cu")
		(net 91)
	)
	(segment
		(start 177.22101 81.409327)
		(end 177.406 81.594317)
		(width 0.155)
		(layer "B.Cu")
		(net 91)
	)
	(segment
		(start 177.214949 83.613)
		(end 177.256 83.613)
		(width 0.155)
		(layer "B.Cu")
		(net 91)
	)
	(segment
		(start 177.406 87.57201)
		(end 173.80501 91.173)
		(width 0.155)
		(layer "B.Cu")
		(net 91)
	)
	(segment
		(start 140.983 91.38201)
		(end 140.983 88.3605)
		(width 0.155)
		(layer "B.Cu")
		(net 91)
	)
	(segment
		(start 173.80501 91.173)
		(end 162.62901 91.173)
		(width 0.155)
		(layer "B.Cu")
		(net 91)
	)
	(segment
		(start 159.96201 93.84)
		(end 143.44099 93.84)
		(width 0.155)
		(layer "B.Cu")
		(net 91)
	)
	(segment
		(start 162.62901 91.173)
		(end 159.96201 93.84)
		(width 0.155)
		(layer "B.Cu")
		(net 91)
	)
	(segment
		(start 177.256 83.313)
		(end 177.214949 83.313)
		(width 0.155)
		(layer "B.Cu")
		(net 91)
	)
	(segment
		(start 177.406 81.594317)
		(end 177.406 82.563)
		(width 0.155)
		(layer "B.Cu")
		(net 91)
	)
	(arc
		(start 177.064949 82.863)
		(mid 177.108883 82.969066)
		(end 177.214949 83.013)
		(width 0.155)
		(layer "B.Cu")
		(net 91)
	)
	(arc
		(start 177.406 83.163)
		(mid 177.362066 83.269066)
		(end 177.256 83.313)
		(width 0.155)
		(layer "B.Cu")
		(net 91)
	)
	(arc
		(start 177.064949 83.463)
		(mid 177.108883 83.569066)
		(end 177.214949 83.613)
		(width 0.155)
		(layer "B.Cu")
		(net 91)
	)
	(arc
		(start 177.214949 83.313)
		(mid 177.108883 83.356934)
		(end 177.064949 83.463)
		(width 0.155)
		(layer "B.Cu")
		(net 91)
	)
	(arc
		(start 177.256 83.013)
		(mid 177.362066 83.056934)
		(end 177.406 83.163)
		(width 0.155)
		(layer "B.Cu")
		(net 91)
	)
	(arc
		(start 177.256 83.613)
		(mid 177.362066 83.656934)
		(end 177.406 83.763)
		(width 0.155)
		(layer "B.Cu")
		(net 91)
	)
	(arc
		(start 177.406 82.563)
		(mid 177.362066 82.669066)
		(end 177.256 82.713)
		(width 0.155)
		(layer "B.Cu")
		(net 91)
	)
	(arc
		(start 177.214949 82.713)
		(mid 177.108883 82.756934)
		(end 177.064949 82.863)
		(width 0.155)
		(layer "B.Cu")
		(net 91)
	)
	(segment
		(start 140.703 87.9155)
		(end 140.703 84.450525)
		(width 0.155)
		(layer "F.Cu")
		(net 92)
	)
	(segment
		(start 142.183837 82.969688)
		(end 140.703 84.450525)
		(width 0.155)
		(layer "F.Cu")
		(net 92)
	)
	(segment
		(start 177.728663 81.521)
		(end 181.79499 81.521)
		(width 0.155)
		(layer "F.Cu")
		(net 92)
	)
	(segment
		(start 177.419 80.896673)
		(end 177.419 81.211337)
		(width 0.155)
		(layer "F.Cu")
		(net 92)
	)
	(segment
		(start 177.419 81.211337)
		(end 177.728663 81.521)
		(width 0.155)
		(layer "F.Cu")
		(net 92)
	)
	(segment
		(start 183.776 82.043)
		(end 183.886 81.933)
		(width 0.155)
		(layer "F.Cu")
		(net 92)
	)
	(segment
		(start 140.703 87.9155)
		(end 140.4805 88.138)
		(width 0.155)
		(layer "F.Cu")
		(net 92)
	)
	(segment
		(start 182.31699 82.043)
		(end 183.776 82.043)
		(width 0.155)
		(layer "F.Cu")
		(net 92)
	)
	(segment
		(start 142.183837 82.814124)
		(end 142.183837 82.969688)
		(width 0.155)
		(layer "F.Cu")
		(net 92)
	)
	(segment
		(start 181.79499 81.521)
		(end 182.31699 82.043)
		(width 0.155)
		(layer "F.Cu")
		(net 92)
	)
	(via
		(at 140.4805 88.138)
		(size 0.6)
		(drill 0.35)
		(layers "F.Cu" "B.Cu")
		(net 92)
	)
	(via
		(at 177.419 80.896673)
		(size 0.6)
		(drill 0.35)
		(layers "F.Cu" "B.Cu")
		(net 92)
	)
	(segment
		(start 162.74499 91.453)
		(end 173.92099 91.453)
		(width 0.155)
		(layer "B.Cu")
		(net 92)
	)
	(segment
		(start 177.686 81.478337)
		(end 177.686 87.68799)
		(width 0.155)
		(layer "B.Cu")
		(net 92)
	)
	(segment
		(start 143.32501 94.12)
		(end 160.07799 94.12)
		(width 0.155)
		(layer "B.Cu")
		(net 92)
	)
	(segment
		(start 160.07799 94.12)
		(end 162.74499 91.453)
		(width 0.155)
		(layer "B.Cu")
		(net 92)
	)
	(segment
		(start 173.92099 91.453)
		(end 177.686 87.68799)
		(width 0.155)
		(layer "B.Cu")
		(net 92)
	)
	(segment
		(start 177.419 81.211337)
		(end 177.419 80.896673)
		(width 0.155)
		(layer "B.Cu")
		(net 92)
	)
	(segment
		(start 140.703 91.49799)
		(end 143.32501 94.12)
		(width 0.155)
		(layer "B.Cu")
		(net 92)
	)
	(segment
		(start 140.4805 88.138)
		(end 140.703 88.3605)
		(width 0.155)
		(layer "B.Cu")
		(net 92)
	)
	(segment
		(start 140.703 88.3605)
		(end 140.703 91.49799)
		(width 0.155)
		(layer "B.Cu")
		(net 92)
	)
	(segment
		(start 177.686 81.478337)
		(end 177.419 81.211337)
		(width 0.155)
		(layer "B.Cu")
		(net 92)
	)
	(segment
		(start 162.62901 80.124)
		(end 161.381505 81.371505)
		(width 0.155)
		(layer "F.Cu")
		(net 93)
	)
	(segment
		(start 160.87512 82.78845)
		(end 160.617831 82.531161)
		(width 0.155)
		(layer "F.Cu")
		(net 93)
	)
	(segment
		(start 161.15523 81.371505)
		(end 161.011077 81.227352)
		(width 0.155)
		(layer "F.Cu")
		(net 93)
	)
	(segment
		(start 166.56601 80.124)
		(end 166.002 80.124)
		(width 0.155)
		(layer "F.Cu")
		(net 93)
	)
	(segment
		(start 161.155229 81.371505)
		(end 161.15523 81.371505)
		(width 0.155)
		(layer "F.Cu")
		(net 93)
	)
	(segment
		(start 159.260186 83.492826)
		(end 156.637809 86.115201)
		(width 0.155)
		(layer "F.Cu")
		(net 93)
	)
	(segment
		(start 168.165149 73.367139)
		(end 167.850485 73.367139)
		(width 0.155)
		(layer "F.Cu")
		(net 93)
	)
	(segment
		(start 160.617831 82.531161)
		(end 160.16255 82.07588)
		(width 0.155)
		(layer "F.Cu")
		(net 93)
	)
	(segment
		(start 160.026592 83.636978)
		(end 159.88244 83.492826)
		(width 0.155)
		(layer "F.Cu")
		(net 93)
	)
	(segment
		(start 165.022 79.969861)
		(end 165.022 79.984)
		(width 0.155)
		(layer "F.Cu")
		(net 93)
	)
	(segment
		(start 164.882 80.124)
		(end 162.62901 80.124)
		(width 0.155)
		(layer "F.Cu")
		(net 93)
	)
	(segment
		(start 159.540296 82.698132)
		(end 159.540296 82.698133)
		(width 0.155)
		(layer "F.Cu")
		(net 93)
	)
	(segment
		(start 183.886 74.433)
		(end 183.776 74.323)
		(width 0.155)
		(layer "F.Cu")
		(net 93)
	)
	(segment
		(start 160.388823 81.849604)
		(end 160.388823 81.849605)
		(width 0.155)
		(layer "F.Cu")
		(net 93)
	)
	(segment
		(start 165.302 79.984)
		(end 165.302 79.969861)
		(width 0.155)
		(layer "F.Cu")
		(net 93)
	)
	(segment
		(start 151.44199 85.458)
		(end 149.180663 85.458)
		(width 0.155)
		(layer "F.Cu")
		(net 93)
	)
	(segment
		(start 156.637809 86.115201)
		(end 155.77101 86.982)
		(width 0.155)
		(layer "F.Cu")
		(net 93)
	)
	(segment
		(start 167.111731 79.263615)
		(end 167.111731 79.578279)
		(width 0.155)
		(layer "F.Cu")
		(net 93)
	)
	(segment
		(start 159.540296 82.698133)
		(end 160.252866 83.410704)
		(width 0.155)
		(layer "F.Cu")
		(net 93)
	)
	(segment
		(start 152.96599 86.982)
		(end 151.44199 85.458)
		(width 0.155)
		(layer "F.Cu")
		(net 93)
	)
	(segment
		(start 160.388823 81.849605)
		(end 161.101394 82.562176)
		(width 0.155)
		(layer "F.Cu")
		(net 93)
	)
	(segment
		(start 183.776 74.323)
		(end 169.12101 74.323)
		(width 0.155)
		(layer "F.Cu")
		(net 93)
	)
	(segment
		(start 167.111731 79.578279)
		(end 166.56601 80.124)
		(width 0.155)
		(layer "F.Cu")
		(net 93)
	)
	(segment
		(start 165.582 79.969861)
		(end 165.582 79.984)
		(width 0.155)
		(layer "F.Cu")
		(net 93)
	)
	(segment
		(start 148.812964 85.090301)
		(end 148.812964 84.934737)
		(width 0.155)
		(layer "F.Cu")
		(net 93)
	)
	(segment
		(start 155.77101 86.982)
		(end 152.96599 86.982)
		(width 0.155)
		(layer "F.Cu")
		(net 93)
	)
	(segment
		(start 169.12101 74.323)
		(end 168.165149 73.367139)
		(width 0.155)
		(layer "F.Cu")
		(net 93)
	)
	(segment
		(start 149.180663 85.458)
		(end 148.812964 85.090301)
		(width 0.155)
		(layer "F.Cu")
		(net 93)
	)
	(segment
		(start 165.862 79.984)
		(end 165.862 79.969861)
		(width 0.155)
		(layer "F.Cu")
		(net 93)
	)
	(via
		(at 167.850485 73.367139)
		(size 0.6)
		(drill 0.35)
		(layers "F.Cu" "B.Cu")
		(net 93)
	)
	(via
		(at 167.111731 79.263615)
		(size 0.6)
		(drill 0.35)
		(layers "F.Cu" "B.Cu")
		(net 93)
	)
	(arc
		(start 161.101394 82.562176)
		(mid 161.148257 82.675313)
		(end 161.101394 82.78845)
		(width 0.155)
		(layer "F.Cu")
		(net 93)
	)
	(arc
		(start 165.302 79.969861)
		(mid 165.260995 79.870866)
		(end 165.162 79.829861)
		(width 0.155)
		(layer "F.Cu")
		(net 93)
	)
	(arc
		(start 161.101394 82.78845)
		(mid 160.988257 82.835313)
		(end 160.87512 82.78845)
		(width 0.155)
		(layer "F.Cu")
		(net 93)
	)
	(arc
		(start 165.162 79.829861)
		(mid 165.063005 79.870866)
		(end 165.022 79.969861)
		(width 0.155)
		(layer "F.Cu")
		(net 93)
	)
	(arc
		(start 161.381505 81.371505)
		(mid 161.268367 81.418368)
		(end 161.155229 81.371505)
		(width 0.155)
		(layer "F.Cu")
		(net 93)
	)
	(arc
		(start 160.252866 83.636978)
		(mid 160.139729 83.683841)
		(end 160.026592 83.636978)
		(width 0.155)
		(layer "F.Cu")
		(net 93)
	)
	(arc
		(start 165.442 80.124)
		(mid 165.343005 80.082995)
		(end 165.302 79.984)
		(width 0.155)
		(layer "F.Cu")
		(net 93)
	)
	(arc
		(start 160.252866 83.410704)
		(mid 160.299729 83.523841)
		(end 160.252866 83.636978)
		(width 0.155)
		(layer "F.Cu")
		(net 93)
	)
	(arc
		(start 161.011077 81.227352)
		(mid 160.69995 81.098479)
		(end 160.388823 81.227352)
		(width 0.155)
		(layer "F.Cu")
		(net 93)
	)
	(arc
		(start 159.88244 83.492826)
		(mid 159.571313 83.363953)
		(end 159.260186 83.492826)
		(width 0.155)
		(layer "F.Cu")
		(net 93)
	)
	(arc
		(start 160.16255 82.07588)
		(mid 159.851423 81.947007)
		(end 159.540296 82.07588)
		(width 0.155)
		(layer "F.Cu")
		(net 93)
	)
	(arc
		(start 160.388823 81.227352)
		(mid 160.25995 81.538478)
		(end 160.388823 81.849604)
		(width 0.155)
		(layer "F.Cu")
		(net 93)
	)
	(arc
		(start 166.002 80.124)
		(mid 165.903005 80.082995)
		(end 165.862 79.984)
		(width 0.155)
		(layer "F.Cu")
		(net 93)
	)
	(arc
		(start 159.540296 82.07588)
		(mid 159.411423 82.387006)
		(end 159.540296 82.698132)
		(width 0.155)
		(layer "F.Cu")
		(net 93)
	)
	(arc
		(start 165.862 79.969861)
		(mid 165.820995 79.870866)
		(end 165.722 79.829861)
		(width 0.155)
		(layer "F.Cu")
		(net 93)
	)
	(arc
		(start 165.022 79.984)
		(mid 164.980995 80.082995)
		(end 164.882 80.124)
		(width 0.155)
		(layer "F.Cu")
		(net 93)
	)
	(arc
		(start 165.582 79.984)
		(mid 165.540995 80.082995)
		(end 165.442 80.124)
		(width 0.155)
		(layer "F.Cu")
		(net 93)
	)
	(arc
		(start 165.722 79.829861)
		(mid 165.623005 79.870866)
		(end 165.582 79.969861)
		(width 0.155)
		(layer "F.Cu")
		(net 93)
	)
	(segment
		(start 168.643 73.84499)
		(end 168.643 78.04701)
		(width 0.155)
		(layer "B.Cu")
		(net 93)
	)
	(segment
		(start 167.426395 79.263615)
		(end 167.111731 79.263615)
		(width 0.155)
		(layer "B.Cu")
		(net 93)
	)
	(segment
		(start 168.643 78.04701)
		(end 167.426395 79.263615)
		(width 0.155)
		(layer "B.Cu")
		(net 93)
	)
	(segment
		(start 168.165149 73.367139)
		(end 168.643 73.84499)
		(width 0.155)
		(layer "B.Cu")
		(net 93)
	)
	(segment
		(start 167.850485 73.367139)
		(end 168.165149 73.367139)
		(width 0.155)
		(layer "B.Cu")
		(net 93)
	)
	(segment
		(start 159.458176 83.690817)
		(end 156.835799 86.313191)
		(width 0.155)
		(layer "F.Cu")
		(net 94)
	)
	(segment
		(start 148.614974 85.288291)
		(end 148.45941 85.288291)
		(width 0.155)
		(layer "F.Cu")
		(net 94)
	)
	(segment
		(start 160.677132 82.98644)
		(end 160.67713 82.986441)
		(width 0.155)
		(layer "F.Cu")
		(net 94)
	)
	(segment
		(start 155.88699 87.262)
		(end 152.85001 87.262)
		(width 0.155)
		(layer "F.Cu")
		(net 94)
	)
	(segment
		(start 160.586813 81.651615)
		(end 160.730965 81.795767)
		(width 0.155)
		(layer "F.Cu")
		(net 94)
	)
	(segment
		(start 159.995575 82.757433)
		(end 160.450856 83.212714)
		(width 0.155)
		(layer "F.Cu")
		(net 94)
	)
	(segment
		(start 160.730965 81.795767)
		(end 161.299384 82.364186)
		(width 0.155)
		(layer "F.Cu")
		(net 94)
	)
	(segment
		(start 166.68199 80.404)
		(end 162.74499 80.404)
		(width 0.155)
		(layer "F.Cu")
		(net 94)
	)
	(segment
		(start 156.835799 86.313191)
		(end 155.88699 87.262)
		(width 0.155)
		(layer "F.Cu")
		(net 94)
	)
	(segment
		(start 167.624385 79.776269)
		(end 167.309721 79.776269)
		(width 0.155)
		(layer "F.Cu")
		(net 94)
	)
	(segment
		(start 151.32601 85.738)
		(end 149.064683 85.738)
		(width 0.155)
		(layer "F.Cu")
		(net 94)
	)
	(segment
		(start 183.776 74.043)
		(end 183.886 73.933)
		(width 0.155)
		(layer "F.Cu")
		(net 94)
	)
	(segment
		(start 169.23699 74.043)
		(end 183.776 74.043)
		(width 0.155)
		(layer "F.Cu")
		(net 94)
	)
	(segment
		(start 168.363139 73.169149)
		(end 169.23699 74.043)
		(width 0.155)
		(layer "F.Cu")
		(net 94)
	)
	(segment
		(start 159.828604 83.834968)
		(end 159.828602 83.834969)
		(width 0.155)
		(layer "F.Cu")
		(net 94)
	)
	(segment
		(start 149.064683 85.738)
		(end 148.614974 85.288291)
		(width 0.155)
		(layer "F.Cu")
		(net 94)
	)
	(segment
		(start 168.363139 72.854485)
		(end 168.363139 73.169149)
		(width 0.155)
		(layer "F.Cu")
		(net 94)
	)
	(segment
		(start 167.309721 79.776269)
		(end 166.68199 80.404)
		(width 0.155)
		(layer "F.Cu")
		(net 94)
	)
	(segment
		(start 152.85001 87.262)
		(end 151.32601 85.738)
		(width 0.155)
		(layer "F.Cu")
		(net 94)
	)
	(segment
		(start 160.67713 82.986441)
		(end 159.96456 82.27387)
		(width 0.155)
		(layer "F.Cu")
		(net 94)
	)
	(segment
		(start 160.95724 81.569494)
		(end 160.813087 81.425341)
		(width 0.155)
		(layer "F.Cu")
		(net 94)
	)
	(segment
		(start 159.828602 83.834969)
		(end 159.68445 83.690817)
		(width 0.155)
		(layer "F.Cu")
		(net 94)
	)
	(segment
		(start 162.74499 80.404)
		(end 161.579494 81.569494)
		(width 0.155)
		(layer "F.Cu")
		(net 94)
	)
	(segment
		(start 159.738286 82.500144)
		(end 159.995575 82.757433)
		(width 0.155)
		(layer "F.Cu")
		(net 94)
	)
	(via
		(at 167.624385 79.776269)
		(size 0.6)
		(drill 0.35)
		(layers "F.Cu" "B.Cu")
		(net 94)
	)
	(via
		(at 168.363139 72.854485)
		(size 0.6)
		(drill 0.35)
		(layers "F.Cu" "B.Cu")
		(net 94)
	)
	(arc
		(start 160.450856 83.834968)
		(mid 160.139729 83.963842)
		(end 159.828604 83.834968)
		(width 0.155)
		(layer "F.Cu")
		(net 94)
	)
	(arc
		(start 159.738286 82.27387)
		(mid 159.691423 82.387007)
		(end 159.738286 82.500144)
		(width 0.155)
		(layer "F.Cu")
		(net 94)
	)
	(arc
		(start 160.450856 83.212714)
		(mid 160.579729 83.523841)
		(end 160.450856 83.834968)
		(width 0.155)
		(layer "F.Cu")
		(net 94)
	)
	(arc
		(start 161.299384 82.98644)
		(mid 160.988257 83.115314)
		(end 160.677132 82.98644)
		(width 0.155)
		(layer "F.Cu")
		(net 94)
	)
	(arc
		(start 160.586813 81.425341)
		(mid 160.53995 81.538478)
		(end 160.586813 81.651615)
		(width 0.155)
		(layer "F.Cu")
		(net 94)
	)
	(arc
		(start 161.299384 82.364186)
		(mid 161.428257 82.675313)
		(end 161.299384 82.98644)
		(width 0.155)
		(layer "F.Cu")
		(net 94)
	)
	(arc
		(start 159.68445 83.690817)
		(mid 159.571313 83.643954)
		(end 159.458176 83.690817)
		(width 0.155)
		(layer "F.Cu")
		(net 94)
	)
	(arc
		(start 161.579494 81.569494)
		(mid 161.268367 81.698367)
		(end 160.95724 81.569494)
		(width 0.155)
		(layer "F.Cu")
		(net 94)
	)
	(arc
		(start 159.96456 82.27387)
		(mid 159.851423 82.227007)
		(end 159.738286 82.27387)
		(width 0.155)
		(layer "F.Cu")
		(net 94)
	)
	(arc
		(start 160.813087 81.425341)
		(mid 160.69995 81.378478)
		(end 160.586813 81.425341)
		(width 0.155)
		(layer "F.Cu")
		(net 94)
	)
	(segment
		(start 168.923 78.16299)
		(end 168.923 73.72901)
		(width 0.155)
		(layer "B.Cu")
		(net 94)
	)
	(segment
		(start 167.624385 79.461605)
		(end 167.624385 79.776269)
		(width 0.155)
		(layer "B.Cu")
		(net 94)
	)
	(segment
		(start 168.363139 73.169149)
		(end 168.923 73.72901)
		(width 0.155)
		(layer "B.Cu")
		(net 94)
	)
	(segment
		(start 168.923 78.16299)
		(end 167.624385 79.461605)
		(width 0.155)
		(layer "B.Cu")
		(net 94)
	)
	(segment
		(start 168.363139 72.854485)
		(end 168.363139 73.169149)
		(width 0.155)
		(layer "B.Cu")
		(net 94)
	)
	(segment
		(start 169.90283 80.978178)
		(end 168.21701 82.664)
		(width 0.155)
		(layer "F.Cu")
		(net 95)
	)
	(segment
		(start 182.72701 73.324)
		(end 183.777 73.324)
		(width 0.155)
		(layer "F.Cu")
		(net 95)
	)
	(segment
		(start 170.539227 80.165005)
		(end 170.539228 80.165005)
		(width 0.155)
		(layer "F.Cu")
		(net 95)
	)
	(segment
		(start 170.327094 80.553914)
		(end 170.327095 80.553913)
		(width 0.155)
		(layer "F.Cu")
		(net 95)
	)
	(segment
		(start 170.362451 80.165004)
		(end 170.362451 80.165005)
		(width 0.155)
		(layer "F.Cu")
		(net 95)
	)
	(segment
		(start 149.53699 89.395)
		(end 148.857 88.71501)
		(width 0.155)
		(layer "F.Cu")
		(net 95)
	)
	(segment
		(start 170.327096 80.377137)
		(end 170.327095 80.377137)
		(width 0.155)
		(layer "F.Cu")
		(net 95)
	)
	(segment
		(start 182.18701 72.784)
		(end 182.72701 73.324)
		(width 0.155)
		(layer "F.Cu")
		(net 95)
	)
	(segment
		(start 148.857 88.71501)
		(end 148.857 87.962764)
		(width 0.155)
		(layer "F.Cu")
		(net 95)
	)
	(segment
		(start 183.777 73.324)
		(end 183.886 73.433)
		(width 0.155)
		(layer "F.Cu")
		(net 95)
	)
	(segment
		(start 170.802 79.0895)
		(end 170.802 80.07901)
		(width 0.155)
		(layer "F.Cu")
		(net 95)
	)
	(segment
		(start 168.21701 82.664)
		(end 164.40701 82.664)
		(width 0.155)
		(layer "F.Cu")
		(net 95)
	)
	(segment
		(start 157.67601 89.395)
		(end 149.53699 89.395)
		(width 0.155)
		(layer "F.Cu")
		(net 95)
	)
	(segment
		(start 170.802 80.07901)
		(end 170.716005 80.165005)
		(width 0.155)
		(layer "F.Cu")
		(net 95)
	)
	(segment
		(start 170.900529 72.784)
		(end 182.18701 72.784)
		(width 0.155)
		(layer "F.Cu")
		(net 95)
	)
	(segment
		(start 170.175129 72.373264)
		(end 170.489793 72.373264)
		(width 0.155)
		(layer "F.Cu")
		(net 95)
	)
	(segment
		(start 169.902831 80.801402)
		(end 169.90283 80.801402)
		(width 0.155)
		(layer "F.Cu")
		(net 95)
	)
	(segment
		(start 170.114962 80.58927)
		(end 170.114963 80.58927)
		(width 0.155)
		(layer "F.Cu")
		(net 95)
	)
	(segment
		(start 170.5795 78.867)
		(end 170.802 79.0895)
		(width 0.155)
		(layer "F.Cu")
		(net 95)
	)
	(segment
		(start 164.40701 82.664)
		(end 157.67601 89.395)
		(width 0.155)
		(layer "F.Cu")
		(net 95)
	)
	(segment
		(start 148.857 87.962764)
		(end 147.39875 86.504514)
		(width 0.155)
		(layer "F.Cu")
		(net 95)
	)
	(segment
		(start 169.902829 80.978179)
		(end 169.90283 80.978178)
		(width 0.155)
		(layer "F.Cu")
		(net 95)
	)
	(segment
		(start 147.39875 86.504514)
		(end 147.39875 86.348951)
		(width 0.155)
		(layer "F.Cu")
		(net 95)
	)
	(segment
		(start 170.327095 80.553913)
		(end 170.29174 80.58927)
		(width 0.155)
		(layer "F.Cu")
		(net 95)
	)
	(segment
		(start 169.938186 80.589269)
		(end 169.938186 80.58927)
		(width 0.155)
		(layer "F.Cu")
		(net 95)
	)
	(segment
		(start 169.938186 80.58927)
		(end 169.90283 80.624625)
		(width 0.155)
		(layer "F.Cu")
		(net 95)
	)
	(segment
		(start 170.489793 72.373264)
		(end 170.900529 72.784)
		(width 0.155)
		(layer "F.Cu")
		(net 95)
	)
	(segment
		(start 170.362451 80.165005)
		(end 170.327095 80.20036)
		(width 0.155)
		(layer "F.Cu")
		(net 95)
	)
	(via
		(at 170.5795 78.867)
		(size 0.6)
		(drill 0.35)
		(layers "F.Cu" "B.Cu")
		(net 95)
	)
	(via
		(at 170.175129 72.373264)
		(size 0.6)
		(drill 0.35)
		(layers "F.Cu" "B.Cu")
		(net 95)
	)
	(arc
		(start 170.327095 80.20036)
		(mid 170.290484 80.288749)
		(end 170.327096 80.377137)
		(width 0.155)
		(layer "F.Cu")
		(net 95)
	)
	(arc
		(start 170.327095 80.377137)
		(mid 170.363706 80.465526)
		(end 170.327094 80.553914)
		(width 0.155)
		(layer "F.Cu")
		(net 95)
	)
	(arc
		(start 169.90283 80.624625)
		(mid 169.866219 80.713014)
		(end 169.902831 80.801402)
		(width 0.155)
		(layer "F.Cu")
		(net 95)
	)
	(arc
		(start 169.90283 80.801402)
		(mid 169.939441 80.889791)
		(end 169.902829 80.978179)
		(width 0.155)
		(layer "F.Cu")
		(net 95)
	)
	(arc
		(start 170.539228 80.165005)
		(mid 170.45084 80.128393)
		(end 170.362451 80.165004)
		(width 0.155)
		(layer "F.Cu")
		(net 95)
	)
	(arc
		(start 170.29174 80.58927)
		(mid 170.203351 80.625882)
		(end 170.114962 80.58927)
		(width 0.155)
		(layer "F.Cu")
		(net 95)
	)
	(arc
		(start 170.716005 80.165005)
		(mid 170.627616 80.201617)
		(end 170.539227 80.165005)
		(width 0.155)
		(layer "F.Cu")
		(net 95)
	)
	(arc
		(start 170.114963 80.58927)
		(mid 170.026575 80.552658)
		(end 169.938186 80.589269)
		(width 0.155)
		(layer "F.Cu")
		(net 95)
	)
	(segment
		(start 170.802 78.6445)
		(end 170.5795 78.867)
		(width 0.155)
		(layer "B.Cu")
		(net 95)
	)
	(segment
		(start 170.175129 72.373264)
		(end 170.489793 72.373264)
		(width 0.155)
		(layer "B.Cu")
		(net 95)
	)
	(segment
		(start 170.802 72.685471)
		(end 170.802 78.6445)
		(width 0.155)
		(layer "B.Cu")
		(net 95)
	)
	(segment
		(start 170.489793 72.373264)
		(end 170.802 72.685471)
		(width 0.155)
		(layer "B.Cu")
		(net 95)
	)
	(segment
		(start 171.016509 72.504)
		(end 182.30299 72.504)
		(width 0.155)
		(layer "F.Cu")
		(net 96)
	)
	(segment
		(start 171.082 80.19499)
		(end 171.082 79.0895)
		(width 0.155)
		(layer "F.Cu")
		(net 96)
	)
	(segment
		(start 148.577 88.078744)
		(end 148.577 88.83099)
		(width 0.155)
		(layer "F.Cu")
		(net 96)
	)
	(segment
		(start 183.777 73.044)
		(end 183.886 72.935)
		(width 0.155)
		(layer "F.Cu")
		(net 96)
	)
	(segment
		(start 168.33299 82.944)
		(end 171.082 80.19499)
		(width 0.155)
		(layer "F.Cu")
		(net 96)
	)
	(segment
		(start 170.687783 72.175274)
		(end 171.016509 72.504)
		(width 0.155)
		(layer "F.Cu")
		(net 96)
	)
	(segment
		(start 147.20076 86.702504)
		(end 148.577 88.078744)
		(width 0.155)
		(layer "F.Cu")
		(net 96)
	)
	(segment
		(start 171.082 79.0895)
		(end 171.3045 78.867)
		(width 0.155)
		(layer "F.Cu")
		(net 96)
	)
	(segment
		(start 182.84299 73.044)
		(end 183.777 73.044)
		(width 0.155)
		(layer "F.Cu")
		(net 96)
	)
	(segment
		(start 170.687783 71.86061)
		(end 170.687783 72.175274)
		(width 0.155)
		(layer "F.Cu")
		(net 96)
	)
	(segment
		(start 147.045197 86.702504)
		(end 147.20076 86.702504)
		(width 0.155)
		(layer "F.Cu")
		(net 96)
	)
	(segment
		(start 164.52299 82.944)
		(end 168.33299 82.944)
		(width 0.155)
		(layer "F.Cu")
		(net 96)
	)
	(segment
		(start 157.79199 89.675)
		(end 149.42101 89.675)
		(width 0.155)
		(layer "F.Cu")
		(net 96)
	)
	(segment
		(start 182.30299 72.504)
		(end 182.84299 73.044)
		(width 0.155)
		(layer "F.Cu")
		(net 96)
	)
	(segment
		(start 164.52299 82.944)
		(end 157.79199 89.675)
		(width 0.155)
		(layer "F.Cu")
		(net 96)
	)
	(segment
		(start 148.577 88.83099)
		(end 149.42101 89.675)
		(width 0.155)
		(layer "F.Cu")
		(net 96)
	)
	(via
		(at 171.3045 78.867)
		(size 0.6)
		(drill 0.35)
		(layers "F.Cu" "B.Cu")
		(net 96)
	)
	(via
		(at 170.687783 71.86061)
		(size 0.6)
		(drill 0.35)
		(layers "F.Cu" "B.Cu")
		(net 96)
	)
	(segment
		(start 170.687783 71.86061)
		(end 170.687783 72.175274)
		(width 0.155)
		(layer "B.Cu")
		(net 96)
	)
	(segment
		(start 171.082 72.569491)
		(end 171.082 78.6445)
		(width 0.155)
		(layer "B.Cu")
		(net 96)
	)
	(segment
		(start 170.687783 72.175274)
		(end 171.082 72.569491)
		(width 0.155)
		(layer "B.Cu")
		(net 96)
	)
	(segment
		(start 171.3045 78.867)
		(end 171.082 78.6445)
		(width 0.155)
		(layer "B.Cu")
		(net 96)
	)
	(segment
		(start 182.87801 71.824)
		(end 182.30101 71.247)
		(width 0.155)
		(layer "F.Cu")
		(net 97)
	)
	(segment
		(start 183.776 71.824)
		(end 182.87801 71.824)
		(width 0.155)
		(layer "F.Cu")
		(net 97)
	)
	(segment
		(start 173.315013 70.770003)
		(end 173.000349 70.770003)
		(width 0.155)
		(layer "F.Cu")
		(net 97)
	)
	(segment
		(start 151.13974 87.381086)
		(end 150.825076 87.381086)
		(width 0.155)
		(layer "F.Cu")
		(net 97)
	)
	(segment
		(start 148.105857 85.797408)
		(end 148.105857 85.641844)
		(width 0.155)
		(layer "F.Cu")
		(net 97)
	)
	(segment
		(start 150.825076 87.381086)
		(end 149.91799 86.474)
		(width 0.155)
		(layer "F.Cu")
		(net 97)
	)
	(segment
		(start 183.886 71.934)
		(end 183.776 71.824)
		(width 0.155)
		(layer "F.Cu")
		(net 97)
	)
	(segment
		(start 173.79201 71.247)
		(end 173.315013 70.770003)
		(width 0.155)
		(layer "F.Cu")
		(net 97)
	)
	(segment
		(start 149.91799 86.474)
		(end 148.782449 86.474)
		(width 0.155)
		(layer "F.Cu")
		(net 97)
	)
	(segment
		(start 148.782449 86.474)
		(end 148.105857 85.797408)
		(width 0.155)
		(layer "F.Cu")
		(net 97)
	)
	(segment
		(start 182.30101 71.247)
		(end 173.79201 71.247)
		(width 0.155)
		(layer "F.Cu")
		(net 97)
	)
	(via
		(at 151.13974 87.381086)
		(size 0.6)
		(drill 0.35)
		(layers "F.Cu" "B.Cu")
		(net 97)
	)
	(via
		(at 173.000349 70.770003)
		(size 0.6)
		(drill 0.35)
		(layers "F.Cu" "B.Cu")
		(net 97)
	)
	(segment
		(start 152.536 88.125)
		(end 152.566 88.125)
		(width 0.155)
		(layer "B.Cu")
		(net 97)
	)
	(segment
		(start 151.13974 87.381086)
		(end 151.13974 87.69575)
		(width 0.155)
		(layer "B.Cu")
		(net 97)
	)
	(segment
		(start 165.805 81.902)
		(end 171.26501 81.902)
		(width 0.155)
		(layer "B.Cu")
		(net 97)
	)
	(segment
		(start 163.01001 81.902)
		(end 164.605 81.902)
		(width 0.155)
		(layer "B.Cu")
		(net 97)
	)
	(segment
		(start 165.507269 81.739731)
		(end 165.507269 81.879731)
		(width 0.155)
		(layer "B.Cu")
		(net 97)
	)
	(segment
		(start 165.529538 81.902)
		(end 165.805 81.902)
		(width 0.155)
		(layer "B.Cu")
		(net 97)
	)
	(segment
		(start 173.596 71.05099)
		(end 173.315013 70.770003)
		(width 0.155)
		(layer "B.Cu")
		(net 97)
	)
	(segment
		(start 173.315013 70.770003)
		(end 173.000349 70.770003)
		(width 0.155)
		(layer "B.Cu")
		(net 97)
	)
	(segment
		(start 152.256 87.875)
		(end 152.286 87.875)
		(width 0.155)
		(layer "B.Cu")
		(net 97)
	)
	(segment
		(start 151.13974 87.69575)
		(end 151.56899 88.125)
		(width 0.155)
		(layer "B.Cu")
		(net 97)
	)
	(segment
		(start 152.816 87.875)
		(end 152.846 87.875)
		(width 0.155)
		(layer "B.Cu")
		(net 97)
	)
	(segment
		(start 156.78701 88.125)
		(end 163.01001 81.902)
		(width 0.155)
		(layer "B.Cu")
		(net 97)
	)
	(segment
		(start 164.627269 81.879731)
		(end 164.627269 81.739731)
		(width 0.155)
		(layer "B.Cu")
		(net 97)
	)
	(segment
		(start 153.096 88.125)
		(end 156.78701 88.125)
		(width 0.155)
		(layer "B.Cu")
		(net 97)
	)
	(segment
		(start 164.929538 81.437462)
		(end 165.205 81.437462)
		(width 0.155)
		(layer "B.Cu")
		(net 97)
	)
	(segment
		(start 171.26501 81.902)
		(end 173.596 79.57101)
		(width 0.155)
		(layer "B.Cu")
		(net 97)
	)
	(segment
		(start 173.596 79.57101)
		(end 173.596 71.05099)
		(width 0.155)
		(layer "B.Cu")
		(net 97)
	)
	(segment
		(start 151.56899 88.125)
		(end 152.006 88.125)
		(width 0.155)
		(layer "B.Cu")
		(net 97)
	)
	(arc
		(start 152.411 88)
		(mid 152.447612 88.088388)
		(end 152.536 88.125)
		(width 0.155)
		(layer "B.Cu")
		(net 97)
	)
	(arc
		(start 152.006 88.125)
		(mid 152.094388 88.088388)
		(end 152.131 88)
		(width 0.155)
		(layer "B.Cu")
		(net 97)
	)
	(arc
		(start 164.605 81.902)
		(mid 164.620747 81.895478)
		(end 164.627269 81.879731)
		(width 0.155)
		(layer "B.Cu")
		(net 97)
	)
	(arc
		(start 152.971 88)
		(mid 153.007612 88.088388)
		(end 153.096 88.125)
		(width 0.155)
		(layer "B.Cu")
		(net 97)
	)
	(arc
		(start 152.131 88)
		(mid 152.167612 87.911612)
		(end 152.256 87.875)
		(width 0.155)
		(layer "B.Cu")
		(net 97)
	)
	(arc
		(start 152.846 87.875)
		(mid 152.934388 87.911612)
		(end 152.971 88)
		(width 0.155)
		(layer "B.Cu")
		(net 97)
	)
	(arc
		(start 165.205 81.437462)
		(mid 165.418736 81.525995)
		(end 165.507269 81.739731)
		(width 0.155)
		(layer "B.Cu")
		(net 97)
	)
	(arc
		(start 152.286 87.875)
		(mid 152.374388 87.911612)
		(end 152.411 88)
		(width 0.155)
		(layer "B.Cu")
		(net 97)
	)
	(arc
		(start 152.691 88)
		(mid 152.727612 87.911612)
		(end 152.816 87.875)
		(width 0.155)
		(layer "B.Cu")
		(net 97)
	)
	(arc
		(start 165.507269 81.879731)
		(mid 165.513791 81.895478)
		(end 165.529538 81.902)
		(width 0.155)
		(layer "B.Cu")
		(net 97)
	)
	(arc
		(start 152.566 88.125)
		(mid 152.654388 88.088388)
		(end 152.691 88)
		(width 0.155)
		(layer "B.Cu")
		(net 97)
	)
	(arc
		(start 164.627269 81.739731)
		(mid 164.715802 81.525995)
		(end 164.929538 81.437462)
		(width 0.155)
		(layer "B.Cu")
		(net 97)
	)
	(segment
		(start 173.90799 70.967)
		(end 182.41699 70.967)
		(width 0.155)
		(layer "F.Cu")
		(net 98)
	)
	(segment
		(start 150.627086 87.89374)
		(end 150.627086 87.579076)
		(width 0.155)
		(layer "F.Cu")
		(net 98)
	)
	(segment
		(start 173.513003 70.572013)
		(end 173.90799 70.967)
		(width 0.155)
		(layer "F.Cu")
		(net 98)
	)
	(segment
		(start 150.627086 87.579076)
		(end 149.80201 86.754)
		(width 0.155)
		(layer "F.Cu")
		(net 98)
	)
	(segment
		(start 149.80201 86.754)
		(end 148.666469 86.754)
		(width 0.155)
		(layer "F.Cu")
		(net 98)
	)
	(segment
		(start 182.41699 70.967)
		(end 182.99399 71.544)
		(width 0.155)
		(layer "F.Cu")
		(net 98)
	)
	(segment
		(start 182.99399 71.544)
		(end 183.776 71.544)
		(width 0.155)
		(layer "F.Cu")
		(net 98)
	)
	(segment
		(start 183.776 71.544)
		(end 183.886 71.434)
		(width 0.155)
		(layer "F.Cu")
		(net 98)
	)
	(segment
		(start 148.666469 86.754)
		(end 147.907867 85.995398)
		(width 0.155)
		(layer "F.Cu")
		(net 98)
	)
	(segment
		(start 173.513003 70.257349)
		(end 173.513003 70.572013)
		(width 0.155)
		(layer "F.Cu")
		(net 98)
	)
	(segment
		(start 147.907867 85.995398)
		(end 147.752303 85.995398)
		(width 0.155)
		(layer "F.Cu")
		(net 98)
	)
	(via
		(at 150.627086 87.89374)
		(size 0.6)
		(drill 0.35)
		(layers "F.Cu" "B.Cu")
		(net 98)
	)
	(via
		(at 173.513003 70.257349)
		(size 0.6)
		(drill 0.35)
		(layers "F.Cu" "B.Cu")
		(net 98)
	)
	(segment
		(start 173.876 70.93501)
		(end 173.513003 70.572013)
		(width 0.155)
		(layer "B.Cu")
		(net 98)
	)
	(segment
		(start 173.876 79.68699)
		(end 173.876 70.93501)
		(width 0.155)
		(layer "B.Cu")
		(net 98)
	)
	(segment
		(start 165.529538 82.182)
		(end 165.805 82.182)
		(width 0.155)
		(layer "B.Cu")
		(net 98)
	)
	(segment
		(start 165.805 82.182)
		(end 171.38099 82.182)
		(width 0.155)
		(layer "B.Cu")
		(net 98)
	)
	(segment
		(start 171.38099 82.182)
		(end 173.876 79.68699)
		(width 0.155)
		(layer "B.Cu")
		(net 98)
	)
	(segment
		(start 173.513003 70.572013)
		(end 173.513003 70.257349)
		(width 0.155)
		(layer "B.Cu")
		(net 98)
	)
	(segment
		(start 150.627086 87.89374)
		(end 150.94175 87.89374)
		(width 0.155)
		(layer "B.Cu")
		(net 98)
	)
	(segment
		(start 151.45301 88.405)
		(end 156.90299 88.405)
		(width 0.155)
		(layer "B.Cu")
		(net 98)
	)
	(segment
		(start 163.12599 82.182)
		(end 164.605 82.182)
		(width 0.155)
		(layer "B.Cu")
		(net 98)
	)
	(segment
		(start 165.227269 81.739731)
		(end 165.227269 81.879731)
		(width 0.155)
		(layer "B.Cu")
		(net 98)
	)
	(segment
		(start 150.94175 87.89374)
		(end 151.45301 88.405)
		(width 0.155)
		(layer "B.Cu")
		(net 98)
	)
	(segment
		(start 156.90299 88.405)
		(end 163.12599 82.182)
		(width 0.155)
		(layer "B.Cu")
		(net 98)
	)
	(segment
		(start 164.907269 81.879731)
		(end 164.907269 81.739731)
		(width 0.155)
		(layer "B.Cu")
		(net 98)
	)
	(segment
		(start 164.929538 81.717462)
		(end 165.205 81.717462)
		(width 0.155)
		(layer "B.Cu")
		(net 98)
	)
	(arc
		(start 164.907269 81.739731)
		(mid 164.913791 81.723984)
		(end 164.929538 81.717462)
		(width 0.155)
		(layer "B.Cu")
		(net 98)
	)
	(arc
		(start 165.227269 81.879731)
		(mid 165.315802 82.093467)
		(end 165.529538 82.182)
		(width 0.155)
		(layer "B.Cu")
		(net 98)
	)
	(arc
		(start 165.205 81.717462)
		(mid 165.220747 81.723984)
		(end 165.227269 81.739731)
		(width 0.155)
		(layer "B.Cu")
		(net 98)
	)
	(arc
		(start 164.605 82.182)
		(mid 164.818736 82.093467)
		(end 164.907269 81.879731)
		(width 0.155)
		(layer "B.Cu")
		(net 98)
	)
	(segment
		(start 168.851 86.709)
		(end 168.851 87.789)
		(width 0.155)
		(layer "F.Cu")
		(net 99)
	)
	(segment
		(start 181.15999 87.389)
		(end 173.811 87.389)
		(width 0.155)
		(layer "F.Cu")
		(net 99)
	)
	(segment
		(start 146.817163 88.453173)
		(end 147.131827 88.453173)
		(width 0.155)
		(layer "F.Cu")
		(net 99)
	)
	(segment
		(start 167.651 86.709)
		(end 167.651 87.789)
		(width 0.155)
		(layer "F.Cu")
		(net 99)
	)
	(segment
		(start 172.771 87.789)
		(end 172.771 86.709)
		(width 0.155)
		(layer "F.Cu")
		(net 99)
	)
	(segment
		(start 164.745 87.762657)
		(end 164.745 88.066387)
		(width 0.155)
		(layer "F.Cu")
		(net 99)
	)
	(segment
		(start 171.571 87.789)
		(end 171.571 86.709)
		(width 0.155)
		(layer "F.Cu")
		(net 99)
	)
	(segment
		(start 183.22599 85.323)
		(end 181.15999 87.389)
		(width 0.155)
		(layer "F.Cu")
		(net 99)
	)
	(segment
		(start 183.886 85.433)
		(end 183.776 85.323)
		(width 0.155)
		(layer "F.Cu")
		(net 99)
	)
	(segment
		(start 169.171 87.789)
		(end 169.171 86.709)
		(width 0.155)
		(layer "F.Cu")
		(net 99)
	)
	(segment
		(start 172.451 86.709)
		(end 172.451 87.789)
		(width 0.155)
		(layer "F.Cu")
		(net 99)
	)
	(segment
		(start 164.745 88.066387)
		(end 164.9675 88.288887)
		(width 0.155)
		(layer "F.Cu")
		(net 99)
	)
	(segment
		(start 146.817163 88.453173)
		(end 145.604871 87.240881)
		(width 0.155)
		(layer "F.Cu")
		(net 99)
	)
	(segment
		(start 166.611 87.389)
		(end 165.118657 87.389)
		(width 0.155)
		(layer "F.Cu")
		(net 99)
	)
	(segment
		(start 145.604871 87.014287)
		(end 145.604871 87.240881)
		(width 0.155)
		(layer "F.Cu")
		(net 99)
	)
	(segment
		(start 173.651 87.549)
		(end 173.651 87.789)
		(width 0.155)
		(layer "F.Cu")
		(net 99)
	)
	(segment
		(start 145.916654 86.702504)
		(end 145.604871 87.014287)
		(width 0.155)
		(layer "F.Cu")
		(net 99)
	)
	(segment
		(start 146.072218 86.702504)
		(end 145.916654 86.702504)
		(width 0.155)
		(layer "F.Cu")
		(net 99)
	)
	(segment
		(start 170.371 87.789)
		(end 170.371 86.709)
		(width 0.155)
		(layer "F.Cu")
		(net 99)
	)
	(segment
		(start 167.971 87.789)
		(end 167.971 86.709)
		(width 0.155)
		(layer "F.Cu")
		(net 99)
	)
	(segment
		(start 170.051 86.709)
		(end 170.051 87.789)
		(width 0.155)
		(layer "F.Cu")
		(net 99)
	)
	(segment
		(start 165.118657 87.389)
		(end 164.745 87.762657)
		(width 0.155)
		(layer "F.Cu")
		(net 99)
	)
	(segment
		(start 171.251 86.709)
		(end 171.251 87.789)
		(width 0.155)
		(layer "F.Cu")
		(net 99)
	)
	(segment
		(start 183.776 85.323)
		(end 183.22599 85.323)
		(width 0.155)
		(layer "F.Cu")
		(net 99)
	)
	(segment
		(start 166.771 87.789)
		(end 166.771 87.549)
		(width 0.155)
		(layer "F.Cu")
		(net 99)
	)
	(via
		(at 147.131827 88.453173)
		(size 0.6)
		(drill 0.35)
		(layers "F.Cu" "B.Cu")
		(net 99)
	)
	(via
		(at 164.9675 88.288887)
		(size 0.6)
		(drill 0.35)
		(layers "F.Cu" "B.Cu")
		(net 99)
	)
	(arc
		(start 168.411 88.229)
		(mid 168.099873 88.100127)
		(end 167.971 87.789)
		(width 0.155)
		(layer "F.Cu")
		(net 99)
	)
	(arc
		(start 169.611 88.229)
		(mid 169.299873 88.100127)
		(end 169.171 87.789)
		(width 0.155)
		(layer "F.Cu")
		(net 99)
	)
	(arc
		(start 167.211 88.229)
		(mid 166.899873 88.100127)
		(end 166.771 87.789)
		(width 0.155)
		(layer "F.Cu")
		(net 99)
	)
	(arc
		(start 171.251 87.789)
		(mid 171.122127 88.100127)
		(end 170.811 88.229)
		(width 0.155)
		(layer "F.Cu")
		(net 99)
	)
	(arc
		(start 170.051 87.789)
		(mid 169.922127 88.100127)
		(end 169.611 88.229)
		(width 0.155)
		(layer "F.Cu")
		(net 99)
	)
	(arc
		(start 167.971 86.709)
		(mid 167.924137 86.595863)
		(end 167.811 86.549)
		(width 0.155)
		(layer "F.Cu")
		(net 99)
	)
	(arc
		(start 172.611 86.549)
		(mid 172.497863 86.595863)
		(end 172.451 86.709)
		(width 0.155)
		(layer "F.Cu")
		(net 99)
	)
	(arc
		(start 173.211 88.229)
		(mid 172.899873 88.100127)
		(end 172.771 87.789)
		(width 0.155)
		(layer "F.Cu")
		(net 99)
	)
	(arc
		(start 172.011 88.229)
		(mid 171.699873 88.100127)
		(end 171.571 87.789)
		(width 0.155)
		(layer "F.Cu")
		(net 99)
	)
	(arc
		(start 166.771 87.549)
		(mid 166.724137 87.435863)
		(end 166.611 87.389)
		(width 0.155)
		(layer "F.Cu")
		(net 99)
	)
	(arc
		(start 167.651 87.789)
		(mid 167.522127 88.100127)
		(end 167.211 88.229)
		(width 0.155)
		(layer "F.Cu")
		(net 99)
	)
	(arc
		(start 171.571 86.709)
		(mid 171.524137 86.595863)
		(end 171.411 86.549)
		(width 0.155)
		(layer "F.Cu")
		(net 99)
	)
	(arc
		(start 172.771 86.709)
		(mid 172.724137 86.595863)
		(end 172.611 86.549)
		(width 0.155)
		(layer "F.Cu")
		(net 99)
	)
	(arc
		(start 168.851 87.789)
		(mid 168.722127 88.100127)
		(end 168.411 88.229)
		(width 0.155)
		(layer "F.Cu")
		(net 99)
	)
	(arc
		(start 167.811 86.549)
		(mid 167.697863 86.595863)
		(end 167.651 86.709)
		(width 0.155)
		(layer "F.Cu")
		(net 99)
	)
	(arc
		(start 173.651 87.789)
		(mid 173.522127 88.100127)
		(end 173.211 88.229)
		(width 0.155)
		(layer "F.Cu")
		(net 99)
	)
	(arc
		(start 169.171 86.709)
		(mid 169.124137 86.595863)
		(end 169.011 86.549)
		(width 0.155)
		(layer "F.Cu")
		(net 99)
	)
	(arc
		(start 169.011 86.549)
		(mid 168.897863 86.595863)
		(end 168.851 86.709)
		(width 0.155)
		(layer "F.Cu")
		(net 99)
	)
	(arc
		(start 173.811 87.389)
		(mid 173.697863 87.435863)
		(end 173.651 87.549)
		(width 0.155)
		(layer "F.Cu")
		(net 99)
	)
	(arc
		(start 172.451 87.789)
		(mid 172.322127 88.100127)
		(end 172.011 88.229)
		(width 0.155)
		(layer "F.Cu")
		(net 99)
	)
	(arc
		(start 170.371 86.709)
		(mid 170.324137 86.595863)
		(end 170.211 86.549)
		(width 0.155)
		(layer "F.Cu")
		(net 99)
	)
	(arc
		(start 170.211 86.549)
		(mid 170.097863 86.595863)
		(end 170.051 86.709)
		(width 0.155)
		(layer "F.Cu")
		(net 99)
	)
	(arc
		(start 170.811 88.229)
		(mid 170.499873 88.100127)
		(end 170.371 87.789)
		(width 0.155)
		(layer "F.Cu")
		(net 99)
	)
	(arc
		(start 171.411 86.549)
		(mid 171.297863 86.595863)
		(end 171.251 86.709)
		(width 0.155)
		(layer "F.Cu")
		(net 99)
	)
	(segment
		(start 149.754 89.753)
		(end 149.754 89.750319)
		(width 0.155)
		(layer "B.Cu")
		(net 99)
	)
	(segment
		(start 149.154 89.753)
		(end 149.154 89.750319)
		(width 0.155)
		(layer "B.Cu")
		(net 99)
	)
	(segment
		(start 158.720344 89.747666)
		(end 158.56501 89.903)
		(width 0.155)
		(layer "B.Cu")
		(net 99)
	)
	(segment
		(start 160.456729 87.785005)
		(end 160.45673 87.785005)
		(width 0.155)
		(layer "B.Cu")
		(net 99)
	)
	(segment
		(start 160.45673 87.785005)
		(end 160.295942 87.624217)
		(width 0.155)
		(layer "B.Cu")
		(net 99)
	)
	(segment
		(start 164.745 88.066387)
		(end 164.745 87.624343)
		(width 0.155)
		(layer "B.Cu")
		(net 99)
	)
	(segment
		(start 158.825161 89.094997)
		(end 158.825161 89.094998)
		(width 0.155)
		(layer "B.Cu")
		(net 99)
	)
	(segment
		(start 159.673688 88.24647)
		(end 160.419529 88.992311)
		(width 0.155)
		(layer "B.Cu")
		(net 99)
	)
	(segment
		(start 158.56501 89.903)
		(end 149.904 89.903)
		(width 0.155)
		(layer "B.Cu")
		(net 99)
	)
	(segment
		(start 158.825161 89.094998)
		(end 158.985948 89.255785)
		(width 0.155)
		(layer "B.Cu")
		(net 99)
	)
	(segment
		(start 148.854 89.750319)
		(end 148.854 89.753)
		(width 0.155)
		(layer "B.Cu")
		(net 99)
	)
	(segment
		(start 148.26699 89.903)
		(end 147.131827 88.767837)
		(width 0.155)
		(layer "B.Cu")
		(net 99)
	)
	(segment
		(start 158.985948 89.482059)
		(end 158.720344 89.747666)
		(width 0.155)
		(layer "B.Cu")
		(net 99)
	)
	(segment
		(start 161.35901 87.109)
		(end 160.683005 87.785005)
		(width 0.155)
		(layer "B.Cu")
		(net 99)
	)
	(segment
		(start 159.673688 88.246469)
		(end 159.673688 88.24647)
		(width 0.155)
		(layer "B.Cu")
		(net 99)
	)
	(segment
		(start 149.454 89.750319)
		(end 149.454 89.753)
		(width 0.155)
		(layer "B.Cu")
		(net 99)
	)
	(segment
		(start 160.193255 89.218585)
		(end 159.919331 88.944661)
		(width 0.155)
		(layer "B.Cu")
		(net 99)
	)
	(segment
		(start 159.919331 88.944661)
		(end 159.447415 88.472745)
		(width 0.155)
		(layer "B.Cu")
		(net 99)
	)
	(segment
		(start 164.745 87.624343)
		(end 164.229657 87.109)
		(width 0.155)
		(layer "B.Cu")
		(net 99)
	)
	(segment
		(start 148.704 89.903)
		(end 148.26699 89.903)
		(width 0.155)
		(layer "B.Cu")
		(net 99)
	)
	(segment
		(start 147.131827 88.767837)
		(end 147.131827 88.453173)
		(width 0.155)
		(layer "B.Cu")
		(net 99)
	)
	(segment
		(start 164.9675 88.288887)
		(end 164.745 88.066387)
		(width 0.155)
		(layer "B.Cu")
		(net 99)
	)
	(segment
		(start 164.229657 87.109)
		(end 161.35901 87.109)
		(width 0.155)
		(layer "B.Cu")
		(net 99)
	)
	(arc
		(start 159.447415 88.472745)
		(mid 159.136288 88.343872)
		(end 158.825161 88.472745)
		(width 0.155)
		(layer "B.Cu")
		(net 99)
	)
	(arc
		(start 149.304 89.903)
		(mid 149.197934 89.859066)
		(end 149.154 89.753)
		(width 0.155)
		(layer "B.Cu")
		(net 99)
	)
	(arc
		(start 160.683005 87.785005)
		(mid 160.569867 87.831868)
		(end 160.456729 87.785005)
		(width 0.155)
		(layer "B.Cu")
		(net 99)
	)
	(arc
		(start 158.825161 88.472745)
		(mid 158.696288 88.783871)
		(end 158.825161 89.094997)
		(width 0.155)
		(layer "B.Cu")
		(net 99)
	)
	(arc
		(start 149.754 89.750319)
		(mid 149.710066 89.644253)
		(end 149.604 89.600319)
		(width 0.155)
		(layer "B.Cu")
		(net 99)
	)
	(arc
		(start 159.673688 87.624217)
		(mid 159.544815 87.935343)
		(end 159.673688 88.246469)
		(width 0.155)
		(layer "B.Cu")
		(net 99)
	)
	(arc
		(start 149.904 89.903)
		(mid 149.797934 89.859066)
		(end 149.754 89.753)
		(width 0.155)
		(layer "B.Cu")
		(net 99)
	)
	(arc
		(start 160.419529 89.218585)
		(mid 160.306392 89.265448)
		(end 160.193255 89.218585)
		(width 0.155)
		(layer "B.Cu")
		(net 99)
	)
	(arc
		(start 149.004 89.600319)
		(mid 148.897934 89.644253)
		(end 148.854 89.750319)
		(width 0.155)
		(layer "B.Cu")
		(net 99)
	)
	(arc
		(start 148.854 89.753)
		(mid 148.810066 89.859066)
		(end 148.704 89.903)
		(width 0.155)
		(layer "B.Cu")
		(net 99)
	)
	(arc
		(start 149.154 89.750319)
		(mid 149.110066 89.644253)
		(end 149.004 89.600319)
		(width 0.155)
		(layer "B.Cu")
		(net 99)
	)
	(arc
		(start 149.454 89.753)
		(mid 149.410066 89.859066)
		(end 149.304 89.903)
		(width 0.155)
		(layer "B.Cu")
		(net 99)
	)
	(arc
		(start 158.985948 89.255785)
		(mid 159.032811 89.368922)
		(end 158.985948 89.482059)
		(width 0.155)
		(layer "B.Cu")
		(net 99)
	)
	(arc
		(start 160.419529 88.992311)
		(mid 160.466392 89.105448)
		(end 160.419529 89.218585)
		(width 0.155)
		(layer "B.Cu")
		(net 99)
	)
	(arc
		(start 149.604 89.600319)
		(mid 149.497934 89.644253)
		(end 149.454 89.750319)
		(width 0.155)
		(layer "B.Cu")
		(net 99)
	)
	(arc
		(start 160.295942 87.624217)
		(mid 159.984815 87.495344)
		(end 159.673688 87.624217)
		(width 0.155)
		(layer "B.Cu")
		(net 99)
	)
	(segment
		(start 145.324871 86.898307)
		(end 145.324871 87.356861)
		(width 0.155)
		(layer "F.Cu")
		(net 100)
	)
	(segment
		(start 145.718664 86.348951)
		(end 145.718664 86.504514)
		(width 0.155)
		(layer "F.Cu")
		(net 100)
	)
	(segment
		(start 173.811 87.109)
		(end 174.144286 87.109)
		(width 0.155)
		(layer "F.Cu")
		(net 100)
	)
	(segment
		(start 172.171 87.389)
		(end 172.171 86.709)
		(width 0.155)
		(layer "F.Cu")
		(net 100)
	)
	(segment
		(start 164.2425 88.288887)
		(end 164.465 88.066387)
		(width 0.155)
		(layer "F.Cu")
		(net 100)
	)
	(segment
		(start 168.251 86.709)
		(end 168.251 87.109)
		(width 0.155)
		(layer "F.Cu")
		(net 100)
	)
	(segment
		(start 173.371 87.789)
		(end 173.371 87.549)
		(width 0.155)
		(layer "F.Cu")
		(net 100)
	)
	(segment
		(start 168.571 87.389)
		(end 168.571 86.709)
		(width 0.155)
		(layer "F.Cu")
		(net 100)
	)
	(segment
		(start 170.651 87.109)
		(end 170.651 87.789)
		(width 0.155)
		(layer "F.Cu")
		(net 100)
	)
	(segment
		(start 167.051 87.549)
		(end 167.051 87.789)
		(width 0.155)
		(layer "F.Cu")
		(net 100)
	)
	(segment
		(start 164.465 88.066387)
		(end 164.465 87.646677)
		(width 0.155)
		(layer "F.Cu")
		(net 100)
	)
	(segment
		(start 169.771 87.389)
		(end 169.771 86.709)
		(width 0.155)
		(layer "F.Cu")
		(net 100)
	)
	(segment
		(start 172.171 87.789)
		(end 172.171 87.389)
		(width 0.155)
		(layer "F.Cu")
		(net 100)
	)
	(segment
		(start 145.718664 86.504514)
		(end 145.324871 86.898307)
		(width 0.155)
		(layer "F.Cu")
		(net 100)
	)
	(segment
		(start 169.451 86.709)
		(end 169.451 87.109)
		(width 0.155)
		(layer "F.Cu")
		(net 100)
	)
	(segment
		(start 173.051 86.709)
		(end 173.051 87.109)
		(width 0.155)
		(layer "F.Cu")
		(net 100)
	)
	(segment
		(start 173.051 87.109)
		(end 173.051 87.789)
		(width 0.155)
		(layer "F.Cu")
		(net 100)
	)
	(segment
		(start 171.851 86.709)
		(end 171.851 87.109)
		(width 0.155)
		(layer "F.Cu")
		(net 100)
	)
	(segment
		(start 168.251 87.109)
		(end 168.251 87.789)
		(width 0.155)
		(layer "F.Cu")
		(net 100)
	)
	(segment
		(start 164.465 87.646677)
		(end 165.002677 87.109)
		(width 0.155)
		(layer "F.Cu")
		(net 100)
	)
	(segment
		(start 170.971 87.389)
		(end 170.971 86.709)
		(width 0.155)
		(layer "F.Cu")
		(net 100)
	)
	(segment
		(start 170.971 87.789)
		(end 170.971 87.389)
		(width 0.155)
		(layer "F.Cu")
		(net 100)
	)
	(segment
		(start 145.324871 87.356861)
		(end 146.619173 88.651163)
		(width 0.155)
		(layer "F.Cu")
		(net 100)
	)
	(segment
		(start 183.776 85.043)
		(end 183.886 84.933)
		(width 0.155)
		(layer "F.Cu")
		(net 100)
	)
	(segment
		(start 167.371 87.549)
		(end 167.371 86.709)
		(width 0.155)
		(layer "F.Cu")
		(net 100)
	)
	(segment
		(start 168.571 87.789)
		(end 168.571 87.389)
		(width 0.155)
		(layer "F.Cu")
		(net 100)
	)
	(segment
		(start 174.144286 87.109)
		(end 181.04401 87.109)
		(width 0.155)
		(layer "F.Cu")
		(net 100)
	)
	(segment
		(start 165.002677 87.109)
		(end 166.611 87.109)
		(width 0.155)
		(layer "F.Cu")
		(net 100)
	)
	(segment
		(start 181.04401 87.109)
		(end 183.11001 85.043)
		(width 0.155)
		(layer "F.Cu")
		(net 100)
	)
	(segment
		(start 171.851 87.109)
		(end 171.851 87.789)
		(width 0.155)
		(layer "F.Cu")
		(net 100)
	)
	(segment
		(start 183.11001 85.043)
		(end 183.776 85.043)
		(width 0.155)
		(layer "F.Cu")
		(net 100)
	)
	(segment
		(start 170.651 86.709)
		(end 170.651 87.109)
		(width 0.155)
		(layer "F.Cu")
		(net 100)
	)
	(segment
		(start 169.771 87.789)
		(end 169.771 87.389)
		(width 0.155)
		(layer "F.Cu")
		(net 100)
	)
	(segment
		(start 169.451 87.109)
		(end 169.451 87.789)
		(width 0.155)
		(layer "F.Cu")
		(net 100)
	)
	(segment
		(start 167.371 87.789)
		(end 167.371 87.549)
		(width 0.155)
		(layer "F.Cu")
		(net 100)
	)
	(segment
		(start 146.619173 88.651163)
		(end 146.619173 88.965827)
		(width 0.155)
		(layer "F.Cu")
		(net 100)
	)
	(via
		(at 146.619173 88.965827)
		(size 0.6)
		(drill 0.35)
		(layers "F.Cu" "B.Cu")
		(net 100)
	)
	(via
		(at 164.2425 88.288887)
		(size 0.6)
		(drill 0.35)
		(layers "F.Cu" "B.Cu")
		(net 100)
	)
	(arc
		(start 168.411 87.949)
		(mid 168.524137 87.902137)
		(end 168.571 87.789)
		(width 0.155)
		(layer "F.Cu")
		(net 100)
	)
	(arc
		(start 170.651 87.789)
		(mid 170.697863 87.902137)
		(end 170.811 87.949)
		(width 0.155)
		(layer "F.Cu")
		(net 100)
	)
	(arc
		(start 167.811 86.269)
		(mid 168.122127 86.397873)
		(end 168.251 86.709)
		(width 0.155)
		(layer "F.Cu")
		(net 100)
	)
	(arc
		(start 173.371 87.549)
		(mid 173.499873 87.237873)
		(end 173.811 87.109)
		(width 0.155)
		(layer "F.Cu")
		(net 100)
	)
	(arc
		(start 171.851 87.789)
		(mid 171.897863 87.902137)
		(end 172.011 87.949)
		(width 0.155)
		(layer "F.Cu")
		(net 100)
	)
	(arc
		(start 172.171 86.709)
		(mid 172.299873 86.397873)
		(end 172.611 86.269)
		(width 0.155)
		(layer "F.Cu")
		(net 100)
	)
	(arc
		(start 166.611 87.109)
		(mid 166.922127 87.237873)
		(end 167.051 87.549)
		(width 0.155)
		(layer "F.Cu")
		(net 100)
	)
	(arc
		(start 168.571 86.709)
		(mid 168.699873 86.397873)
		(end 169.011 86.269)
		(width 0.155)
		(layer "F.Cu")
		(net 100)
	)
	(arc
		(start 169.771 86.709)
		(mid 169.899873 86.397873)
		(end 170.211 86.269)
		(width 0.155)
		(layer "F.Cu")
		(net 100)
	)
	(arc
		(start 169.451 87.789)
		(mid 169.497863 87.902137)
		(end 169.611 87.949)
		(width 0.155)
		(layer "F.Cu")
		(net 100)
	)
	(arc
		(start 167.371 86.709)
		(mid 167.499873 86.397873)
		(end 167.811 86.269)
		(width 0.155)
		(layer "F.Cu")
		(net 100)
	)
	(arc
		(start 173.211 87.949)
		(mid 173.324137 87.902137)
		(end 173.371 87.789)
		(width 0.155)
		(layer "F.Cu")
		(net 100)
	)
	(arc
		(start 173.051 87.789)
		(mid 173.097863 87.902137)
		(end 173.211 87.949)
		(width 0.155)
		(layer "F.Cu")
		(net 100)
	)
	(arc
		(start 169.611 87.949)
		(mid 169.724137 87.902137)
		(end 169.771 87.789)
		(width 0.155)
		(layer "F.Cu")
		(net 100)
	)
	(arc
		(start 170.811 87.949)
		(mid 170.924137 87.902137)
		(end 170.971 87.789)
		(width 0.155)
		(layer "F.Cu")
		(net 100)
	)
	(arc
		(start 170.971 86.709)
		(mid 171.099873 86.397873)
		(end 171.411 86.269)
		(width 0.155)
		(layer "F.Cu")
		(net 100)
	)
	(arc
		(start 172.611 86.269)
		(mid 172.922127 86.397873)
		(end 173.051 86.709)
		(width 0.155)
		(layer "F.Cu")
		(net 100)
	)
	(arc
		(start 171.411 86.269)
		(mid 171.722127 86.397873)
		(end 171.851 86.709)
		(width 0.155)
		(layer "F.Cu")
		(net 100)
	)
	(arc
		(start 167.051 87.789)
		(mid 167.097863 87.902137)
		(end 167.211 87.949)
		(width 0.155)
		(layer "F.Cu")
		(net 100)
	)
	(arc
		(start 172.011 87.949)
		(mid 172.124137 87.902137)
		(end 172.171 87.789)
		(width 0.155)
		(layer "F.Cu")
		(net 100)
	)
	(arc
		(start 168.251 87.789)
		(mid 168.297863 87.902137)
		(end 168.411 87.949)
		(width 0.155)
		(layer "F.Cu")
		(net 100)
	)
	(arc
		(start 167.211 87.949)
		(mid 167.324137 87.902137)
		(end 167.371 87.789)
		(width 0.155)
		(layer "F.Cu")
		(net 100)
	)
	(arc
		(start 170.211 86.269)
		(mid 170.522127 86.397873)
		(end 170.651 86.709)
		(width 0.155)
		(layer "F.Cu")
		(net 100)
	)
	(arc
		(start 169.011 86.269)
		(mid 169.322127 86.397873)
		(end 169.451 86.709)
		(width 0.155)
		(layer "F.Cu")
		(net 100)
	)
	(segment
		(start 160.25874 87.982994)
		(end 160.097952 87.822206)
		(width 0.155)
		(layer "B.Cu")
		(net 100)
	)
	(segment
		(start 161.47499 87.389)
		(end 160.880994 87.982994)
		(width 0.155)
		(layer "B.Cu")
		(net 100)
	)
	(segment
		(start 159.871678 88.04848)
		(end 160.032465 88.209267)
		(width 0.155)
		(layer "B.Cu")
		(net 100)
	)
	(segment
		(start 164.113677 87.389)
		(end 161.47499 87.389)
		(width 0.155)
		(layer "B.Cu")
		(net 100)
	)
	(segment
		(start 159.023151 88.897009)
		(end 159.183938 89.057796)
		(width 0.155)
		(layer "B.Cu")
		(net 100)
	)
	(segment
		(start 164.465 88.066387)
		(end 164.465 87.740323)
		(width 0.155)
		(layer "B.Cu")
		(net 100)
	)
	(segment
		(start 164.465 87.740323)
		(end 164.113677 87.389)
		(width 0.155)
		(layer "B.Cu")
		(net 100)
	)
	(segment
		(start 148.15101 90.183)
		(end 146.933837 88.965827)
		(width 0.155)
		(layer "B.Cu")
		(net 100)
	)
	(segment
		(start 158.68099 90.183)
		(end 148.15101 90.183)
		(width 0.155)
		(layer "B.Cu")
		(net 100)
	)
	(segment
		(start 159.183938 89.68005)
		(end 158.918334 89.945656)
		(width 0.155)
		(layer "B.Cu")
		(net 100)
	)
	(segment
		(start 164.2425 88.288887)
		(end 164.465 88.066387)
		(width 0.155)
		(layer "B.Cu")
		(net 100)
	)
	(segment
		(start 160.032465 88.209267)
		(end 160.617519 88.794321)
		(width 0.155)
		(layer "B.Cu")
		(net 100)
	)
	(segment
		(start 159.995265 89.416576)
		(end 159.249425 88.670735)
		(width 0.155)
		(layer "B.Cu")
		(net 100)
	)
	(segment
		(start 146.933837 88.965827)
		(end 146.619173 88.965827)
		(width 0.155)
		(layer "B.Cu")
		(net 100)
	)
	(segment
		(start 159.995267 89.416575)
		(end 159.995265 89.416576)
		(width 0.155)
		(layer "B.Cu")
		(net 100)
	)
	(segment
		(start 158.918334 89.945656)
		(end 158.68099 90.183)
		(width 0.155)
		(layer "B.Cu")
		(net 100)
	)
	(arc
		(start 159.871678 87.822206)
		(mid 159.824815 87.935343)
		(end 159.871678 88.04848)
		(width 0.155)
		(layer "B.Cu")
		(net 100)
	)
	(arc
		(start 159.183938 89.057796)
		(mid 159.312811 89.368923)
		(end 159.183938 89.68005)
		(width 0.155)
		(layer "B.Cu")
		(net 100)
	)
	(arc
		(start 160.097952 87.822206)
		(mid 159.984815 87.775343)
		(end 159.871678 87.822206)
		(width 0.155)
		(layer "B.Cu")
		(net 100)
	)
	(arc
		(start 160.617519 89.416575)
		(mid 160.306392 89.545449)
		(end 159.995267 89.416575)
		(width 0.155)
		(layer "B.Cu")
		(net 100)
	)
	(arc
		(start 160.880994 87.982994)
		(mid 160.569867 88.111867)
		(end 160.25874 87.982994)
		(width 0.155)
		(layer "B.Cu")
		(net 100)
	)
	(arc
		(start 159.249425 88.670735)
		(mid 159.136288 88.623872)
		(end 159.023151 88.670735)
		(width 0.155)
		(layer "B.Cu")
		(net 100)
	)
	(arc
		(start 160.617519 88.794321)
		(mid 160.746392 89.105448)
		(end 160.617519 89.416575)
		(width 0.155)
		(layer "B.Cu")
		(net 100)
	)
	(arc
		(start 159.023151 88.670735)
		(mid 158.976288 88.783872)
		(end 159.023151 88.897009)
		(width 0.155)
		(layer "B.Cu")
		(net 100)
	)
	(segment
		(start 144.502441 85.288291)
		(end 144.658004 85.288291)
		(width 0.155)
		(layer "F.Cu")
		(net 101)
	)
	(segment
		(start 173.480773 85.540763)
		(end 174.05901 86.119)
		(width 0.155)
		(layer "F.Cu")
		(net 101)
	)
	(segment
		(start 173.480773 85.017345)
		(end 173.480773 85.540763)
		(width 0.155)
		(layer "F.Cu")
		(net 101)
	)
	(segment
		(start 144.782327 91.437673)
		(end 144.467663 91.437673)
		(width 0.155)
		(layer "F.Cu")
		(net 101)
	)
	(segment
		(start 173.258273 84.794845)
		(end 173.480773 85.017345)
		(width 0.155)
		(layer "F.Cu")
		(net 101)
	)
	(segment
		(start 143.904 90.87401)
		(end 143.904 90.31)
		(width 0.155)
		(layer "F.Cu")
		(net 101)
	)
	(segment
		(start 179.76299 86.119)
		(end 181.55899 84.323)
		(width 0.155)
		(layer "F.Cu")
		(net 101)
	)
	(segment
		(start 143.904 85.886732)
		(end 144.502441 85.288291)
		(width 0.155)
		(layer "F.Cu")
		(net 101)
	)
	(segment
		(start 181.55899 84.323)
		(end 183.776 84.323)
		(width 0.155)
		(layer "F.Cu")
		(net 101)
	)
	(segment
		(start 183.776 84.323)
		(end 183.886 84.433)
		(width 0.155)
		(layer "F.Cu")
		(net 101)
	)
	(segment
		(start 174.05901 86.119)
		(end 179.76299 86.119)
		(width 0.155)
		(layer "F.Cu")
		(net 101)
	)
	(segment
		(start 143.904 89.06)
		(end 143.904 85.886732)
		(width 0.155)
		(layer "F.Cu")
		(net 101)
	)
	(segment
		(start 143.904 89.11)
		(end 143.904 89.06)
		(width 0.155)
		(layer "F.Cu")
		(net 101)
	)
	(segment
		(start 144.467663 91.437673)
		(end 143.904 90.87401)
		(width 0.155)
		(layer "F.Cu")
		(net 101)
	)
	(via
		(at 173.258273 84.794845)
		(size 0.6)
		(drill 0.35)
		(layers "F.Cu" "B.Cu")
		(net 101)
	)
	(via
		(at 144.782327 91.437673)
		(size 0.6)
		(drill 0.35)
		(layers "F.Cu" "B.Cu")
		(net 101)
	)
	(arc
		(start 144.204 90.01)
		(mid 144.160066 89.903934)
		(end 144.054 89.86)
		(width 0.155)
		(layer "F.Cu")
		(net 101)
	)
	(arc
		(start 144.204 89.41)
		(mid 144.160066 89.303934)
		(end 144.054 89.26)
		(width 0.155)
		(layer "F.Cu")
		(net 101)
	)
	(arc
		(start 144.054 89.86)
		(mid 143.947934 89.816066)
		(end 143.904 89.71)
		(width 0.155)
		(layer "F.Cu")
		(net 101)
	)
	(arc
		(start 144.054 89.26)
		(mid 143.947934 89.216066)
		(end 143.904 89.11)
		(width 0.155)
		(layer "F.Cu")
		(net 101)
	)
	(arc
		(start 143.904 90.31)
		(mid 143.947934 90.203934)
		(end 144.054 90.16)
		(width 0.155)
		(layer "F.Cu")
		(net 101)
	)
	(arc
		(start 143.904 89.71)
		(mid 143.947934 89.603934)
		(end 144.054 89.56)
		(width 0.155)
		(layer "F.Cu")
		(net 101)
	)
	(arc
		(start 144.054 89.56)
		(mid 144.160066 89.516066)
		(end 144.204 89.41)
		(width 0.155)
		(layer "F.Cu")
		(net 101)
	)
	(arc
		(start 144.054 90.16)
		(mid 144.160066 90.116066)
		(end 144.204 90.01)
		(width 0.155)
		(layer "F.Cu")
		(net 101)
	)
	(segment
		(start 148.373836 91.554672)
		(end 148.268164 91.554672)
		(width 0.155)
		(layer "B.Cu")
		(net 101)
	)
	(segment
		(start 166.43901 89.776)
		(end 161.35901 89.776)
		(width 0.155)
		(layer "B.Cu")
		(net 101)
	)
	(segment
		(start 172.53501 86.474)
		(end 169.74101 86.474)
		(width 0.155)
		(layer "B.Cu")
		(net 101)
	)
	(segment
		(start 152.681 91.941836)
		(end 152.681 92.716164)
		(width 0.155)
		(layer "B.Cu")
		(net 101)
	)
	(segment
		(start 148.973836 92.823328)
		(end 148.868164 92.823328)
		(width 0.155)
		(layer "B.Cu")
		(net 101)
	)
	(segment
		(start 147.881 91.941836)
		(end 147.881 92.716164)
		(width 0.155)
		(layer "B.Cu")
		(net 101)
	)
	(segment
		(start 173.480773 85.017345)
		(end 173.480773 85.528237)
		(width 0.155)
		(layer "B.Cu")
		(net 101)
	)
	(segment
		(start 149.573836 91.554672)
		(end 149.468164 91.554672)
		(width 0.155)
		(layer "B.Cu")
		(net 101)
	)
	(segment
		(start 169.74101 86.474)
		(end 166.43901 89.776)
		(width 0.155)
		(layer "B.Cu")
		(net 101)
	)
	(segment
		(start 150.173836 92.823328)
		(end 150.068164 92.823328)
		(width 0.155)
		(layer "B.Cu")
		(net 101)
	)
	(segment
		(start 158.94601 92.189)
		(end 153.668164 92.189)
		(width 0.155)
		(layer "B.Cu")
		(net 101)
	)
	(segment
		(start 152.361 92.716164)
		(end 152.361 91.941836)
		(width 0.155)
		(layer "B.Cu")
		(net 101)
	)
	(segment
		(start 146.678164 91.941836)
		(end 146.678164 92.081836)
		(width 0.155)
		(layer "B.Cu")
		(net 101)
	)
	(segment
		(start 153.173836 91.554672)
		(end 153.068164 91.554672)
		(width 0.155)
		(layer "B.Cu")
		(net 101)
	)
	(segment
		(start 153.561 92.081836)
		(end 153.561 91.941836)
		(width 0.155)
		(layer "B.Cu")
		(net 101)
	)
	(segment
		(start 150.773836 91.554672)
		(end 150.668164 91.554672)
		(width 0.155)
		(layer "B.Cu")
		(net 101)
	)
	(segment
		(start 173.480773 85.528237)
		(end 172.53501 86.474)
		(width 0.155)
		(layer "B.Cu")
		(net 101)
	)
	(segment
		(start 149.081 91.941836)
		(end 149.081 92.716164)
		(width 0.155)
		(layer "B.Cu")
		(net 101)
	)
	(segment
		(start 149.961 92.716164)
		(end 149.961 91.941836)
		(width 0.155)
		(layer "B.Cu")
		(net 101)
	)
	(segment
		(start 148.761 92.716164)
		(end 148.761 91.941836)
		(width 0.155)
		(layer "B.Cu")
		(net 101)
	)
	(segment
		(start 150.281 91.941836)
		(end 150.281 92.716164)
		(width 0.155)
		(layer "B.Cu")
		(net 101)
	)
	(segment
		(start 151.161 92.716164)
		(end 151.161 91.941836)
		(width 0.155)
		(layer "B.Cu")
		(net 101)
	)
	(segment
		(start 147.561 91.944672)
		(end 147.558164 91.941836)
		(width 0.155)
		(layer "B.Cu")
		(net 101)
	)
	(segment
		(start 173.258273 84.794845)
		(end 173.480773 85.017345)
		(width 0.155)
		(layer "B.Cu")
		(net 101)
	)
	(segment
		(start 151.373836 92.823328)
		(end 151.268164 92.823328)
		(width 0.155)
		(layer "B.Cu")
		(net 101)
	)
	(segment
		(start 152.573836 92.823328)
		(end 152.468164 92.823328)
		(width 0.155)
		(layer "B.Cu")
		(net 101)
	)
	(segment
		(start 151.481 91.941836)
		(end 151.481 92.716164)
		(width 0.155)
		(layer "B.Cu")
		(net 101)
	)
	(segment
		(start 147.561 92.716164)
		(end 147.561 91.944672)
		(width 0.155)
		(layer "B.Cu")
		(net 101)
	)
	(segment
		(start 147.773836 92.823328)
		(end 147.668164 92.823328)
		(width 0.155)
		(layer "B.Cu")
		(net 101)
	)
	(segment
		(start 145.21899 92.189)
		(end 144.782327 91.752337)
		(width 0.155)
		(layer "B.Cu")
		(net 101)
	)
	(segment
		(start 146.571 92.189)
		(end 145.21899 92.189)
		(width 0.155)
		(layer "B.Cu")
		(net 101)
	)
	(segment
		(start 161.35901 89.776)
		(end 158.94601 92.189)
		(width 0.155)
		(layer "B.Cu")
		(net 101)
	)
	(segment
		(start 151.973836 91.554672)
		(end 151.868164 91.554672)
		(width 0.155)
		(layer "B.Cu")
		(net 101)
	)
	(segment
		(start 144.782327 91.752337)
		(end 144.782327 91.437673)
		(width 0.155)
		(layer "B.Cu")
		(net 101)
	)
	(segment
		(start 147.171 91.554672)
		(end 147.065328 91.554672)
		(width 0.155)
		(layer "B.Cu")
		(net 101)
	)
	(arc
		(start 151.161 91.941836)
		(mid 151.047602 91.66807)
		(end 150.773836 91.554672)
		(width 0.155)
		(layer "B.Cu")
		(net 101)
	)
	(arc
		(start 151.868164 91.554672)
		(mid 151.594398 91.66807)
		(end 151.481 91.941836)
		(width 0.155)
		(layer "B.Cu")
		(net 101)
	)
	(arc
		(start 147.065328 91.554672)
		(mid 146.791562 91.66807)
		(end 146.678164 91.941836)
		(width 0.155)
		(layer "B.Cu")
		(net 101)
	)
	(arc
		(start 149.961 91.941836)
		(mid 149.847602 91.66807)
		(end 149.573836 91.554672)
		(width 0.155)
		(layer "B.Cu")
		(net 101)
	)
	(arc
		(start 148.268164 91.554672)
		(mid 147.994398 91.66807)
		(end 147.881 91.941836)
		(width 0.155)
		(layer "B.Cu")
		(net 101)
	)
	(arc
		(start 148.761 91.941836)
		(mid 148.647602 91.66807)
		(end 148.373836 91.554672)
		(width 0.155)
		(layer "B.Cu")
		(net 101)
	)
	(arc
		(start 148.868164 92.823328)
		(mid 148.792388 92.79194)
		(end 148.761 92.716164)
		(width 0.155)
		(layer "B.Cu")
		(net 101)
	)
	(arc
		(start 153.068164 91.554672)
		(mid 152.794398 91.66807)
		(end 152.681 91.941836)
		(width 0.155)
		(layer "B.Cu")
		(net 101)
	)
	(arc
		(start 146.678164 92.081836)
		(mid 146.646776 92.157612)
		(end 146.571 92.189)
		(width 0.155)
		(layer "B.Cu")
		(net 101)
	)
	(arc
		(start 153.561 91.941836)
		(mid 153.447602 91.66807)
		(end 153.173836 91.554672)
		(width 0.155)
		(layer "B.Cu")
		(net 101)
	)
	(arc
		(start 150.668164 91.554672)
		(mid 150.394398 91.66807)
		(end 150.281 91.941836)
		(width 0.155)
		(layer "B.Cu")
		(net 101)
	)
	(arc
		(start 149.468164 91.554672)
		(mid 149.194398 91.66807)
		(end 149.081 91.941836)
		(width 0.155)
		(layer "B.Cu")
		(net 101)
	)
	(arc
		(start 150.068164 92.823328)
		(mid 149.992388 92.79194)
		(end 149.961 92.716164)
		(width 0.155)
		(layer "B.Cu")
		(net 101)
	)
	(arc
		(start 147.558164 91.941836)
		(mid 147.444766 91.66807)
		(end 147.171 91.554672)
		(width 0.155)
		(layer "B.Cu")
		(net 101)
	)
	(arc
		(start 147.881 92.716164)
		(mid 147.849612 92.79194)
		(end 147.773836 92.823328)
		(width 0.155)
		(layer "B.Cu")
		(net 101)
	)
	(arc
		(start 147.668164 92.823328)
		(mid 147.592388 92.79194)
		(end 147.561 92.716164)
		(width 0.155)
		(layer "B.Cu")
		(net 101)
	)
	(arc
		(start 150.281 92.716164)
		(mid 150.249612 92.79194)
		(end 150.173836 92.823328)
		(width 0.155)
		(layer "B.Cu")
		(net 101)
	)
	(arc
		(start 151.268164 92.823328)
		(mid 151.192388 92.79194)
		(end 151.161 92.716164)
		(width 0.155)
		(layer "B.Cu")
		(net 101)
	)
	(arc
		(start 152.681 92.716164)
		(mid 152.649612 92.79194)
		(end 152.573836 92.823328)
		(width 0.155)
		(layer "B.Cu")
		(net 101)
	)
	(arc
		(start 151.481 92.716164)
		(mid 151.449612 92.79194)
		(end 151.373836 92.823328)
		(width 0.155)
		(layer "B.Cu")
		(net 101)
	)
	(arc
		(start 152.468164 92.823328)
		(mid 152.392388 92.79194)
		(end 152.361 92.716164)
		(width 0.155)
		(layer "B.Cu")
		(net 101)
	)
	(arc
		(start 153.668164 92.189)
		(mid 153.592388 92.157612)
		(end 153.561 92.081836)
		(width 0.155)
		(layer "B.Cu")
		(net 101)
	)
	(arc
		(start 149.081 92.716164)
		(mid 149.049612 92.79194)
		(end 148.973836 92.823328)
		(width 0.155)
		(layer "B.Cu")
		(net 101)
	)
	(arc
		(start 152.361 91.941836)
		(mid 152.247602 91.66807)
		(end 151.973836 91.554672)
		(width 0.155)
		(layer "B.Cu")
		(net 101)
	)
	(segment
		(start 173.760773 85.017345)
		(end 173.760773 85.424783)
		(width 0.155)
		(layer "F.Cu")
		(net 102)
	)
	(segment
		(start 173.983273 84.794845)
		(end 173.760773 85.017345)
		(width 0.155)
		(layer "F.Cu")
		(net 102)
	)
	(segment
		(start 183.776 84.043)
		(end 183.886 83.933)
		(width 0.155)
		(layer "F.Cu")
		(net 102)
	)
	(segment
		(start 144.304451 85.090301)
		(end 143.624 85.770752)
		(width 0.155)
		(layer "F.Cu")
		(net 102)
	)
	(segment
		(start 173.760773 85.424783)
		(end 174.17499 85.839)
		(width 0.155)
		(layer "F.Cu")
		(net 102)
	)
	(segment
		(start 143.624 90.98999)
		(end 144.269673 91.635663)
		(width 0.155)
		(layer "F.Cu")
		(net 102)
	)
	(segment
		(start 144.269673 91.635663)
		(end 144.269673 91.950327)
		(width 0.155)
		(layer "F.Cu")
		(net 102)
	)
	(segment
		(start 181.44301 84.043)
		(end 183.776 84.043)
		(width 0.155)
		(layer "F.Cu")
		(net 102)
	)
	(segment
		(start 143.624 90.98999)
		(end 143.624 85.770752)
		(width 0.155)
		(layer "F.Cu")
		(net 102)
	)
	(segment
		(start 174.17499 85.839)
		(end 179.64701 85.839)
		(width 0.155)
		(layer "F.Cu")
		(net 102)
	)
	(segment
		(start 144.304451 84.934737)
		(end 144.304451 85.090301)
		(width 0.155)
		(layer "F.Cu")
		(net 102)
	)
	(segment
		(start 179.64701 85.839)
		(end 181.44301 84.043)
		(width 0.155)
		(layer "F.Cu")
		(net 102)
	)
	(via
		(at 144.269673 91.950327)
		(size 0.6)
		(drill 0.35)
		(layers "F.Cu" "B.Cu")
		(net 102)
	)
	(via
		(at 173.983273 84.794845)
		(size 0.6)
		(drill 0.35)
		(layers "F.Cu" "B.Cu")
		(net 102)
	)
	(segment
		(start 148.481 91.941836)
		(end 148.481 92.716164)
		(width 0.155)
		(layer "B.Cu")
		(net 102)
	)
	(segment
		(start 147.278164 91.941836)
		(end 147.278164 92.713328)
		(width 0.155)
		(layer "B.Cu")
		(net 102)
	)
	(segment
		(start 145.10301 92.469)
		(end 146.571 92.469)
		(width 0.155)
		(layer "B.Cu")
		(net 102)
	)
	(segment
		(start 153.668164 92.469)
		(end 159.06199 92.469)
		(width 0.155)
		(layer "B.Cu")
		(net 102)
	)
	(segment
		(start 152.961 92.716164)
		(end 152.961 91.941836)
		(width 0.155)
		(layer "B.Cu")
		(net 102)
	)
	(segment
		(start 159.06199 92.469)
		(end 161.47499 90.056)
		(width 0.155)
		(layer "B.Cu")
		(net 102)
	)
	(segment
		(start 148.161 92.716164)
		(end 148.161 91.941836)
		(width 0.155)
		(layer "B.Cu")
		(net 102)
	)
	(segment
		(start 151.868164 91.834672)
		(end 151.973836 91.834672)
		(width 0.155)
		(layer "B.Cu")
		(net 102)
	)
	(segment
		(start 173.760773 85.017345)
		(end 173.983273 84.794845)
		(width 0.155)
		(layer "B.Cu")
		(net 102)
	)
	(segment
		(start 149.361 92.716164)
		(end 149.361 91.941836)
		(width 0.155)
		(layer "B.Cu")
		(net 102)
	)
	(segment
		(start 144.269673 91.950327)
		(end 144.584337 91.950327)
		(width 0.155)
		(layer "B.Cu")
		(net 102)
	)
	(segment
		(start 152.468164 93.103328)
		(end 152.573836 93.103328)
		(width 0.155)
		(layer "B.Cu")
		(net 102)
	)
	(segment
		(start 152.081 91.941836)
		(end 152.081 92.716164)
		(width 0.155)
		(layer "B.Cu")
		(net 102)
	)
	(segment
		(start 151.268164 93.103328)
		(end 151.373836 93.103328)
		(width 0.155)
		(layer "B.Cu")
		(net 102)
	)
	(segment
		(start 148.868164 93.103328)
		(end 148.973836 93.103328)
		(width 0.155)
		(layer "B.Cu")
		(net 102)
	)
	(segment
		(start 147.278164 92.713328)
		(end 147.281 92.716164)
		(width 0.155)
		(layer "B.Cu")
		(net 102)
	)
	(segment
		(start 147.065328 91.834672)
		(end 147.171 91.834672)
		(width 0.155)
		(layer "B.Cu")
		(net 102)
	)
	(segment
		(start 150.881 91.941836)
		(end 150.881 92.716164)
		(width 0.155)
		(layer "B.Cu")
		(net 102)
	)
	(segment
		(start 161.47499 90.056)
		(end 166.55499 90.056)
		(width 0.155)
		(layer "B.Cu")
		(net 102)
	)
	(segment
		(start 144.584337 91.950327)
		(end 145.10301 92.469)
		(width 0.155)
		(layer "B.Cu")
		(net 102)
	)
	(segment
		(start 146.958164 92.081836)
		(end 146.958164 91.941836)
		(width 0.155)
		(layer "B.Cu")
		(net 102)
	)
	(segment
		(start 173.760773 85.644217)
		(end 173.760773 85.017345)
		(width 0.155)
		(layer "B.Cu")
		(net 102)
	)
	(segment
		(start 172.65099 86.754)
		(end 173.760773 85.644217)
		(width 0.155)
		(layer "B.Cu")
		(net 102)
	)
	(segment
		(start 153.281 91.941836)
		(end 153.281 92.081836)
		(width 0.155)
		(layer "B.Cu")
		(net 102)
	)
	(segment
		(start 148.268164 91.834672)
		(end 148.373836 91.834672)
		(width 0.155)
		(layer "B.Cu")
		(net 102)
	)
	(segment
		(start 150.068164 93.103328)
		(end 150.173836 93.103328)
		(width 0.155)
		(layer "B.Cu")
		(net 102)
	)
	(segment
		(start 149.681 91.941836)
		(end 149.681 92.716164)
		(width 0.155)
		(layer "B.Cu")
		(net 102)
	)
	(segment
		(start 151.761 92.716164)
		(end 151.761 91.941836)
		(width 0.155)
		(layer "B.Cu")
		(net 102)
	)
	(segment
		(start 150.668164 91.834672)
		(end 150.773836 91.834672)
		(width 0.155)
		(layer "B.Cu")
		(net 102)
	)
	(segment
		(start 153.068164 91.834672)
		(end 153.173836 91.834672)
		(width 0.155)
		(layer "B.Cu")
		(net 102)
	)
	(segment
		(start 150.561 92.716164)
		(end 150.561 91.941836)
		(width 0.155)
		(layer "B.Cu")
		(net 102)
	)
	(segment
		(start 166.55499 90.056)
		(end 169.85699 86.754)
		(width 0.155)
		(layer "B.Cu")
		(net 102)
	)
	(segment
		(start 147.668164 93.103328)
		(end 147.773836 93.103328)
		(width 0.155)
		(layer "B.Cu")
		(net 102)
	)
	(segment
		(start 149.468164 91.834672)
		(end 149.573836 91.834672)
		(width 0.155)
		(layer "B.Cu")
		(net 102)
	)
	(segment
		(start 169.85699 86.754)
		(end 172.65099 86.754)
		(width 0.155)
		(layer "B.Cu")
		(net 102)
	)
	(arc
		(start 150.173836 93.103328)
		(mid 150.447602 92.98993)
		(end 150.561 92.716164)
		(width 0.155)
		(layer "B.Cu")
		(net 102)
	)
	(arc
		(start 151.973836 91.834672)
		(mid 152.049612 91.86606)
		(end 152.081 91.941836)
		(width 0.155)
		(layer "B.Cu")
		(net 102)
	)
	(arc
		(start 153.173836 91.834672)
		(mid 153.249612 91.86606)
		(end 153.281 91.941836)
		(width 0.155)
		(layer "B.Cu")
		(net 102)
	)
	(arc
		(start 148.973836 93.103328)
		(mid 149.247602 92.98993)
		(end 149.361 92.716164)
		(width 0.155)
		(layer "B.Cu")
		(net 102)
	)
	(arc
		(start 150.561 91.941836)
		(mid 150.592388 91.86606)
		(end 150.668164 91.834672)
		(width 0.155)
		(layer "B.Cu")
		(net 102)
	)
	(arc
		(start 147.171 91.834672)
		(mid 147.246776 91.86606)
		(end 147.278164 91.941836)
		(width 0.155)
		(layer "B.Cu")
		(net 102)
	)
	(arc
		(start 152.961 91.941836)
		(mid 152.992388 91.86606)
		(end 153.068164 91.834672)
		(width 0.155)
		(layer "B.Cu")
		(net 102)
	)
	(arc
		(start 153.281 92.081836)
		(mid 153.394398 92.355602)
		(end 153.668164 92.469)
		(width 0.155)
		(layer "B.Cu")
		(net 102)
	)
	(arc
		(start 150.881 92.716164)
		(mid 150.994398 92.98993)
		(end 151.268164 93.103328)
		(width 0.155)
		(layer "B.Cu")
		(net 102)
	)
	(arc
		(start 147.773836 93.103328)
		(mid 148.047602 92.98993)
		(end 148.161 92.716164)
		(width 0.155)
		(layer "B.Cu")
		(net 102)
	)
	(arc
		(start 150.773836 91.834672)
		(mid 150.849612 91.86606)
		(end 150.881 91.941836)
		(width 0.155)
		(layer "B.Cu")
		(net 102)
	)
	(arc
		(start 151.373836 93.103328)
		(mid 151.647602 92.98993)
		(end 151.761 92.716164)
		(width 0.155)
		(layer "B.Cu")
		(net 102)
	)
	(arc
		(start 149.681 92.716164)
		(mid 149.794398 92.98993)
		(end 150.068164 93.103328)
		(width 0.155)
		(layer "B.Cu")
		(net 102)
	)
	(arc
		(start 148.161 91.941836)
		(mid 148.192388 91.86606)
		(end 148.268164 91.834672)
		(width 0.155)
		(layer "B.Cu")
		(net 102)
	)
	(arc
		(start 146.958164 91.941836)
		(mid 146.989552 91.86606)
		(end 147.065328 91.834672)
		(width 0.155)
		(layer "B.Cu")
		(net 102)
	)
	(arc
		(start 146.571 92.469)
		(mid 146.844766 92.355602)
		(end 146.958164 92.081836)
		(width 0.155)
		(layer "B.Cu")
		(net 102)
	)
	(arc
		(start 148.373836 91.834672)
		(mid 148.449612 91.86606)
		(end 148.481 91.941836)
		(width 0.155)
		(layer "B.Cu")
		(net 102)
	)
	(arc
		(start 151.761 91.941836)
		(mid 151.792388 91.86606)
		(end 151.868164 91.834672)
		(width 0.155)
		(layer "B.Cu")
		(net 102)
	)
	(arc
		(start 149.573836 91.834672)
		(mid 149.649612 91.86606)
		(end 149.681 91.941836)
		(width 0.155)
		(layer "B.Cu")
		(net 102)
	)
	(arc
		(start 148.481 92.716164)
		(mid 148.594398 92.98993)
		(end 148.868164 93.103328)
		(width 0.155)
		(layer "B.Cu")
		(net 102)
	)
	(arc
		(start 152.573836 93.103328)
		(mid 152.847602 92.98993)
		(end 152.961 92.716164)
		(width 0.155)
		(layer "B.Cu")
		(net 102)
	)
	(arc
		(start 147.281 92.716164)
		(mid 147.394398 92.98993)
		(end 147.668164 93.103328)
		(width 0.155)
		(layer "B.Cu")
		(net 102)
	)
	(arc
		(start 152.081 92.716164)
		(mid 152.194398 92.98993)
		(end 152.468164 93.103328)
		(width 0.155)
		(layer "B.Cu")
		(net 102)
	)
	(arc
		(start 149.361 91.941836)
		(mid 149.392388 91.86606)
		(end 149.468164 91.834672)
		(width 0.155)
		(layer "B.Cu")
		(net 102)
	)
	(segment
		(start 154.752 92.062)
		(end 157.117608 92.062)
		(width 0.155)
		(layer "F.Cu")
		(net 103)
	)
	(segment
		(start 175.255129 79.104264)
		(end 175.569793 79.104264)
		(width 0.155)
		(layer "F.Cu")
		(net 103)
	)
	(segment
		(start 175.569793 79.104264)
		(end 175.980529 79.515)
		(width 0.155)
		(layer "F.Cu")
		(net 103)
	)
	(segment
		(start 149.018 91.909268)
		(end 149.018 91.912)
		(width 0.155)
		(layer "F.Cu")
		(net 103)
	)
	(segment
		(start 145.365111 85.995398)
		(end 145.209547 85.995398)
		(width 0.155)
		(layer "F.Cu")
		(net 103)
	)
	(segment
		(start 148.418 91.909268)
		(end 148.418 91.912)
		(width 0.155)
		(layer "F.Cu")
		(net 103)
	)
	(segment
		(start 153.112 92.750981)
		(end 153.112 92.342)
		(width 0.155)
		(layer "F.Cu")
		(net 103)
	)
	(segment
		(start 149.168 92.062)
		(end 151.752 92.062)
		(width 0.155)
		(layer "F.Cu")
		(net 103)
	)
	(segment
		(start 153.992 91.653019)
		(end 153.992 92.062)
		(width 0.155)
		(layer "F.Cu")
		(net 103)
	)
	(segment
		(start 164.986 84.95)
		(end 165.6395 84.95)
		(width 0.155)
		(layer "F.Cu")
		(net 103)
	)
	(segment
		(start 145.209547 85.995398)
		(end 144.793 86.411945)
		(width 0.155)
		(layer "F.Cu")
		(net 103)
	)
	(segment
		(start 152.792 91.653019)
		(end 152.792 91.902)
		(width 0.155)
		(layer "F.Cu")
		(net 103)
	)
	(segment
		(start 148.118 91.912)
		(end 148.118 91.909268)
		(width 0.155)
		(layer "F.Cu")
		(net 103)
	)
	(segment
		(start 181.570515 79.515)
		(end 182.900515 80.845)
		(width 0.155)
		(layer "F.Cu")
		(net 103)
	)
	(segment
		(start 153.112 92.342)
		(end 153.112 91.653019)
		(width 0.155)
		(layer "F.Cu")
		(net 103)
	)
	(segment
		(start 154.312 92.750981)
		(end 154.312 92.502)
		(width 0.155)
		(layer "F.Cu")
		(net 103)
	)
	(segment
		(start 157.117608 92.062)
		(end 157.874 92.062)
		(width 0.155)
		(layer "F.Cu")
		(net 103)
	)
	(segment
		(start 144.793 86.411945)
		(end 144.793 87.69901)
		(width 0.155)
		(layer "F.Cu")
		(net 103)
	)
	(segment
		(start 182.900515 80.845)
		(end 183.798505 80.845)
		(width 0.155)
		(layer "F.Cu")
		(net 103)
	)
	(segment
		(start 183.798505 80.845)
		(end 183.908505 80.955)
		(width 0.155)
		(layer "F.Cu")
		(net 103)
	)
	(segment
		(start 151.912 91.902)
		(end 151.912 91.653019)
		(width 0.155)
		(layer "F.Cu")
		(net 103)
	)
	(segment
		(start 165.6395 84.95)
		(end 165.862 84.7275)
		(width 0.155)
		(layer "F.Cu")
		(net 103)
	)
	(segment
		(start 144.793 87.69901)
		(end 145.174 88.08001)
		(width 0.155)
		(layer "F.Cu")
		(net 103)
	)
	(segment
		(start 152.792 91.902)
		(end 152.792 92.750981)
		(width 0.155)
		(layer "F.Cu")
		(net 103)
	)
	(segment
		(start 148.718 91.912)
		(end 148.718 91.909268)
		(width 0.155)
		(layer "F.Cu")
		(net 103)
	)
	(segment
		(start 145.174 89.675)
		(end 147.561 92.062)
		(width 0.155)
		(layer "F.Cu")
		(net 103)
	)
	(segment
		(start 147.561 92.062)
		(end 147.968 92.062)
		(width 0.155)
		(layer "F.Cu")
		(net 103)
	)
	(segment
		(start 157.874 92.062)
		(end 164.986 84.95)
		(width 0.155)
		(layer "F.Cu")
		(net 103)
	)
	(segment
		(start 145.174 88.08001)
		(end 145.174 89.675)
		(width 0.155)
		(layer "F.Cu")
		(net 103)
	)
	(segment
		(start 175.980529 79.515)
		(end 181.570515 79.515)
		(width 0.155)
		(layer "F.Cu")
		(net 103)
	)
	(segment
		(start 153.992 92.062)
		(end 153.992 92.750981)
		(width 0.155)
		(layer "F.Cu")
		(net 103)
	)
	(via
		(at 175.255129 79.104264)
		(size 0.6)
		(drill 0.35)
		(layers "F.Cu" "B.Cu")
		(net 103)
	)
	(via
		(at 165.862 84.7275)
		(size 0.6)
		(drill 0.35)
		(layers "F.Cu" "B.Cu")
		(net 103)
	)
	(arc
		(start 151.912 91.653019)
		(mid 152.040873 91.341892)
		(end 152.352 91.213019)
		(width 0.155)
		(layer "F.Cu")
		(net 103)
	)
	(arc
		(start 147.968 92.062)
		(mid 148.074066 92.018066)
		(end 148.118 91.912)
		(width 0.155)
		(layer "F.Cu")
		(net 103)
	)
	(arc
		(start 148.568 92.062)
		(mid 148.674066 92.018066)
		(end 148.718 91.912)
		(width 0.155)
		(layer "F.Cu")
		(net 103)
	)
	(arc
		(start 153.552 91.213019)
		(mid 153.863127 91.341892)
		(end 153.992 91.653019)
		(width 0.155)
		(layer "F.Cu")
		(net 103)
	)
	(arc
		(start 153.112 91.653019)
		(mid 153.240873 91.341892)
		(end 153.552 91.213019)
		(width 0.155)
		(layer "F.Cu")
		(net 103)
	)
	(arc
		(start 152.952 92.910981)
		(mid 153.065137 92.864118)
		(end 153.112 92.750981)
		(width 0.155)
		(layer "F.Cu")
		(net 103)
	)
	(arc
		(start 148.118 91.909268)
		(mid 148.161934 91.803202)
		(end 148.268 91.759268)
		(width 0.155)
		(layer "F.Cu")
		(net 103)
	)
	(arc
		(start 153.992 92.750981)
		(mid 154.038863 92.864118)
		(end 154.152 92.910981)
		(width 0.155)
		(layer "F.Cu")
		(net 103)
	)
	(arc
		(start 152.352 91.213019)
		(mid 152.663127 91.341892)
		(end 152.792 91.653019)
		(width 0.155)
		(layer "F.Cu")
		(net 103)
	)
	(arc
		(start 148.268 91.759268)
		(mid 148.374066 91.803202)
		(end 148.418 91.909268)
		(width 0.155)
		(layer "F.Cu")
		(net 103)
	)
	(arc
		(start 152.792 92.750981)
		(mid 152.838863 92.864118)
		(end 152.952 92.910981)
		(width 0.155)
		(layer "F.Cu")
		(net 103)
	)
	(arc
		(start 154.312 92.502)
		(mid 154.440873 92.190873)
		(end 154.752 92.062)
		(width 0.155)
		(layer "F.Cu")
		(net 103)
	)
	(arc
		(start 149.018 91.912)
		(mid 149.061934 92.018066)
		(end 149.168 92.062)
		(width 0.155)
		(layer "F.Cu")
		(net 103)
	)
	(arc
		(start 148.718 91.909268)
		(mid 148.761934 91.803202)
		(end 148.868 91.759268)
		(width 0.155)
		(layer "F.Cu")
		(net 103)
	)
	(arc
		(start 148.418 91.912)
		(mid 148.461934 92.018066)
		(end 148.568 92.062)
		(width 0.155)
		(layer "F.Cu")
		(net 103)
	)
	(arc
		(start 148.868 91.759268)
		(mid 148.974066 91.803202)
		(end 149.018 91.909268)
		(width 0.155)
		(layer "F.Cu")
		(net 103)
	)
	(arc
		(start 151.752 92.062)
		(mid 151.865137 92.015137)
		(end 151.912 91.902)
		(width 0.155)
		(layer "F.Cu")
		(net 103)
	)
	(arc
		(start 154.152 92.910981)
		(mid 154.265137 92.864118)
		(end 154.312 92.750981)
		(width 0.155)
		(layer "F.Cu")
		(net 103)
	)
	(segment
		(start 175.129354 80.355504)
		(end 175.11994 80.364917)
		(width 0.155)
		(layer "B.Cu")
		(net 103)
	)
	(segment
		(start 175.11994 80.841065)
		(end 175.11994 80.841066)
		(width 0.155)
		(layer "B.Cu")
		(net 103)
	)
	(segment
		(start 175.569793 79.104264)
		(end 175.882 79.416471)
		(width 0.155)
		(layer "B.Cu")
		(net 103)
	)
	(segment
		(start 168.098 84.25)
		(end 168.098 85.93)
		(width 0.155)
		(layer "B.Cu")
		(net 103)
	)
	(segment
		(start 175.882 79.416471)
		(end 175.882 80.07901)
		(width 0.155)
		(layer "B.Cu")
		(net 103)
	)
	(segment
		(start 166.898 84.25)
		(end 166.898 84.79)
		(width 0.155)
		(layer "B.Cu")
		(net 103)
	)
	(segment
		(start 175.255129 79.104264)
		(end 175.569793 79.104264)
		(width 0.155)
		(layer "B.Cu")
		(net 103)
	)
	(segment
		(start 166.0845 84.95)
		(end 165.862 84.7275)
		(width 0.155)
		(layer "B.Cu")
		(net 103)
	)
	(segment
		(start 166.738 84.95)
		(end 166.0845 84.95)
		(width 0.155)
		(layer "B.Cu")
		(net 103)
	)
	(segment
		(start 175.11053 80.850479)
		(end 171.01101 84.95)
		(width 0.155)
		(layer "B.Cu")
		(net 103)
	)
	(segment
		(start 175.129355 80.355504)
		(end 175.129354 80.355504)
		(width 0.155)
		(layer "B.Cu")
		(net 103)
	)
	(segment
		(start 167.778 85.93)
		(end 167.778 84.25)
		(width 0.155)
		(layer "B.Cu")
		(net 103)
	)
	(segment
		(start 175.367429 80.355505)
		(end 175.36743 80.355505)
		(width 0.155)
		(layer "B.Cu")
		(net 103)
	)
	(segment
		(start 171.01101 84.95)
		(end 169.138 84.95)
		(width 0.155)
		(layer "B.Cu")
		(net 103)
	)
	(segment
		(start 175.882 80.07901)
		(end 175.605505 80.355505)
		(width 0.155)
		(layer "B.Cu")
		(net 103)
	)
	(segment
		(start 175.11994 80.841066)
		(end 175.11053 80.850479)
		(width 0.155)
		(layer "B.Cu")
		(net 103)
	)
	(segment
		(start 175.119941 80.602992)
		(end 175.11994 80.602991)
		(width 0.155)
		(layer "B.Cu")
		(net 103)
	)
	(segment
		(start 175.36743 80.355505)
		(end 175.367429 80.355504)
		(width 0.155)
		(layer "B.Cu")
		(net 103)
	)
	(segment
		(start 168.978 84.79)
		(end 168.978 84.25)
		(width 0.155)
		(layer "B.Cu")
		(net 103)
	)
	(arc
		(start 169.138 84.95)
		(mid 169.024863 84.903137)
		(end 168.978 84.79)
		(width 0.155)
		(layer "B.Cu")
		(net 103)
	)
	(arc
		(start 175.11994 80.364917)
		(mid 175.070634 80.483955)
		(end 175.119941 80.602992)
		(width 0.155)
		(layer "B.Cu")
		(net 103)
	)
	(arc
		(start 175.605505 80.355505)
		(mid 175.486467 80.404812)
		(end 175.367429 80.355505)
		(width 0.155)
		(layer "B.Cu")
		(net 103)
	)
	(arc
		(start 167.938 86.09)
		(mid 167.824863 86.043137)
		(end 167.778 85.93)
		(width 0.155)
		(layer "B.Cu")
		(net 103)
	)
	(arc
		(start 168.978 84.25)
		(mid 168.849127 83.938873)
		(end 168.538 83.81)
		(width 0.155)
		(layer "B.Cu")
		(net 103)
	)
	(arc
		(start 166.898 84.79)
		(mid 166.851137 84.903137)
		(end 166.738 84.95)
		(width 0.155)
		(layer "B.Cu")
		(net 103)
	)
	(arc
		(start 175.367429 80.355504)
		(mid 175.248392 80.306197)
		(end 175.129355 80.355504)
		(width 0.155)
		(layer "B.Cu")
		(net 103)
	)
	(arc
		(start 175.11994 80.602991)
		(mid 175.169247 80.722028)
		(end 175.11994 80.841065)
		(width 0.155)
		(layer "B.Cu")
		(net 103)
	)
	(arc
		(start 167.778 84.25)
		(mid 167.649127 83.938873)
		(end 167.338 83.81)
		(width 0.155)
		(layer "B.Cu")
		(net 103)
	)
	(arc
		(start 167.338 83.81)
		(mid 167.026873 83.938873)
		(end 166.898 84.25)
		(width 0.155)
		(layer "B.Cu")
		(net 103)
	)
	(arc
		(start 168.098 85.93)
		(mid 168.051137 86.043137)
		(end 167.938 86.09)
		(width 0.155)
		(layer "B.Cu")
		(net 103)
	)
	(arc
		(start 168.538 83.81)
		(mid 168.226873 83.938873)
		(end 168.098 84.25)
		(width 0.155)
		(layer "B.Cu")
		(net 103)
	)
	(segment
		(start 144.513 87.81499)
		(end 144.894 88.19599)
		(width 0.155)
		(layer "F.Cu")
		(net 104)
	)
	(segment
		(start 181.686495 79.235)
		(end 183.016495 80.565)
		(width 0.155)
		(layer "F.Cu")
		(net 104)
	)
	(segment
		(start 175.767783 78.59161)
		(end 175.767783 78.906274)
		(width 0.155)
		(layer "F.Cu")
		(net 104)
	)
	(segment
		(start 157.98998 92.342)
		(end 165.10198 85.23)
		(width 0.155)
		(layer "F.Cu")
		(net 104)
	)
	(segment
		(start 144.894 89.79098)
		(end 147.44502 92.342)
		(width 0.155)
		(layer "F.Cu")
		(net 104)
	)
	(segment
		(start 154.592 92.750981)
		(end 154.592 92.502)
		(width 0.155)
		(layer "F.Cu")
		(net 104)
	)
	(segment
		(start 153.392 92.750981)
		(end 153.392 92.342)
		(width 0.155)
		(layer "F.Cu")
		(net 104)
	)
	(segment
		(start 183.016495 80.565)
		(end 183.798505 80.565)
		(width 0.155)
		(layer "F.Cu")
		(net 104)
	)
	(segment
		(start 144.513 86.295965)
		(end 144.513 87.81499)
		(width 0.155)
		(layer "F.Cu")
		(net 104)
	)
	(segment
		(start 154.752 92.342)
		(end 157.117608 92.342)
		(width 0.155)
		(layer "F.Cu")
		(net 104)
	)
	(segment
		(start 153.392 92.342)
		(end 153.392 91.653019)
		(width 0.155)
		(layer "F.Cu")
		(net 104)
	)
	(segment
		(start 152.192 91.902)
		(end 152.192 91.653019)
		(width 0.155)
		(layer "F.Cu")
		(net 104)
	)
	(segment
		(start 147.44502 92.342)
		(end 151.752 92.342)
		(width 0.155)
		(layer "F.Cu")
		(net 104)
	)
	(segment
		(start 145.011557 85.797408)
		(end 144.513 86.295965)
		(width 0.155)
		(layer "F.Cu")
		(net 104)
	)
	(segment
		(start 153.712 92.062)
		(end 153.712 92.750981)
		(width 0.155)
		(layer "F.Cu")
		(net 104)
	)
	(segment
		(start 152.512 91.653019)
		(end 152.512 91.902)
		(width 0.155)
		(layer "F.Cu")
		(net 104)
	)
	(segment
		(start 165.6395 85.23)
		(end 165.862 85.4525)
		(width 0.155)
		(layer "F.Cu")
		(net 104)
	)
	(segment
		(start 152.512 91.902)
		(end 152.512 92.750981)
		(width 0.155)
		(layer "F.Cu")
		(net 104)
	)
	(segment
		(start 175.767783 78.906274)
		(end 176.096509 79.235)
		(width 0.155)
		(layer "F.Cu")
		(net 104)
	)
	(segment
		(start 183.798505 80.565)
		(end 183.908505 80.455)
		(width 0.155)
		(layer "F.Cu")
		(net 104)
	)
	(segment
		(start 153.712 91.653019)
		(end 153.712 92.062)
		(width 0.155)
		(layer "F.Cu")
		(net 104)
	)
	(segment
		(start 165.10198 85.23)
		(end 165.6395 85.23)
		(width 0.155)
		(layer "F.Cu")
		(net 104)
	)
	(segment
		(start 144.894 88.19599)
		(end 144.894 89.79098)
		(width 0.155)
		(layer "F.Cu")
		(net 104)
	)
	(segment
		(start 145.011557 85.641844)
		(end 145.011557 85.797408)
		(width 0.155)
		(layer "F.Cu")
		(net 104)
	)
	(segment
		(start 176.096509 79.235)
		(end 181.686495 79.235)
		(width 0.155)
		(layer "F.Cu")
		(net 104)
	)
	(segment
		(start 157.117608 92.342)
		(end 157.98998 92.342)
		(width 0.155)
		(layer "F.Cu")
		(net 104)
	)
	(via
		(at 165.862 85.4525)
		(size 0.6)
		(drill 0.35)
		(layers "F.Cu" "B.Cu")
		(net 104)
	)
	(via
		(at 175.767783 78.59161)
		(size 0.6)
		(drill 0.35)
		(layers "F.Cu" "B.Cu")
		(net 104)
	)
	(arc
		(start 151.752 92.342)
		(mid 152.063127 92.213127)
		(end 152.192 91.902)
		(width 0.155)
		(layer "F.Cu")
		(net 104)
	)
	(arc
		(start 153.712 92.750981)
		(mid 153.840873 93.062108)
		(end 154.152 93.190981)
		(width 0.155)
		(layer "F.Cu")
		(net 104)
	)
	(arc
		(start 154.592 92.502)
		(mid 154.638863 92.388863)
		(end 154.752 92.342)
		(width 0.155)
		(layer "F.Cu")
		(net 104)
	)
	(arc
		(start 153.552 91.493019)
		(mid 153.665137 91.539882)
		(end 153.712 91.653019)
		(width 0.155)
		(layer "F.Cu")
		(net 104)
	)
	(arc
		(start 153.392 91.653019)
		(mid 153.438863 91.539882)
		(end 153.552 91.493019)
		(width 0.155)
		(layer "F.Cu")
		(net 104)
	)
	(arc
		(start 152.512 92.750981)
		(mid 152.640873 93.062108)
		(end 152.952 93.190981)
		(width 0.155)
		(layer "F.Cu")
		(net 104)
	)
	(arc
		(start 152.352 91.493019)
		(mid 152.465137 91.539882)
		(end 152.512 91.653019)
		(width 0.155)
		(layer "F.Cu")
		(net 104)
	)
	(arc
		(start 152.952 93.190981)
		(mid 153.263127 93.062108)
		(end 153.392 92.750981)
		(width 0.155)
		(layer "F.Cu")
		(net 104)
	)
	(arc
		(start 152.192 91.653019)
		(mid 152.238863 91.539882)
		(end 152.352 91.493019)
		(width 0.155)
		(layer "F.Cu")
		(net 104)
	)
	(arc
		(start 154.152 93.190981)
		(mid 154.463127 93.062108)
		(end 154.592 92.750981)
		(width 0.155)
		(layer "F.Cu")
		(net 104)
	)
	(segment
		(start 165.862 85.4525)
		(end 166.0845 85.23)
		(width 0.155)
		(layer "B.Cu")
		(net 104)
	)
	(segment
		(start 167.498 84.25)
		(end 167.498 84.79)
		(width 0.155)
		(layer "B.Cu")
		(net 104)
	)
	(segment
		(start 176.162 79.300491)
		(end 175.767783 78.906274)
		(width 0.155)
		(layer "B.Cu")
		(net 104)
	)
	(segment
		(start 168.378 85.93)
		(end 168.378 85.23)
		(width 0.155)
		(layer "B.Cu")
		(net 104)
	)
	(segment
		(start 169.138 85.23)
		(end 169.913439 85.23)
		(width 0.155)
		(layer "B.Cu")
		(net 104)
	)
	(segment
		(start 168.378 85.23)
		(end 168.378 84.25)
		(width 0.155)
		(layer "B.Cu")
		(net 104)
	)
	(segment
		(start 167.498 84.79)
		(end 167.498 85.93)
		(width 0.155)
		(layer "B.Cu")
		(net 104)
	)
	(segment
		(start 171.12699 85.23)
		(end 176.162 80.19499)
		(width 0.155)
		(layer "B.Cu")
		(net 104)
	)
	(segment
		(start 169.913439 85.23)
		(end 171.12699 85.23)
		(width 0.155)
		(layer "B.Cu")
		(net 104)
	)
	(segment
		(start 167.178 84.79)
		(end 167.178 84.25)
		(width 0.155)
		(layer "B.Cu")
		(net 104)
	)
	(segment
		(start 168.698 84.25)
		(end 168.698 84.79)
		(width 0.155)
		(layer "B.Cu")
		(net 104)
	)
	(segment
		(start 166.0845 85.23)
		(end 166.738 85.23)
		(width 0.155)
		(layer "B.Cu")
		(net 104)
	)
	(segment
		(start 176.162 80.19499)
		(end 176.162 79.300491)
		(width 0.155)
		(layer "B.Cu")
		(net 104)
	)
	(segment
		(start 175.767783 78.906274)
		(end 175.767783 78.59161)
		(width 0.155)
		(layer "B.Cu")
		(net 104)
	)
	(arc
		(start 166.738 85.23)
		(mid 167.049127 85.101127)
		(end 167.178 84.79)
		(width 0.155)
		(layer "B.Cu")
		(net 104)
	)
	(arc
		(start 168.378 84.25)
		(mid 168.424863 84.136863)
		(end 168.538 84.09)
		(width 0.155)
		(layer "B.Cu")
		(net 104)
	)
	(arc
		(start 167.178 84.25)
		(mid 167.224863 84.136863)
		(end 167.338 84.09)
		(width 0.155)
		(layer "B.Cu")
		(net 104)
	)
	(arc
		(start 167.498 85.93)
		(mid 167.626873 86.241127)
		(end 167.938 86.37)
		(width 0.155)
		(layer "B.Cu")
		(net 104)
	)
	(arc
		(start 168.698 84.79)
		(mid 168.826873 85.101127)
		(end 169.138 85.23)
		(width 0.155)
		(layer "B.Cu")
		(net 104)
	)
	(arc
		(start 167.938 86.37)
		(mid 168.249127 86.241127)
		(end 168.378 85.93)
		(width 0.155)
		(layer "B.Cu")
		(net 104)
	)
	(arc
		(start 168.538 84.09)
		(mid 168.651137 84.136863)
		(end 168.698 84.25)
		(width 0.155)
		(layer "B.Cu")
		(net 104)
	)
	(arc
		(start 167.338 84.09)
		(mid 167.451137 84.136863)
		(end 167.498 84.25)
		(width 0.155)
		(layer "B.Cu")
		(net 104)
	)
	(segment
		(start 157.47307 82.093872)
		(end 156.285129 80.905931)
		(width 0.155)
		(layer "F.Cu")
		(net 105)
	)
	(segment
		(start 182.17599 77.356)
		(end 183.20899 76.323)
		(width 0.155)
		(layer "F.Cu")
		(net 105)
	)
	(segment
		(start 159.06113 78.092)
		(end 158.43801 78.092)
		(width 0.155)
		(layer "F.Cu")
		(net 105)
	)
	(segment
		(start 157.317506 81.48576)
		(end 157.699344 81.867598)
		(width 0.155)
		(layer "F.Cu")
		(net 105)
	)
	(segment
		(start 162.814628 76.713282)
		(end 163.129292 76.713282)
		(width 0.155)
		(layer "F.Cu")
		(net 105)
	)
	(segment
		(start 165.305 77.788928)
		(end 165.305 77.496)
		(width 0.155)
		(layer "F.Cu")
		(net 105)
	)
	(segment
		(start 155.196184 82.984823)
		(end 154.88201 83.299)
		(width 0.155)
		(layer "F.Cu")
		(net 105)
	)
	(segment
		(start 158.43801 78.092)
		(end 157.594 78.93601)
		(width 0.155)
		(layer "F.Cu")
		(net 105)
	)
	(segment
		(start 154.814347 82.376712)
		(end 155.196184 82.758549)
		(width 0.155)
		(layer "F.Cu")
		(net 105)
	)
	(segment
		(start 154.88201 83.299)
		(end 151.262889 83.299)
		(width 0.155)
		(layer "F.Cu")
		(net 105)
	)
	(segment
		(start 157.594 78.93601)
		(end 157.594 80.58701)
		(width 0.155)
		(layer "F.Cu")
		(net 105)
	)
	(segment
		(start 156.624541 82.942399)
		(end 155.436601 81.754459)
		(width 0.155)
		(layer "F.Cu")
		(net 105)
	)
	(segment
		(start 166.005 77.356)
		(end 167.657962 77.356)
		(width 0.155)
		(layer "F.Cu")
		(net 105)
	)
	(segment
		(start 154.814347 82.376711)
		(end 154.814347 82.376712)
		(width 0.155)
		(layer "F.Cu")
		(net 105)
	)
	(segment
		(start 155.662875 81.528183)
		(end 155.662875 81.528184)
		(width 0.155)
		(layer "F.Cu")
		(net 105)
	)
	(segment
		(start 159.28363 77.8695)
		(end 159.06113 78.092)
		(width 0.155)
		(layer "F.Cu")
		(net 105)
	)
	(segment
		(start 157.594 80.58701)
		(end 157.317506 80.863506)
		(width 0.155)
		(layer "F.Cu")
		(net 105)
	)
	(segment
		(start 165.585 76.643072)
		(end 165.585 76.936)
		(width 0.155)
		(layer "F.Cu")
		(net 105)
	)
	(segment
		(start 150.933577 82.969688)
		(end 150.933577 82.814124)
		(width 0.155)
		(layer "F.Cu")
		(net 105)
	)
	(segment
		(start 151.262889 83.299)
		(end 150.933577 82.969688)
		(width 0.155)
		(layer "F.Cu")
		(net 105)
	)
	(segment
		(start 163.77201 77.356)
		(end 164.325 77.356)
		(width 0.155)
		(layer "F.Cu")
		(net 105)
	)
	(segment
		(start 164.465 77.496)
		(end 164.465 77.788928)
		(width 0.155)
		(layer "F.Cu")
		(net 105)
	)
	(segment
		(start 155.662875 81.528184)
		(end 156.850815 82.716125)
		(width 0.155)
		(layer "F.Cu")
		(net 105)
	)
	(segment
		(start 183.776 76.323)
		(end 183.886 76.433)
		(width 0.155)
		(layer "F.Cu")
		(net 105)
	)
	(segment
		(start 165.305 77.496)
		(end 165.305 76.643072)
		(width 0.155)
		(layer "F.Cu")
		(net 105)
	)
	(segment
		(start 183.20899 76.323)
		(end 183.776 76.323)
		(width 0.155)
		(layer "F.Cu")
		(net 105)
	)
	(segment
		(start 167.657962 77.356)
		(end 182.17599 77.356)
		(width 0.155)
		(layer "F.Cu")
		(net 105)
	)
	(segment
		(start 163.129292 76.713282)
		(end 163.77201 77.356)
		(width 0.155)
		(layer "F.Cu")
		(net 105)
	)
	(via
		(at 162.814628 76.713282)
		(size 0.6)
		(drill 0.35)
		(layers "F.Cu" "B.Cu")
		(net 105)
	)
	(via
		(at 159.28363 77.8695)
		(size 0.6)
		(drill 0.35)
		(layers "F.Cu" "B.Cu")
		(net 105)
	)
	(arc
		(start 156.850815 82.716125)
		(mid 156.897678 82.829262)
		(end 156.850815 82.942399)
		(width 0.155)
		(layer "F.Cu")
		(net 105)
	)
	(arc
		(start 164.885 78.208928)
		(mid 165.181985 78.085913)
		(end 165.305 77.788928)
		(width 0.155)
		(layer "F.Cu")
		(net 105)
	)
	(arc
		(start 156.285129 80.905931)
		(mid 155.974002 80.777058)
		(end 155.662875 80.905931)
		(width 0.155)
		(layer "F.Cu")
		(net 105)
	)
	(arc
		(start 155.662875 80.905931)
		(mid 155.534002 81.217057)
		(end 155.662875 81.528183)
		(width 0.155)
		(layer "F.Cu")
		(net 105)
	)
	(arc
		(start 157.317506 80.863506)
		(mid 157.188633 81.174633)
		(end 157.317506 81.48576)
		(width 0.155)
		(layer "F.Cu")
		(net 105)
	)
	(arc
		(start 165.445 76.503072)
		(mid 165.543995 76.544077)
		(end 165.585 76.643072)
		(width 0.155)
		(layer "F.Cu")
		(net 105)
	)
	(arc
		(start 157.699344 81.867598)
		(mid 157.746207 81.980735)
		(end 157.699344 82.093872)
		(width 0.155)
		(layer "F.Cu")
		(net 105)
	)
	(arc
		(start 165.305 76.643072)
		(mid 165.346005 76.544077)
		(end 165.445 76.503072)
		(width 0.155)
		(layer "F.Cu")
		(net 105)
	)
	(arc
		(start 155.436601 81.754459)
		(mid 155.125474 81.625586)
		(end 154.814347 81.754459)
		(width 0.155)
		(layer "F.Cu")
		(net 105)
	)
	(arc
		(start 164.465 77.788928)
		(mid 164.588015 78.085913)
		(end 164.885 78.208928)
		(width 0.155)
		(layer "F.Cu")
		(net 105)
	)
	(arc
		(start 155.196184 82.758549)
		(mid 155.243047 82.871686)
		(end 155.196184 82.984823)
		(width 0.155)
		(layer "F.Cu")
		(net 105)
	)
	(arc
		(start 157.699344 82.093872)
		(mid 157.586207 82.140735)
		(end 157.47307 82.093872)
		(width 0.155)
		(layer "F.Cu")
		(net 105)
	)
	(arc
		(start 164.325 77.356)
		(mid 164.423995 77.397005)
		(end 164.465 77.496)
		(width 0.155)
		(layer "F.Cu")
		(net 105)
	)
	(arc
		(start 165.585 76.936)
		(mid 165.708015 77.232985)
		(end 166.005 77.356)
		(width 0.155)
		(layer "F.Cu")
		(net 105)
	)
	(arc
		(start 154.814347 81.754459)
		(mid 154.685474 82.065585)
		(end 154.814347 82.376711)
		(width 0.155)
		(layer "F.Cu")
		(net 105)
	)
	(arc
		(start 156.850815 82.942399)
		(mid 156.737678 82.989262)
		(end 156.624541 82.942399)
		(width 0.155)
		(layer "F.Cu")
		(net 105)
	)
	(segment
		(start 161.493 78.092)
		(end 161.176 78.092)
		(width 0.155)
		(layer "B.Cu")
		(net 105)
	)
	(segment
		(start 163.309 76.89299)
		(end 163.309 77.41201)
		(width 0.155)
		(layer "B.Cu")
		(net 105)
	)
	(segment
		(start 163.309 77.41201)
		(end 162.62901 78.092)
		(width 0.155)
		(layer "B.Cu")
		(net 105)
	)
	(segment
		(start 160.136 77.392)
		(end 160.136 77.932)
		(width 0.155)
		(layer "B.Cu")
		(net 105)
	)
	(segment
		(start 159.50613 78.092)
		(end 159.28363 77.8695)
		(width 0.155)
		(layer "B.Cu")
		(net 105)
	)
	(segment
		(start 162.62901 78.092)
		(end 162.293 78.092)
		(width 0.155)
		(layer "B.Cu")
		(net 105)
	)
	(segment
		(start 162.093 77.892)
		(end 162.093 77.7609)
		(width 0.155)
		(layer "B.Cu")
		(net 105)
	)
	(segment
		(start 161.693 77.7609)
		(end 161.693 77.892)
		(width 0.155)
		(layer "B.Cu")
		(net 105)
	)
	(segment
		(start 159.976 78.092)
		(end 159.50613 78.092)
		(width 0.155)
		(layer "B.Cu")
		(net 105)
	)
	(segment
		(start 162.814628 76.713282)
		(end 163.129292 76.713282)
		(width 0.155)
		(layer "B.Cu")
		(net 105)
	)
	(segment
		(start 161.016 77.932)
		(end 161.016 77.392)
		(width 0.155)
		(layer "B.Cu")
		(net 105)
	)
	(segment
		(start 163.129292 76.713282)
		(end 163.309 76.89299)
		(width 0.155)
		(layer "B.Cu")
		(net 105)
	)
	(arc
		(start 160.136 77.932)
		(mid 160.089137 78.045137)
		(end 159.976 78.092)
		(width 0.155)
		(layer "B.Cu")
		(net 105)
	)
	(arc
		(start 162.293 78.092)
		(mid 162.151579 78.033421)
		(end 162.093 77.892)
		(width 0.155)
		(layer "B.Cu")
		(net 105)
	)
	(arc
		(start 161.176 78.092)
		(mid 161.062863 78.045137)
		(end 161.016 77.932)
		(width 0.155)
		(layer "B.Cu")
		(net 105)
	)
	(arc
		(start 161.893 77.5609)
		(mid 161.751579 77.619479)
		(end 161.693 77.7609)
		(width 0.155)
		(layer "B.Cu")
		(net 105)
	)
	(arc
		(start 161.016 77.392)
		(mid 160.887127 77.080873)
		(end 160.576 76.952)
		(width 0.155)
		(layer "B.Cu")
		(net 105)
	)
	(arc
		(start 162.093 77.7609)
		(mid 162.034421 77.619479)
		(end 161.893 77.5609)
		(width 0.155)
		(layer "B.Cu")
		(net 105)
	)
	(arc
		(start 160.576 76.952)
		(mid 160.264873 77.080873)
		(end 160.136 77.392)
		(width 0.155)
		(layer "B.Cu")
		(net 105)
	)
	(arc
		(start 161.693 77.892)
		(mid 161.634421 78.033421)
		(end 161.493 78.092)
		(width 0.155)
		(layer "B.Cu")
		(net 105)
	)
	(segment
		(start 165.025 77.788928)
		(end 165.025 77.496)
		(width 0.155)
		(layer "F.Cu")
		(net 106)
	)
	(segment
		(start 183.776 76.043)
		(end 183.886 75.933)
		(width 0.155)
		(layer "F.Cu")
		(net 106)
	)
	(segment
		(start 157.515495 81.061495)
		(end 157.874 80.70299)
		(width 0.155)
		(layer "F.Cu")
		(net 106)
	)
	(segment
		(start 183.09301 76.043)
		(end 183.776 76.043)
		(width 0.155)
		(layer "F.Cu")
		(net 106)
	)
	(segment
		(start 150.580023 83.167678)
		(end 150.735587 83.167678)
		(width 0.155)
		(layer "F.Cu")
		(net 106)
	)
	(segment
		(start 158.55399 78.372)
		(end 159.06113 78.372)
		(width 0.155)
		(layer "F.Cu")
		(net 106)
	)
	(segment
		(start 159.06113 78.372)
		(end 159.28363 78.5945)
		(width 0.155)
		(layer "F.Cu")
		(net 106)
	)
	(segment
		(start 157.897332 81.669609)
		(end 157.515494 81.287771)
		(width 0.155)
		(layer "F.Cu")
		(net 106)
	)
	(segment
		(start 164.745 77.496)
		(end 164.745 77.788928)
		(width 0.155)
		(layer "F.Cu")
		(net 106)
	)
	(segment
		(start 163.327282 76.515292)
		(end 163.88799 77.076)
		(width 0.155)
		(layer "F.Cu")
		(net 106)
	)
	(segment
		(start 157.048805 82.518135)
		(end 155.860865 81.330195)
		(width 0.155)
		(layer "F.Cu")
		(net 106)
	)
	(segment
		(start 157.874 80.70299)
		(end 157.874 79.05199)
		(width 0.155)
		(layer "F.Cu")
		(net 106)
	)
	(segment
		(start 157.27508 82.291862)
		(end 157.27508 82.291863)
		(width 0.155)
		(layer "F.Cu")
		(net 106)
	)
	(segment
		(start 154.99799 83.579)
		(end 155.394174 83.182814)
		(width 0.155)
		(layer "F.Cu")
		(net 106)
	)
	(segment
		(start 156.426551 83.14039)
		(end 156.426553 83.140389)
		(width 0.155)
		(layer "F.Cu")
		(net 106)
	)
	(segment
		(start 155.394174 82.56056)
		(end 155.012337 82.178723)
		(width 0.155)
		(layer "F.Cu")
		(net 106)
	)
	(segment
		(start 165.025 77.496)
		(end 165.025 76.643072)
		(width 0.155)
		(layer "F.Cu")
		(net 106)
	)
	(segment
		(start 156.087139 81.103921)
		(end 157.27508 82.291862)
		(width 0.155)
		(layer "F.Cu")
		(net 106)
	)
	(segment
		(start 163.327282 76.200628)
		(end 163.327282 76.515292)
		(width 0.155)
		(layer "F.Cu")
		(net 106)
	)
	(segment
		(start 163.88799 77.076)
		(end 164.325 77.076)
		(width 0.155)
		(layer "F.Cu")
		(net 106)
	)
	(segment
		(start 166.005 77.076)
		(end 167.657962 77.076)
		(width 0.155)
		(layer "F.Cu")
		(net 106)
	)
	(segment
		(start 167.657962 77.076)
		(end 182.06001 77.076)
		(width 0.155)
		(layer "F.Cu")
		(net 106)
	)
	(segment
		(start 165.865 76.643072)
		(end 165.865 76.936)
		(width 0.155)
		(layer "F.Cu")
		(net 106)
	)
	(segment
		(start 182.06001 77.076)
		(end 183.09301 76.043)
		(width 0.155)
		(layer "F.Cu")
		(net 106)
	)
	(segment
		(start 151.146909 83.579)
		(end 154.99799 83.579)
		(width 0.155)
		(layer "F.Cu")
		(net 106)
	)
	(segment
		(start 157.515494 81.287771)
		(end 157.515495 81.287771)
		(width 0.155)
		(layer "F.Cu")
		(net 106)
	)
	(segment
		(start 155.238611 81.952449)
		(end 156.426551 83.14039)
		(width 0.155)
		(layer "F.Cu")
		(net 106)
	)
	(segment
		(start 157.874 79.05199)
		(end 158.55399 78.372)
		(width 0.155)
		(layer "F.Cu")
		(net 106)
	)
	(segment
		(start 150.735587 83.167678)
		(end 151.146909 83.579)
		(width 0.155)
		(layer "F.Cu")
		(net 106)
	)
	(via
		(at 163.327282 76.200628)
		(size 0.6)
		(drill 0.35)
		(layers "F.Cu" "B.Cu")
		(net 106)
	)
	(via
		(at 159.28363 78.5945)
		(size 0.6)
		(drill 0.35)
		(layers "F.Cu" "B.Cu")
		(net 106)
	)
	(arc
		(start 164.885 77.928928)
		(mid 164.983995 77.887923)
		(end 165.025 77.788928)
		(width 0.155)
		(layer "F.Cu")
		(net 106)
	)
	(arc
		(start 155.860865 81.330195)
		(mid 155.814002 81.217058)
		(end 155.860865 81.103921)
		(width 0.155)
		(layer "F.Cu")
		(net 106)
	)
	(arc
		(start 165.865 76.936)
		(mid 165.906005 77.034995)
		(end 166.005 77.076)
		(width 0.155)
		(layer "F.Cu")
		(net 106)
	)
	(arc
		(start 164.745 77.788928)
		(mid 164.786005 77.887923)
		(end 164.885 77.928928)
		(width 0.155)
		(layer "F.Cu")
		(net 106)
	)
	(arc
		(start 155.012337 82.178723)
		(mid 154.965474 82.065586)
		(end 155.012337 81.952449)
		(width 0.155)
		(layer "F.Cu")
		(net 106)
	)
	(arc
		(start 165.445 76.223072)
		(mid 165.741985 76.346087)
		(end 165.865 76.643072)
		(width 0.155)
		(layer "F.Cu")
		(net 106)
	)
	(arc
		(start 155.394174 83.182814)
		(mid 155.523047 82.871687)
		(end 155.394174 82.56056)
		(width 0.155)
		(layer "F.Cu")
		(net 106)
	)
	(arc
		(start 157.897332 82.291863)
		(mid 158.026205 81.980736)
		(end 157.897332 81.669609)
		(width 0.155)
		(layer "F.Cu")
		(net 106)
	)
	(arc
		(start 157.27508 82.291863)
		(mid 157.586207 82.420735)
		(end 157.897332 82.291863)
		(width 0.155)
		(layer "F.Cu")
		(net 106)
	)
	(arc
		(start 157.515495 81.287771)
		(mid 157.468631 81.174634)
		(end 157.515495 81.061495)
		(width 0.155)
		(layer "F.Cu")
		(net 106)
	)
	(arc
		(start 155.012337 81.952449)
		(mid 155.125474 81.905586)
		(end 155.238611 81.952449)
		(width 0.155)
		(layer "F.Cu")
		(net 106)
	)
	(arc
		(start 164.325 77.076)
		(mid 164.621985 77.199015)
		(end 164.745 77.496)
		(width 0.155)
		(layer "F.Cu")
		(net 106)
	)
	(arc
		(start 165.025 76.643072)
		(mid 165.148015 76.346087)
		(end 165.445 76.223072)
		(width 0.155)
		(layer "F.Cu")
		(net 106)
	)
	(arc
		(start 155.860865 81.103921)
		(mid 155.974002 81.057058)
		(end 156.087139 81.103921)
		(width 0.155)
		(layer "F.Cu")
		(net 106)
	)
	(arc
		(start 157.048805 83.140389)
		(mid 157.177678 82.829262)
		(end 157.048805 82.518135)
		(width 0.155)
		(layer "F.Cu")
		(net 106)
	)
	(arc
		(start 156.426553 83.140389)
		(mid 156.737678 83.269263)
		(end 157.048805 83.140389)
		(width 0.155)
		(layer "F.Cu")
		(net 106)
	)
	(segment
		(start 163.327282 76.200628)
		(end 163.327282 76.515292)
		(width 0.155)
		(layer "B.Cu")
		(net 106)
	)
	(segment
		(start 159.707926 78.372)
		(end 159.50613 78.372)
		(width 0.155)
		(layer "B.Cu")
		(net 106)
	)
	(segment
		(start 160.736 77.932)
		(end 160.736 77.392)
		(width 0.155)
		(layer "B.Cu")
		(net 106)
	)
	(segment
		(start 163.589 76.77701)
		(end 163.589 77.52799)
		(width 0.155)
		(layer "B.Cu")
		(net 106)
	)
	(segment
		(start 159.976 78.372)
		(end 159.707926 78.372)
		(width 0.155)
		(layer "B.Cu")
		(net 106)
	)
	(segment
		(start 159.50613 78.372)
		(end 159.28363 78.5945)
		(width 0.155)
		(layer "B.Cu")
		(net 106)
	)
	(segment
		(start 160.416 77.392)
		(end 160.416 77.932)
		(width 0.155)
		(layer "B.Cu")
		(net 106)
	)
	(segment
		(start 163.327282 76.515292)
		(end 163.589 76.77701)
		(width 0.155)
		(layer "B.Cu")
		(net 106)
	)
	(segment
		(start 163.589 77.52799)
		(end 162.74499 78.372)
		(width 0.155)
		(layer "B.Cu")
		(net 106)
	)
	(segment
		(start 162.74499 78.372)
		(end 161.176 78.372)
		(width 0.155)
		(layer "B.Cu")
		(net 106)
	)
	(arc
		(start 161.176 78.372)
		(mid 160.864873 78.243127)
		(end 160.736 77.932)
		(width 0.155)
		(layer "B.Cu")
		(net 106)
	)
	(arc
		(start 160.736 77.392)
		(mid 160.689137 77.278863)
		(end 160.576 77.232)
		(width 0.155)
		(layer "B.Cu")
		(net 106)
	)
	(arc
		(start 160.416 77.932)
		(mid 160.287127 78.243127)
		(end 159.976 78.372)
		(width 0.155)
		(layer "B.Cu")
		(net 106)
	)
	(arc
		(start 160.576 77.232)
		(mid 160.462863 77.278863)
		(end 160.416 77.392)
		(width 0.155)
		(layer "B.Cu")
		(net 106)
	)
	(segment
		(start 166.56601 75.832)
		(end 165.625149 74.891139)
		(width 0.155)
		(layer "F.Cu")
		(net 107)
	)
	(segment
		(start 182.81199 75.323)
		(end 182.30299 75.832)
		(width 0.155)
		(layer "F.Cu")
		(net 107)
	)
	(segment
		(start 154.5905 85.331)
		(end 153.21999 85.331)
		(width 0.155)
		(layer "F.Cu")
		(net 107)
	)
	(segment
		(start 183.776 75.323)
		(end 182.81199 75.323)
		(width 0.155)
		(layer "F.Cu")
		(net 107)
	)
	(segment
		(start 149.519363 84.228338)
		(end 149.519363 84.383194)
		(width 0.155)
		(layer "F.Cu")
		(net 107)
	)
	(segment
		(start 165.625149 74.891139)
		(end 165.310485 74.891139)
		(width 0.155)
		(layer "F.Cu")
		(net 107)
	)
	(segment
		(start 154.5905 85.331)
		(end 154.813 85.1085)
		(width 0.155)
		(layer "F.Cu")
		(net 107)
	)
	(segment
		(start 149.705169 84.569)
		(end 152.45799 84.569)
		(width 0.155)
		(layer "F.Cu")
		(net 107)
	)
	(segment
		(start 149.519363 84.383194)
		(end 149.705169 84.569)
		(width 0.155)
		(layer "F.Cu")
		(net 107)
	)
	(segment
		(start 183.886 75.433)
		(end 183.776 75.323)
		(width 0.155)
		(layer "F.Cu")
		(net 107)
	)
	(segment
		(start 182.30299 75.832)
		(end 166.56601 75.832)
		(width 0.155)
		(layer "F.Cu")
		(net 107)
	)
	(segment
		(start 152.45799 84.569)
		(end 153.21999 85.331)
		(width 0.155)
		(layer "F.Cu")
		(net 107)
	)
	(via
		(at 154.813 85.1085)
		(size 0.6)
		(drill 0.35)
		(layers "F.Cu" "B.Cu")
		(net 107)
	)
	(via
		(at 165.310485 74.891139)
		(size 0.6)
		(drill 0.35)
		(layers "F.Cu" "B.Cu")
		(net 107)
	)
	(segment
		(start 155.0355 85.331)
		(end 156.66001 85.331)
		(width 0.155)
		(layer "B.Cu")
		(net 107)
	)
	(segment
		(start 165.625149 74.891139)
		(end 165.310485 74.891139)
		(width 0.155)
		(layer "B.Cu")
		(net 107)
	)
	(segment
		(start 161.346622 80.644385)
		(end 162.12101 79.87)
		(width 0.155)
		(layer "B.Cu")
		(net 107)
	)
	(segment
		(start 159.753691 83.067828)
		(end 159.121172 82.435308)
		(width 0.155)
		(layer "B.Cu")
		(net 107)
	)
	(segment
		(start 157.366025 84.624984)
		(end 157.366024 84.624983)
		(width 0.155)
		(layer "B.Cu")
		(net 107)
	)
	(segment
		(start 159.960692 82.03032)
		(end 160.375947 82.445573)
		(width 0.155)
		(layer "B.Cu")
		(net 107)
	)
	(segment
		(start 162.12101 79.87)
		(end 163.77201 79.87)
		(width 0.155)
		(layer "B.Cu")
		(net 107)
	)
	(segment
		(start 158.894896 82.661584)
		(end 159.112162 82.87885)
		(width 0.155)
		(layer "B.Cu")
		(net 107)
	)
	(segment
		(start 157.549872 84.214862)
		(end 157.564015 84.229005)
		(width 0.155)
		(layer "B.Cu")
		(net 107)
	)
	(segment
		(start 156.970044 84.822973)
		(end 156.955902 84.808831)
		(width 0.155)
		(layer "B.Cu")
		(net 107)
	)
	(segment
		(start 157.366025 84.624985)
		(end 157.366025 84.624984)
		(width 0.155)
		(layer "B.Cu")
		(net 107)
	)
	(segment
		(start 159.112162 82.87885)
		(end 159.527417 83.294103)
		(width 0.155)
		(layer "B.Cu")
		(net 107)
	)
	(segment
		(start 161.450751 81.370767)
		(end 161.450751 81.370768)
		(width 0.155)
		(layer "B.Cu")
		(net 107)
	)
	(segment
		(start 156.955902 84.808831)
		(end 156.955902 84.80883)
		(width 0.155)
		(layer "B.Cu")
		(net 107)
	)
	(segment
		(start 154.813 85.1085)
		(end 155.0355 85.331)
		(width 0.155)
		(layer "B.Cu")
		(net 107)
	)
	(segment
		(start 163.77201 79.87)
		(end 166.23 77.41201)
		(width 0.155)
		(layer "B.Cu")
		(net 107)
	)
	(segment
		(start 159.743426 81.813054)
		(end 159.960692 82.03032)
		(width 0.155)
		(layer "B.Cu")
		(net 107)
	)
	(segment
		(start 160.591956 80.964524)
		(end 160.809222 81.18179)
		(width 0.155)
		(layer "B.Cu")
		(net 107)
	)
	(segment
		(start 160.602221 82.219298)
		(end 159.969702 81.586778)
		(width 0.155)
		(layer "B.Cu")
		(net 107)
	)
	(segment
		(start 156.66001 85.331)
		(end 156.970044 85.020963)
		(width 0.155)
		(layer "B.Cu")
		(net 107)
	)
	(segment
		(start 157.351882 84.412851)
		(end 157.351882 84.41285)
		(width 0.155)
		(layer "B.Cu")
		(net 107)
	)
	(segment
		(start 157.366024 84.426993)
		(end 157.351882 84.412851)
		(width 0.155)
		(layer "B.Cu")
		(net 107)
	)
	(segment
		(start 161.450751 81.370768)
		(end 161.346622 81.266639)
		(width 0.155)
		(layer "B.Cu")
		(net 107)
	)
	(segment
		(start 166.23 77.41201)
		(end 166.23 75.49599)
		(width 0.155)
		(layer "B.Cu")
		(net 107)
	)
	(segment
		(start 166.23 75.49599)
		(end 165.625149 74.891139)
		(width 0.155)
		(layer "B.Cu")
		(net 107)
	)
	(segment
		(start 158.574759 84.038505)
		(end 158.678887 84.142633)
		(width 0.155)
		(layer "B.Cu")
		(net 107)
	)
	(segment
		(start 157.762005 84.229005)
		(end 157.952505 84.038505)
		(width 0.155)
		(layer "B.Cu")
		(net 107)
	)
	(segment
		(start 160.602221 82.219297)
		(end 160.602221 82.219298)
		(width 0.155)
		(layer "B.Cu")
		(net 107)
	)
	(segment
		(start 160.809222 81.18179)
		(end 161.224477 81.597043)
		(width 0.155)
		(layer "B.Cu")
		(net 107)
	)
	(segment
		(start 158.905161 83.916357)
		(end 158.905161 83.916358)
		(width 0.155)
		(layer "B.Cu")
		(net 107)
	)
	(segment
		(start 157.153892 84.610842)
		(end 157.168035 84.624985)
		(width 0.155)
		(layer "B.Cu")
		(net 107)
	)
	(segment
		(start 158.905161 83.916358)
		(end 158.272642 83.283838)
		(width 0.155)
		(layer "B.Cu")
		(net 107)
	)
	(segment
		(start 159.753691 83.067827)
		(end 159.753691 83.067828)
		(width 0.155)
		(layer "B.Cu")
		(net 107)
	)
	(arc
		(start 159.969702 80.964524)
		(mid 160.280829 80.835651)
		(end 160.591956 80.964524)
		(width 0.155)
		(layer "B.Cu")
		(net 107)
	)
	(arc
		(start 157.351882 84.41285)
		(mid 157.310877 84.313856)
		(end 157.351882 84.214862)
		(width 0.155)
		(layer "B.Cu")
		(net 107)
	)
	(arc
		(start 158.272642 83.283838)
		(mid 158.143769 82.972711)
		(end 158.272642 82.661584)
		(width 0.155)
		(layer "B.Cu")
		(net 107)
	)
	(arc
		(start 157.952505 84.038505)
		(mid 158.263632 83.909632)
		(end 158.574759 84.038505)
		(width 0.155)
		(layer "B.Cu")
		(net 107)
	)
	(arc
		(start 159.121172 81.813054)
		(mid 159.432299 81.684181)
		(end 159.743426 81.813054)
		(width 0.155)
		(layer "B.Cu")
		(net 107)
	)
	(arc
		(start 161.346622 81.266639)
		(mid 161.217749 80.955512)
		(end 161.346622 80.644385)
		(width 0.155)
		(layer "B.Cu")
		(net 107)
	)
	(arc
		(start 161.450751 81.597043)
		(mid 161.497614 81.483905)
		(end 161.450751 81.370767)
		(width 0.155)
		(layer "B.Cu")
		(net 107)
	)
	(arc
		(start 157.168035 84.624985)
		(mid 157.26703 84.66599)
		(end 157.366025 84.624985)
		(width 0.155)
		(layer "B.Cu")
		(net 107)
	)
	(arc
		(start 158.678887 84.142633)
		(mid 158.792024 84.189496)
		(end 158.905161 84.142633)
		(width 0.155)
		(layer "B.Cu")
		(net 107)
	)
	(arc
		(start 161.224477 81.597043)
		(mid 161.337614 81.643906)
		(end 161.450751 81.597043)
		(width 0.155)
		(layer "B.Cu")
		(net 107)
	)
	(arc
		(start 156.955902 84.610842)
		(mid 157.054897 84.569837)
		(end 157.153892 84.610842)
		(width 0.155)
		(layer "B.Cu")
		(net 107)
	)
	(arc
		(start 160.602221 82.445573)
		(mid 160.649084 82.332435)
		(end 160.602221 82.219297)
		(width 0.155)
		(layer "B.Cu")
		(net 107)
	)
	(arc
		(start 157.564015 84.229005)
		(mid 157.66301 84.27001)
		(end 157.762005 84.229005)
		(width 0.155)
		(layer "B.Cu")
		(net 107)
	)
	(arc
		(start 159.527417 83.294103)
		(mid 159.640554 83.340966)
		(end 159.753691 83.294103)
		(width 0.155)
		(layer "B.Cu")
		(net 107)
	)
	(arc
		(start 156.955902 84.80883)
		(mid 156.914897 84.709836)
		(end 156.955902 84.610842)
		(width 0.155)
		(layer "B.Cu")
		(net 107)
	)
	(arc
		(start 157.351882 84.214862)
		(mid 157.450877 84.173857)
		(end 157.549872 84.214862)
		(width 0.155)
		(layer "B.Cu")
		(net 107)
	)
	(arc
		(start 159.753691 83.294103)
		(mid 159.800554 83.180965)
		(end 159.753691 83.067827)
		(width 0.155)
		(layer "B.Cu")
		(net 107)
	)
	(arc
		(start 157.366024 84.624983)
		(mid 157.407029 84.525988)
		(end 157.366024 84.426993)
		(width 0.155)
		(layer "B.Cu")
		(net 107)
	)
	(arc
		(start 158.905161 84.142633)
		(mid 158.952024 84.029495)
		(end 158.905161 83.916357)
		(width 0.155)
		(layer "B.Cu")
		(net 107)
	)
	(arc
		(start 159.969702 81.586778)
		(mid 159.840829 81.275651)
		(end 159.969702 80.964524)
		(width 0.155)
		(layer "B.Cu")
		(net 107)
	)
	(arc
		(start 156.970044 85.020963)
		(mid 157.011049 84.921968)
		(end 156.970044 84.822973)
		(width 0.155)
		(layer "B.Cu")
		(net 107)
	)
	(arc
		(start 158.272642 82.661584)
		(mid 158.583769 82.532711)
		(end 158.894896 82.661584)
		(width 0.155)
		(layer "B.Cu")
		(net 107)
	)
	(arc
		(start 160.375947 82.445573)
		(mid 160.489084 82.492436)
		(end 160.602221 82.445573)
		(width 0.155)
		(layer "B.Cu")
		(net 107)
	)
	(arc
		(start 159.121172 82.435308)
		(mid 158.992299 82.124181)
		(end 159.121172 81.813054)
		(width 0.155)
		(layer "B.Cu")
		(net 107)
	)
	(segment
		(start 149.321373 84.581184)
		(end 149.589189 84.849)
		(width 0.155)
		(layer "F.Cu")
		(net 108)
	)
	(segment
		(start 183.776 75.043)
		(end 183.886 74.933)
		(width 0.155)
		(layer "F.Cu")
		(net 108)
	)
	(segment
		(start 149.589189 84.849)
		(end 152.34201 84.849)
		(width 0.155)
		(layer "F.Cu")
		(net 108)
	)
	(segment
		(start 182.69601 75.043)
		(end 183.776 75.043)
		(width 0.155)
		(layer "F.Cu")
		(net 108)
	)
	(segment
		(start 152.34201 84.849)
		(end 153.10401 85.611)
		(width 0.155)
		(layer "F.Cu")
		(net 108)
	)
	(segment
		(start 182.18701 75.552)
		(end 182.69601 75.043)
		(width 0.155)
		(layer "F.Cu")
		(net 108)
	)
	(segment
		(start 154.5905 85.611)
		(end 154.813 85.8335)
		(width 0.155)
		(layer "F.Cu")
		(net 108)
	)
	(segment
		(start 165.823139 74.693149)
		(end 166.68199 75.552)
		(width 0.155)
		(layer "F.Cu")
		(net 108)
	)
	(segment
		(start 166.68199 75.552)
		(end 182.18701 75.552)
		(width 0.155)
		(layer "F.Cu")
		(net 108)
	)
	(segment
		(start 165.823139 74.378485)
		(end 165.823139 74.693149)
		(width 0.155)
		(layer "F.Cu")
		(net 108)
	)
	(segment
		(start 149.166517 84.581184)
		(end 149.321373 84.581184)
		(width 0.155)
		(layer "F.Cu")
		(net 108)
	)
	(segment
		(start 153.10401 85.611)
		(end 154.5905 85.611)
		(width 0.155)
		(layer "F.Cu")
		(net 108)
	)
	(via
		(at 165.823139 74.378485)
		(size 0.6)
		(drill 0.35)
		(layers "F.Cu" "B.Cu")
		(net 108)
	)
	(via
		(at 154.813 85.8335)
		(size 0.6)
		(drill 0.35)
		(layers "F.Cu" "B.Cu")
		(net 108)
	)
	(segment
		(start 161.544612 80.842376)
		(end 162.23699 80.15)
		(width 0.155)
		(layer "B.Cu")
		(net 108)
	)
	(segment
		(start 158.376769 84.236494)
		(end 158.480897 84.340622)
		(width 0.155)
		(layer "B.Cu")
		(net 108)
	)
	(segment
		(start 160.800211 82.021309)
		(end 160.582945 81.804043)
		(width 0.155)
		(layer "B.Cu")
		(net 108)
	)
	(segment
		(start 158.696908 82.859574)
		(end 158.696908 82.859573)
		(width 0.155)
		(layer "B.Cu")
		(net 108)
	)
	(segment
		(start 159.103151 83.718368)
		(end 158.999022 83.614239)
		(width 0.155)
		(layer "B.Cu")
		(net 108)
	)
	(segment
		(start 160.48395 81.705048)
		(end 160.483953 81.705048)
		(width 0.155)
		(layer "B.Cu")
		(net 108)
	)
	(segment
		(start 163.88799 80.15)
		(end 166.51 77.52799)
		(width 0.155)
		(layer "B.Cu")
		(net 108)
	)
	(segment
		(start 165.823139 74.693149)
		(end 165.823139 74.378485)
		(width 0.155)
		(layer "B.Cu")
		(net 108)
	)
	(segment
		(start 156.77599 85.611)
		(end 158.150494 84.236494)
		(width 0.155)
		(layer "B.Cu")
		(net 108)
	)
	(segment
		(start 159.545438 82.011044)
		(end 159.545438 82.011043)
		(width 0.155)
		(layer "B.Cu")
		(net 108)
	)
	(segment
		(start 160.393968 81.162513)
		(end 161.026487 81.795033)
		(width 0.155)
		(layer "B.Cu")
		(net 108)
	)
	(segment
		(start 166.51 77.52799)
		(end 166.51 75.38001)
		(width 0.155)
		(layer "B.Cu")
		(net 108)
	)
	(segment
		(start 160.483953 81.705048)
		(end 160.167692 81.388788)
		(width 0.155)
		(layer "B.Cu")
		(net 108)
	)
	(segment
		(start 158.37677 84.236494)
		(end 158.376769 84.236494)
		(width 0.155)
		(layer "B.Cu")
		(net 108)
	)
	(segment
		(start 158.999022 83.614239)
		(end 158.470632 83.085848)
		(width 0.155)
		(layer "B.Cu")
		(net 108)
	)
	(segment
		(start 155.0355 85.611)
		(end 156.77599 85.611)
		(width 0.155)
		(layer "B.Cu")
		(net 108)
	)
	(segment
		(start 159.545438 82.011043)
		(end 160.177957 82.643563)
		(width 0.155)
		(layer "B.Cu")
		(net 108)
	)
	(segment
		(start 158.696908 82.859573)
		(end 159.329427 83.492093)
		(width 0.155)
		(layer "B.Cu")
		(net 108)
	)
	(segment
		(start 159.635423 82.553578)
		(end 159.319162 82.237318)
		(width 0.155)
		(layer "B.Cu")
		(net 108)
	)
	(segment
		(start 159.951681 82.869839)
		(end 159.734415 82.652573)
		(width 0.155)
		(layer "B.Cu")
		(net 108)
	)
	(segment
		(start 166.51 75.38001)
		(end 165.823139 74.693149)
		(width 0.155)
		(layer "B.Cu")
		(net 108)
	)
	(segment
		(start 160.393968 81.162514)
		(end 160.393968 81.162513)
		(width 0.155)
		(layer "B.Cu")
		(net 108)
	)
	(segment
		(start 159.734415 82.652573)
		(end 159.63542 82.553578)
		(width 0.155)
		(layer "B.Cu")
		(net 108)
	)
	(segment
		(start 159.63542 82.553578)
		(end 159.635423 82.553578)
		(width 0.155)
		(layer "B.Cu")
		(net 108)
	)
	(segment
		(start 154.813 85.8335)
		(end 155.0355 85.611)
		(width 0.155)
		(layer "B.Cu")
		(net 108)
	)
	(segment
		(start 161.648741 81.172779)
		(end 161.544612 81.06865)
		(width 0.155)
		(layer "B.Cu")
		(net 108)
	)
	(segment
		(start 162.23699 80.15)
		(end 163.88799 80.15)
		(width 0.155)
		(layer "B.Cu")
		(net 108)
	)
	(segment
		(start 160.582945 81.804043)
		(end 160.48395 81.705048)
		(width 0.155)
		(layer "B.Cu")
		(net 108)
	)
	(arc
		(start 158.150494 84.236494)
		(mid 158.263632 84.189631)
		(end 158.37677 84.236494)
		(width 0.155)
		(layer "B.Cu")
		(net 108)
	)
	(arc
		(start 159.319162 82.011044)
		(mid 159.432301 81.96418)
		(end 159.545438 82.011044)
		(width 0.155)
		(layer "B.Cu")
		(net 108)
	)
	(arc
		(start 159.103151 84.340622)
		(mid 159.232024 84.029495)
		(end 159.103151 83.718368)
		(width 0.155)
		(layer "B.Cu")
		(net 108)
	)
	(arc
		(start 160.800211 82.643563)
		(mid 160.929084 82.332436)
		(end 160.800211 82.021309)
		(width 0.155)
		(layer "B.Cu")
		(net 108)
	)
	(arc
		(start 160.177957 82.643563)
		(mid 160.489084 82.772436)
		(end 160.800211 82.643563)
		(width 0.155)
		(layer "B.Cu")
		(net 108)
	)
	(arc
		(start 158.480897 84.340622)
		(mid 158.792024 84.469495)
		(end 159.103151 84.340622)
		(width 0.155)
		(layer "B.Cu")
		(net 108)
	)
	(arc
		(start 159.329427 83.492093)
		(mid 159.640554 83.620966)
		(end 159.951681 83.492093)
		(width 0.155)
		(layer "B.Cu")
		(net 108)
	)
	(arc
		(start 161.648741 81.795033)
		(mid 161.777614 81.483906)
		(end 161.648741 81.172779)
		(width 0.155)
		(layer "B.Cu")
		(net 108)
	)
	(arc
		(start 160.167692 81.162514)
		(mid 160.280831 81.11565)
		(end 160.393968 81.162514)
		(width 0.155)
		(layer "B.Cu")
		(net 108)
	)
	(arc
		(start 159.951681 83.492093)
		(mid 160.080554 83.180966)
		(end 159.951681 82.869839)
		(width 0.155)
		(layer "B.Cu")
		(net 108)
	)
	(arc
		(start 159.319162 82.237318)
		(mid 159.272299 82.124181)
		(end 159.319162 82.011044)
		(width 0.155)
		(layer "B.Cu")
		(net 108)
	)
	(arc
		(start 161.026487 81.795033)
		(mid 161.337614 81.923906)
		(end 161.648741 81.795033)
		(width 0.155)
		(layer "B.Cu")
		(net 108)
	)
	(arc
		(start 160.167692 81.388788)
		(mid 160.120829 81.275651)
		(end 160.167692 81.162514)
		(width 0.155)
		(layer "B.Cu")
		(net 108)
	)
	(arc
		(start 158.470632 83.085848)
		(mid 158.423769 82.972711)
		(end 158.470632 82.859574)
		(width 0.155)
		(layer "B.Cu")
		(net 108)
	)
	(arc
		(start 161.544612 81.06865)
		(mid 161.497749 80.955513)
		(end 161.544612 80.842376)
		(width 0.155)
		(layer "B.Cu")
		(net 108)
	)
	(arc
		(start 158.470632 82.859574)
		(mid 158.583771 82.81271)
		(end 158.696908 82.859574)
		(width 0.155)
		(layer "B.Cu")
		(net 108)
	)
	(segment
		(start 155.51 95.41)
		(end 155.448 95.41)
		(width 0.187)
		(layer "F.Cu")
		(net 109)
	)
	(segment
		(start 156.18 96.08)
		(end 155.51 95.41)
		(width 0.187)
		(layer "F.Cu")
		(net 109)
	)
	(via
		(at 156.18 96.08)
		(size 0.6)
		(drill 0.35)
		(layers "F.Cu" "B.Cu")
		(net 109)
	)
	(segment
		(start 155.467792 95.915897)
		(end 156.015897 95.915897)
		(width 0.187)
		(layer "B.Cu")
		(net 109)
	)
	(segment
		(start 156.015897 95.915897)
		(end 156.18 96.08)
		(width 0.187)
		(layer "B.Cu")
		(net 109)
	)
	(segment
		(start 159.22 96.04)
		(end 158.58 95.4)
		(width 0.187)
		(layer "F.Cu")
		(net 110)
	)
	(segment
		(start 159.38 96.04)
		(end 159.22 96.04)
		(width 0.187)
		(layer "F.Cu")
		(net 110)
	)
	(segment
		(start 158.58 95.4)
		(end 158.496 95.4)
		(width 0.187)
		(layer "F.Cu")
		(net 110)
	)
	(via
		(at 159.38 96.04)
		(size 0.6)
		(drill 0.35)
		(layers "F.Cu" "B.Cu")
		(net 110)
	)
	(segment
		(start 159.235897 95.895897)
		(end 159.38 96.04)
		(width 0.187)
		(layer "B.Cu")
		(net 110)
	)
	(segment
		(start 158.500124 95.895897)
		(end 159.235897 95.895897)
		(width 0.187)
		(layer "B.Cu")
		(net 110)
	)
	(segment
		(start 161.37 95.77)
		(end 160.34 96.8)
		(width 0.187)
		(layer "F.Cu")
		(net 111)
	)
	(segment
		(start 160.34 96.8)
		(end 158.496 96.8)
		(width 0.187)
		(layer "F.Cu")
		(net 111)
	)
	(segment
		(start 161.45 95.77)
		(end 161.37 95.77)
		(width 0.187)
		(layer "F.Cu")
		(net 111)
	)
	(via
		(at 161.45 95.77)
		(size 0.6)
		(drill 0.35)
		(layers "F.Cu" "B.Cu")
		(net 111)
	)
	(segment
		(start 161.45 95.77)
		(end 162.228 95.77)
		(width 0.187)
		(layer "B.Cu")
		(net 111)
	)
	(segment
		(start 162.228 95.77)
		(end 162.45 95.548)
		(width 0.187)
		(layer "B.Cu")
		(net 111)
	)
	(segment
		(start 154.66 96.07)
		(end 154 95.41)
		(width 0.187)
		(layer "F.Cu")
		(net 112)
	)
	(segment
		(start 154 95.41)
		(end 153.924 95.41)
		(width 0.187)
		(layer "F.Cu")
		(net 112)
	)
	(via
		(at 154.66 96.07)
		(size 0.6)
		(drill 0.35)
		(layers "F.Cu" "B.Cu")
		(net 112)
	)
	(segment
		(start 154.485897 95.895897)
		(end 154.66 96.07)
		(width 0.187)
		(layer "B.Cu")
		(net 112)
	)
	(segment
		(start 153.940161 95.895897)
		(end 154.485897 95.895897)
		(width 0.187)
		(layer "B.Cu")
		(net 112)
	)
	(segment
		(start 188.649 53.7928)
		(end 187.9048 53.7928)
		(width 0.8)
		(layer "F.Cu")
		(net 113)
	)
	(segment
		(start 155.448 96.81)
		(end 155.448 97.89)
		(width 0.5)
		(layer "F.Cu")
		(net 113)
	)
	(segment
		(start 188.649 54.302)
		(end 188.649 53.7928)
		(width 0.8)
		(layer "F.Cu")
		(net 113)
	)
	(segment
		(start 186.978362 52.612362)
		(end 187.311 52.945)
		(width 0.187)
		(layer "F.Cu")
		(net 113)
	)
	(segment
		(start 187.706 53.594)
		(end 187.34 53.594)
		(width 0.8)
		(layer "F.Cu")
		(net 113)
	)
	(segment
		(start 187.34 53.594)
		(end 187.311 53.623)
		(width 0.8)
		(layer "F.Cu")
		(net 113)
	)
	(segment
		(start 183.886 61.434)
		(end 183.1 61.434)
		(width 0.187)
		(layer "F.Cu")
		(net 113)
	)
	(segment
		(start 182.981 61.315)
		(end 182.981 60.934)
		(width 0.187)
		(layer "F.Cu")
		(net 113)
	)
	(segment
		(start 187.897 56.261)
		(end 188.214 55.944)
		(width 0.8)
		(layer "F.Cu")
		(net 113)
	)
	(segment
		(start 187.897 60.6674)
		(end 187.897 56.261)
		(width 0.8)
		(layer "F.Cu")
		(net 113)
	)
	(segment
		(start 188.214 55.944)
		(end 188.214 55.142)
		(width 0.8)
		(layer "F.Cu")
		(net 113)
	)
	(segment
		(start 184.486215 52.2478)
		(end 184.850777 52.612362)
		(width 0.187)
		(layer "F.Cu")
		(net 113)
	)
	(segment
		(start 185.0892 60.934)
		(end 185.3184 61.1632)
		(width 0.3)
		(layer "F.Cu")
		(net 113)
	)
	(segment
		(start 184.850777 52.612362)
		(end 186.978362 52.612362)
		(width 0.187)
		(layer "F.Cu")
		(net 113)
	)
	(segment
		(start 188.19 54.761)
		(end 188.649 54.302)
		(width 0.8)
		(layer "F.Cu")
		(net 113)
	)
	(segment
		(start 187.311 52.945)
		(end 187.311 53.623)
		(width 0.187)
		(layer "F.Cu")
		(net 113)
	)
	(segment
		(start 183.886 60.934)
		(end 185.0892 60.934)
		(width 0.3)
		(layer "F.Cu")
		(net 113)
	)
	(segment
		(start 182.981 60.934)
		(end 182.7285 60.6815)
		(width 0.187)
		(layer "F.Cu")
		(net 113)
	)
	(segment
		(start 188.214 55.142)
		(end 188.19 55.118)
		(width 0.8)
		(layer "F.Cu")
		(net 113)
	)
	(segment
		(start 185.0476 61.434)
		(end 183.886 61.434)
		(width 0.3)
		(layer "F.Cu")
		(net 113)
	)
	(segment
		(start 185.3184 61.1632)
		(end 185.0476 61.434)
		(width 0.3)
		(layer "F.Cu")
		(net 113)
	)
	(segment
		(start 187.9048 53.7928)
		(end 187.706 53.594)
		(width 0.8)
		(layer "F.Cu")
		(net 113)
	)
	(segment
		(start 182.7285 60.6815)
		(end 182.132 60.6815)
		(width 0.187)
		(layer "F.Cu")
		(net 113)
	)
	(segment
		(start 183.1 61.434)
		(end 182.981 61.315)
		(width 0.187)
		(layer "F.Cu")
		(net 113)
	)
	(segment
		(start 183.886 60.934)
		(end 182.981 60.934)
		(width 0.187)
		(layer "F.Cu")
		(net 113)
	)
	(segment
		(start 187.4012 61.1632)
		(end 187.897 60.6674)
		(width 0.8)
		(layer "F.Cu")
		(net 113)
	)
	(segment
		(start 188.19 55.118)
		(end 188.19 54.761)
		(width 0.8)
		(layer "F.Cu")
		(net 113)
	)
	(segment
		(start 187.4012 61.1632)
		(end 185.3184 61.1632)
		(width 0.8)
		(layer "F.Cu")
		(net 113)
	)
	(segment
		(start 184.077 52.2478)
		(end 184.486215 52.2478)
		(width 0.187)
		(layer "F.Cu")
		(net 113)
	)
	(via
		(at 155.448 97.89)
		(size 0.6)
		(drill 0.35)
		(layers "F.Cu" "B.Cu")
		(net 113)
	)
	(via
		(at 187.4012 61.1632)
		(size 0.6)
		(drill 0.35)
		(layers "F.Cu" "B.Cu")
		(net 113)
	)
	(segment
		(start 187.27 61.2944)
		(end 187.4012 61.1632)
		(width 0.187)
		(layer "In2.Cu")
		(net 113)
	)
	(segment
		(start 157.18677 97.2715)
		(end 157.61527 97.7)
		(width 0.187)
		(layer "In2.Cu")
		(net 113)
	)
	(segment
		(start 188.058 96.622298)
		(end 188.058 63.398)
		(width 0.187)
		(layer "In2.Cu")
		(net 113)
	)
	(segment
		(start 186.980298 97.7)
		(end 188.058 96.622298)
		(width 0.187)
		(layer "In2.Cu")
		(net 113)
	)
	(segment
		(start 187.27 62.61)
		(end 187.27 61.2944)
		(width 0.187)
		(layer "In2.Cu")
		(net 113)
	)
	(segment
		(start 155.448 97.79)
		(end 155.9665 97.2715)
		(width 0.187)
		(layer "In2.Cu")
		(net 113)
	)
	(segment
		(start 188.058 63.398)
		(end 187.27 62.61)
		(width 0.187)
		(layer "In2.Cu")
		(net 113)
	)
	(segment
		(start 157.61527 97.7)
		(end 186.980298 97.7)
		(width 0.187)
		(layer "In2.Cu")
		(net 113)
	)
	(segment
		(start 155.9665 97.2715)
		(end 157.18677 97.2715)
		(width 0.187)
		(layer "In2.Cu")
		(net 113)
	)
	(segment
		(start 129.159 63.841932)
		(end 129.159 53.594)
		(width 0.2)
		(layer "F.Cu")
		(net 114)
	)
	(segment
		(start 129.159 41.075)
		(end 129.286 40.948)
		(width 0.2)
		(layer "F.Cu")
		(net 114)
	)
	(segment
		(start 139.48476 76.23876)
		(end 130.623466 67.377466)
		(width 0.2)
		(layer "F.Cu")
		(net 114)
	)
	(segment
		(start 129.159 41.529)
		(end 129.286 41.402)
		(width 0.2)
		(layer "F.Cu")
		(net 114)
	)
	(segment
		(start 129.159 53.594)
		(end 129.159 41.99)
		(width 0.2)
		(layer "F.Cu")
		(net 114)
	)
	(segment
		(start 129.159 41.99)
		(end 129.286 41.863)
		(width 0.2)
		(layer "F.Cu")
		(net 114)
	)
	(arc
		(start 129.159 63.841932)
		(mid 129.539602 65.755349)
		(end 130.623466 67.377466)
		(width 0.2)
		(layer "F.Cu")
		(net 114)
	)
	(segment
		(start 140.815 41.893334)
		(end 140.784666 41.863)
		(width 0.2)
		(layer "F.Cu")
		(net 115)
	)
	(segment
		(start 140.815 72.168573)
		(end 140.815 53.594)
		(width 0.2)
		(layer "F.Cu")
		(net 115)
	)
	(segment
		(start 140.815 53.594)
		(end 140.815 41.893334)
		(width 0.2)
		(layer "F.Cu")
		(net 115)
	)
	(segment
		(start 140.815 41.432334)
		(end 140.784666 41.402)
		(width 0.2)
		(layer "F.Cu")
		(net 115)
	)
	(segment
		(start 141.77076 73.95276)
		(end 141.400786 73.582786)
		(width 0.2)
		(layer "F.Cu")
		(net 115)
	)
	(arc
		(start 140.815 72.168573)
		(mid 140.967241 72.93394)
		(end 141.400786 73.582786)
		(width 0.2)
		(layer "F.Cu")
		(net 115)
	)
	(segment
		(start 152.273 41.412332)
		(end 152.283332 41.402)
		(width 0.2)
		(layer "F.Cu")
		(net 116)
	)
	(segment
		(start 152.273 53.594)
		(end 152.273 41.873332)
		(width 0.2)
		(layer "F.Cu")
		(net 116)
	)
	(segment
		(start 151.687213 74.118787)
		(end 151.47224 74.33376)
		(width 0.2)
		(layer "F.Cu")
		(net 116)
	)
	(segment
		(start 152.273 41.873332)
		(end 152.283332 41.863)
		(width 0.2)
		(layer "F.Cu")
		(net 116)
	)
	(segment
		(start 152.273 53.594)
		(end 152.273 72.704573)
		(width 0.2)
		(layer "F.Cu")
		(net 116)
	)
	(arc
		(start 151.687213 74.118787)
		(mid 152.120759 73.46994)
		(end 152.273 72.704573)
		(width 0.2)
		(layer "F.Cu")
		(net 116)
	)
	(segment
		(start 163.655 53.594)
		(end 163.655 41.99)
		(width 0.2)
		(layer "F.Cu")
		(net 117)
	)
	(segment
		(start 163.655 53.594)
		(end 163.655 64.651932)
		(width 0.2)
		(layer "F.Cu")
		(net 117)
	)
	(segment
		(start 153.75824 76.61976)
		(end 162.190534 68.187466)
		(width 0.2)
		(layer "F.Cu")
		(net 117)
	)
	(segment
		(start 163.655 41.99)
		(end 163.782 41.863)
		(width 0.2)
		(layer "F.Cu")
		(net 117)
	)
	(segment
		(start 163.655 41.529)
		(end 163.782 41.402)
		(width 0.2)
		(layer "F.Cu")
		(net 117)
	)
	(arc
		(start 163.655 64.651932)
		(mid 163.274398 66.565349)
		(end 162.190534 68.187466)
		(width 0.2)
		(layer "F.Cu")
		(net 117)
	)
	(segment
		(start 179.259 55.307)
		(end 179.259 55.89)
		(width 0.187)
		(layer "F.Cu")
		(net 118)
	)
	(segment
		(start 176.325 55.577)
		(end 174.752 55.577)
		(width 0.187)
		(layer "F.Cu")
		(net 118)
	)
	(segment
		(start 176.53 55.372)
		(end 176.325 55.577)
		(width 0.187)
		(layer "F.Cu")
		(net 118)
	)
	(segment
		(start 176.53 54.864)
		(end 176.53 55.372)
		(width 0.187)
		(layer "F.Cu")
		(net 118)
	)
	(segment
		(start 177.318 54.61)
		(end 176.784 54.61)
		(width 0.187)
		(layer "F.Cu")
		(net 118)
	)
	(segment
		(start 177.319 54.609)
		(end 177.319 54.988594)
		(width 0.187)
		(layer "F.Cu")
		(net 118)
	)
	(segment
		(start 177.477906 55.1475)
		(end 179.0995 55.1475)
		(width 0.187)
		(layer "F.Cu")
		(net 118)
	)
	(segment
		(start 179.0995 55.1475)
		(end 179.259 55.307)
		(width 0.187)
		(layer "F.Cu")
		(net 118)
	)
	(segment
		(start 177.319 54.609)
		(end 177.292 54.582)
		(width 0.187)
		(layer "F.Cu")
		(net 118)
	)
	(segment
		(start 177.292 54.582)
		(end 177.292 53.848)
		(width 0.187)
		(layer "F.Cu")
		(net 118)
	)
	(segment
		(start 177.319 54.988594)
		(end 177.477906 55.1475)
		(width 0.187)
		(layer "F.Cu")
		(net 118)
	)
	(segment
		(start 153.924 96.81)
		(end 153.924 97.89)
		(width 0.5)
		(layer "F.Cu")
		(net 118)
	)
	(segment
		(start 176.784 54.61)
		(end 176.53 54.864)
		(width 0.187)
		(layer "F.Cu")
		(net 118)
	)
	(segment
		(start 177.319 54.609)
		(end 177.318 54.61)
		(width 0.187)
		(layer "F.Cu")
		(net 118)
	)
	(via
		(at 153.924 97.89)
		(size 0.6)
		(drill 0.35)
		(layers "F.Cu" "B.Cu")
		(net 118)
	)
	(via
		(at 177.292 53.848)
		(size 0.6)
		(drill 0.35)
		(layers "F.Cu" "B.Cu")
		(net 118)
	)
	(segment
		(start 188.78 96.782767)
		(end 188.78 50.346691)
		(width 0.187)
		(layer "In2.Cu")
		(net 118)
	)
	(segment
		(start 189.0865 43.1565)
		(end 187.522 41.592)
		(width 0.187)
		(layer "In2.Cu")
		(net 118)
	)
	(segment
		(start 154.584 98.45)
		(end 187.112767 98.45)
		(width 0.187)
		(layer "In2.Cu")
		(net 118)
	)
	(segment
		(start 189.0865 50.040191)
		(end 189.0865 43.1565)
		(width 0.187)
		(layer "In2.Cu")
		(net 118)
	)
	(segment
		(start 188.78 50.346691)
		(end 189.0865 50.040191)
		(width 0.187)
		(layer "In2.Cu")
		(net 118)
	)
	(segment
		(start 180.34 43.307)
		(end 180.34 50.8)
		(width 0.187)
		(layer "In2.Cu")
		(net 118)
	)
	(segment
		(start 180.34 50.8)
		(end 177.292 53.848)
		(width 0.187)
		(layer "In2.Cu")
		(net 118)
	)
	(segment
		(start 187.522 41.592)
		(end 182.055 41.592)
		(width 0.187)
		(layer "In2.Cu")
		(net 118)
	)
	(segment
		(start 187.112767 98.45)
		(end 188.78 96.782767)
		(width 0.187)
		(layer "In2.Cu")
		(net 118)
	)
	(segment
		(start 182.055 41.592)
		(end 180.34 43.307)
		(width 0.187)
		(layer "In2.Cu")
		(net 118)
	)
	(segment
		(start 153.924 97.79)
		(end 154.584 98.45)
		(width 0.187)
		(layer "In2.Cu")
		(net 118)
	)
	(segment
		(start 182.4736 67.056)
		(end 181.841 67.056)
		(width 0.187)
		(layer "F.Cu")
		(net 119)
	)
	(segment
		(start 183.0956 66.434)
		(end 182.4736 67.056)
		(width 0.187)
		(layer "F.Cu")
		(net 119)
	)
	(segment
		(start 183.886 66.434)
		(end 183.0956 66.434)
		(width 0.187)
		(layer "F.Cu")
		(net 119)
	)
	(segment
		(start 182.7828 65.934)
		(end 182.6768 66.04)
		(width 0.187)
		(layer "F.Cu")
		(net 120)
	)
	(segment
		(start 182.6768 66.04)
		(end 181.841 66.04)
		(width 0.187)
		(layer "F.Cu")
		(net 120)
	)
	(segment
		(start 183.886 65.934)
		(end 182.7828 65.934)
		(width 0.187)
		(layer "F.Cu")
		(net 120)
	)
	(segment
		(start 169.656 66.818)
		(end 170.203 66.818)
		(width 0.187)
		(layer "F.Cu")
		(net 121)
	)
	(segment
		(start 167.132 68.834)
		(end 168.656 67.31)
		(width 0.187)
		(layer "F.Cu")
		(net 121)
	)
	(segment
		(start 140.504528 82.14076)
		(end 140.685288 81.96)
		(width 0.187)
		(layer "F.Cu")
		(net 121)
	)
	(segment
		(start 168.656 67.31)
		(end 169.164 67.31)
		(width 0.187)
		(layer "F.Cu")
		(net 121)
	)
	(segment
		(start 140.685288 81.96)
		(end 141.240618 81.96)
		(width 0.187)
		(layer "F.Cu")
		(net 121)
	)
	(segment
		(start 169.164 67.31)
		(end 169.656 66.818)
		(width 0.187)
		(layer "F.Cu")
		(net 121)
	)
	(segment
		(start 141.240618 81.96)
		(end 141.431476 82.150858)
		(width 0.187)
		(layer "F.Cu")
		(net 121)
	)
	(via
		(at 140.504528 82.14076)
		(size 0.6)
		(drill 0.35)
		(layers "F.Cu" "B.Cu")
		(net 121)
	)
	(via
		(at 167.132 68.834)
		(size 0.6)
		(drill 0.35)
		(layers "F.Cu" "B.Cu")
		(net 121)
	)
	(segment
		(start 155.956 77.47)
		(end 164.592 68.834)
		(width 0.187)
		(layer "B.Cu")
		(net 121)
	)
	(segment
		(start 155.956 77.978)
		(end 155.956 77.47)
		(width 0.187)
		(layer "B.Cu")
		(net 121)
	)
	(segment
		(start 145.735766 85.344)
		(end 147.066 85.344)
		(width 0.187)
		(layer "B.Cu")
		(net 121)
	)
	(segment
		(start 152.4 80.01)
		(end 153.924 80.01)
		(width 0.187)
		(layer "B.Cu")
		(net 121)
	)
	(segment
		(start 147.066 85.344)
		(end 152.4 80.01)
		(width 0.187)
		(layer "B.Cu")
		(net 121)
	)
	(segment
		(start 140.504528 82.14076)
		(end 142.532526 82.14076)
		(width 0.187)
		(layer "B.Cu")
		(net 121)
	)
	(segment
		(start 142.532526 82.14076)
		(end 145.735766 85.344)
		(width 0.187)
		(layer "B.Cu")
		(net 121)
	)
	(segment
		(start 153.924 80.01)
		(end 155.956 77.978)
		(width 0.187)
		(layer "B.Cu")
		(net 121)
	)
	(segment
		(start 164.592 68.834)
		(end 167.132 68.834)
		(width 0.187)
		(layer "B.Cu")
		(net 121)
	)
	(segment
		(start 129.725 76.385)
		(end 130.302 76.962)
		(width 0.5)
		(layer "F.Cu")
		(net 122)
	)
	(segment
		(start 130.579 76.962)
		(end 130.579 75.947)
		(width 0.5)
		(layer "F.Cu")
		(net 122)
	)
	(segment
		(start 130.579 75.947)
		(end 130.58 75.946)
		(width 0.5)
		(layer "F.Cu")
		(net 122)
	)
	(segment
		(start 129.147 76.385)
		(end 129.725 76.385)
		(width 0.5)
		(layer "F.Cu")
		(net 122)
	)
	(segment
		(start 130.58 74.924)
		(end 130.563 74.907)
		(width 0.5)
		(layer "F.Cu")
		(net 122)
	)
	(segment
		(start 130.302 76.962)
		(end 130.579 76.962)
		(width 0.5)
		(layer "F.Cu")
		(net 122)
	)
	(segment
		(start 130.58 75.946)
		(end 130.58 74.924)
		(width 0.5)
		(layer "F.Cu")
		(net 122)
	)
	(segment
		(start 127.762 78.74)
		(end 128.27 78.74)
		(width 0.187)
		(layer "F.Cu")
		(net 123)
	)
	(segment
		(start 131.549 78.082)
		(end 131.549 76.962)
		(width 0.5)
		(layer "F.Cu")
		(net 123)
	)
	(segment
		(start 147.85 96.8)
		(end 147.85 97.868)
		(width 0.5)
		(layer "F.Cu")
		(net 123)
	)
	(segment
		(start 131.548 76.961)
		(end 131.549 76.962)
		(width 0.5)
		(layer "F.Cu")
		(net 123)
	)
	(segment
		(start 128.228 79.544)
		(end 128.482 79.544)
		(width 0.5)
		(layer "F.Cu")
		(net 123)
	)
	(segment
		(start 126.167 79.895)
		(end 127.877 79.895)
		(width 0.5)
		(layer "F.Cu")
		(net 123)
	)
	(segment
		(start 128.482 79.544)
		(end 129.448 79.544)
		(width 0.5)
		(layer "F.Cu")
		(net 123)
	)
	(segment
		(start 131.699 79.375)
		(end 131.699 78.232)
		(width 0.5)
		(layer "F.Cu")
		(net 123)
	)
	(segment
		(start 147.85 97.868)
		(end 147.828 97.89)
		(width 0.5)
		(layer "F.Cu")
		(net 123)
	)
	(segment
		(start 128.524 79.502)
		(end 128.482 79.544)
		(width 0.187)
		(layer "F.Cu")
		(net 123)
	)
	(segment
		(start 131.548 75.946)
		(end 131.548 76.961)
		(width 0.5)
		(layer "F.Cu")
		(net 123)
	)
	(segment
		(start 130.917 79.544)
		(end 130.937 79.564)
		(width 0.5)
		(layer "F.Cu")
		(net 123)
	)
	(segment
		(start 127.877 79.895)
		(end 128.228 79.544)
		(width 0.5)
		(layer "F.Cu")
		(net 123)
	)
	(segment
		(start 128.27 78.74)
		(end 128.524 78.994)
		(width 0.187)
		(layer "F.Cu")
		(net 123)
	)
	(segment
		(start 128.524 78.994)
		(end 128.524 79.502)
		(width 0.187)
		(layer "F.Cu")
		(net 123)
	)
	(segment
		(start 129.448 79.544)
		(end 130.917 79.544)
		(width 0.5)
		(layer "F.Cu")
		(net 123)
	)
	(segment
		(start 147.85 97.768)
		(end 147.828 97.79)
		(width 0.5)
		(layer "F.Cu")
		(net 123)
	)
	(segment
		(start 131.51 79.564)
		(end 131.699 79.375)
		(width 0.5)
		(layer "F.Cu")
		(net 123)
	)
	(segment
		(start 130.937 79.564)
		(end 131.51 79.564)
		(width 0.5)
		(layer "F.Cu")
		(net 123)
	)
	(segment
		(start 131.699 78.232)
		(end 131.549 78.082)
		(width 0.5)
		(layer "F.Cu")
		(net 123)
	)
	(via
		(at 127.762 78.74)
		(size 0.6)
		(drill 0.35)
		(layers "F.Cu" "B.Cu")
		(net 123)
	)
	(via
		(at 147.828 97.89)
		(size 0.6)
		(drill 0.35)
		(layers "F.Cu" "B.Cu")
		(net 123)
	)
	(segment
		(start 147.118 98.5)
		(end 144.4 98.5)
		(width 0.187)
		(layer "B.Cu")
		(net 123)
	)
	(segment
		(start 118.84 83.47)
		(end 118.84 81.72173)
		(width 0.187)
		(layer "B.Cu")
		(net 123)
	)
	(segment
		(start 144.4 98.5)
		(end 143 97.1)
		(width 0.187)
		(layer "B.Cu")
		(net 123)
	)
	(segment
		(start 140.17573 97.7795)
		(end 133.1495 97.7795)
		(width 0.187)
		(layer "B.Cu")
		(net 123)
	)
	(segment
		(start 118.84 81.72173)
		(end 121.82173 78.74)
		(width 0.187)
		(layer "B.Cu")
		(net 123)
	)
	(segment
		(start 133.1495 97.7795)
		(end 118.84 83.47)
		(width 0.187)
		(layer "B.Cu")
		(net 123)
	)
	(segment
		(start 121.82173 78.74)
		(end 127.762 78.74)
		(width 0.187)
		(layer "B.Cu")
		(net 123)
	)
	(segment
		(start 140.85523 97.1)
		(end 140.17573 97.7795)
		(width 0.187)
		(layer "B.Cu")
		(net 123)
	)
	(segment
		(start 143 97.1)
		(end 140.85523 97.1)
		(width 0.187)
		(layer "B.Cu")
		(net 123)
	)
	(segment
		(start 147.828 97.79)
		(end 147.118 98.5)
		(width 0.187)
		(layer "B.Cu")
		(net 123)
	)
	(segment
		(start 128.683 72.644113)
		(end 129.147 73.108113)
		(width 0.5)
		(layer "F.Cu")
		(net 125)
	)
	(segment
		(start 128.683 72.24)
		(end 128.683 72.644113)
		(width 0.5)
		(layer "F.Cu")
		(net 125)
	)
	(segment
		(start 129.147 73.108113)
		(end 129.147 73.684)
		(width 0.5)
		(layer "F.Cu")
		(net 125)
	)
	(segment
		(start 180.275 50.677229)
		(end 180.139771 50.542)
		(width 0.187)
		(layer "F.Cu")
		(net 126)
	)
	(segment
		(start 180.275 51.732)
		(end 180.275 50.677229)
		(width 0.187)
		(layer "F.Cu")
		(net 126)
	)
	(segment
		(start 179.916 51.732)
		(end 180.275 51.732)
		(width 0.187)
		(layer "F.Cu")
		(net 126)
	)
	(segment
		(start 178.289 54.609)
		(end 178.289 53.359)
		(width 0.187)
		(layer "F.Cu")
		(net 126)
	)
	(segment
		(start 180.139771 50.542)
		(end 179.786 50.542)
		(width 0.187)
		(layer "F.Cu")
		(net 126)
	)
	(segment
		(start 178.289 53.359)
		(end 179.916 51.732)
		(width 0.187)
		(layer "F.Cu")
		(net 126)
	)
	(segment
		(start 177.36 58.629)
		(end 177.36 57.387)
		(width 0.187)
		(layer "F.Cu")
		(net 127)
	)
	(segment
		(start 177.36 57.387)
		(end 176.547 57.387)
		(width 0.187)
		(layer "F.Cu")
		(net 127)
	)
	(segment
		(start 177.315 58.674)
		(end 177.36 58.629)
		(width 0.187)
		(layer "F.Cu")
		(net 127)
	)
	(segment
		(start 176.547 57.387)
		(end 176.364 57.57)
		(width 0.187)
		(layer "F.Cu")
		(net 127)
	)
	(segment
		(start 177.315 58.636)
		(end 177.315 58.674)
		(width 0.187)
		(layer "F.Cu")
		(net 127)
	)
	(segment
		(start 176.364 57.57)
		(end 175.74 57.57)
		(width 0.187)
		(layer "F.Cu")
		(net 127)
	)
	(segment
		(start 178.308 56.896)
		(end 178.308 57.658)
		(width 0.187)
		(layer "F.Cu")
		(net 128)
	)
	(segment
		(start 178.585 57.935)
		(end 179.07 57.935)
		(width 0.187)
		(layer "F.Cu")
		(net 128)
	)
	(segment
		(start 178.308 57.658)
		(end 178.585 57.935)
		(width 0.187)
		(layer "F.Cu")
		(net 128)
	)
	(segment
		(start 179.07 57.935)
		(end 179.347 58.212)
		(width 0.187)
		(layer "F.Cu")
		(net 128)
	)
	(segment
		(start 179.347 58.212)
		(end 179.347 58.674)
		(width 0.187)
		(layer "F.Cu")
		(net 128)
	)
	(segment
		(start 177.36 56.64)
		(end 178.052 56.64)
		(width 0.187)
		(layer "F.Cu")
		(net 128)
	)
	(segment
		(start 178.052 56.64)
		(end 178.308 56.896)
		(width 0.187)
		(layer "F.Cu")
		(net 128)
	)
	(segment
		(start 170.877 59.736)
		(end 171.027 59.586)
		(width 0.187)
		(layer "F.Cu")
		(net 129)
	)
	(segment
		(start 171.027 59.586)
		(end 172.212 59.586)
		(width 0.187)
		(layer "F.Cu")
		(net 129)
	)
	(segment
		(start 168.977 63.2298)
		(end 168.977 62.437)
		(width 0.187)
		(layer "F.Cu")
		(net 130)
	)
	(segment
		(start 168.91 63.65)
		(end 168.91 63.2968)
		(width 0.187)
		(layer "F.Cu")
		(net 130)
	)
	(segment
		(start 170.18 63.65)
		(end 170.18 63.246)
		(width 0.187)
		(layer "F.Cu")
		(net 130)
	)
	(segment
		(start 168.91 63.2968)
		(end 168.977 63.2298)
		(width 0.187)
		(layer "F.Cu")
		(net 130)
	)
	(segment
		(start 169.371 62.437)
		(end 168.977 62.437)
		(width 0.187)
		(layer "F.Cu")
		(net 130)
	)
	(segment
		(start 170.18 63.246)
		(end 169.371 62.437)
		(width 0.187)
		(layer "F.Cu")
		(net 130)
	)
	(segment
		(start 168.083 55.418)
		(end 168.233 55.268)
		(width 0.187)
		(layer "F.Cu")
		(net 131)
	)
	(segment
		(start 168.233 55.268)
		(end 169.418 55.268)
		(width 0.187)
		(layer "F.Cu")
		(net 131)
	)
	(segment
		(start 166.9264 59.332)
		(end 166.7764 59.182)
		(width 0.187)
		(layer "F.Cu")
		(net 132)
	)
	(segment
		(start 166.7764 59.182)
		(end 166.7764 58.3184)
		(width 0.187)
		(layer "F.Cu")
		(net 132)
	)
	(segment
		(start 166.116 59.332)
		(end 166.116 58.9788)
		(width 0.187)
		(layer "F.Cu")
		(net 132)
	)
	(segment
		(start 166.577 58.119)
		(end 166.183 58.119)
		(width 0.187)
		(layer "F.Cu")
		(net 132)
	)
	(segment
		(start 166.183 58.9118)
		(end 166.183 58.119)
		(width 0.187)
		(layer "F.Cu")
		(net 132)
	)
	(segment
		(start 166.116 58.9788)
		(end 166.183 58.9118)
		(width 0.187)
		(layer "F.Cu")
		(net 132)
	)
	(segment
		(start 166.7764 58.3184)
		(end 166.577 58.119)
		(width 0.187)
		(layer "F.Cu")
		(net 132)
	)
	(segment
		(start 167.386 59.332)
		(end 166.9264 59.332)
		(width 0.187)
		(layer "F.Cu")
		(net 132)
	)
	(segment
		(start 173.228 66.568)
		(end 173.228 68.072)
		(width 0.187)
		(layer "F.Cu")
		(net 133)
	)
	(segment
		(start 173.656 65.355)
		(end 173.656 66.14)
		(width 0.187)
		(layer "F.Cu")
		(net 133)
	)
	(segment
		(start 173.228 68.072)
		(end 172.466 68.834)
		(width 0.187)
		(layer "F.Cu")
		(net 133)
	)
	(segment
		(start 172.465 68.833)
		(end 172.466 68.834)
		(width 0.187)
		(layer "F.Cu")
		(net 133)
	)
	(segment
		(start 174.807 64.735)
		(end 175.209 64.735)
		(width 0.187)
		(layer "F.Cu")
		(net 133)
	)
	(segment
		(start 173.656 66.14)
		(end 173.228 66.568)
		(width 0.187)
		(layer "F.Cu")
		(net 133)
	)
	(segment
		(start 174.187 65.355)
		(end 174.807 64.735)
		(width 0.187)
		(layer "F.Cu")
		(net 133)
	)
	(segment
		(start 172.466 68.834)
		(end 172.466 69.342)
		(width 0.187)
		(layer "F.Cu")
		(net 133)
	)
	(segment
		(start 172.466 69.342)
		(end 171.951 69.857)
		(width 0.187)
		(layer "F.Cu")
		(net 133)
	)
	(segment
		(start 173.656 65.355)
		(end 174.187 65.355)
		(width 0.187)
		(layer "F.Cu")
		(net 133)
	)
	(segment
		(start 171.951 69.857)
		(end 171.165 69.857)
		(width 0.187)
		(layer "F.Cu")
		(net 133)
	)
	(segment
		(start 171.167 68.833)
		(end 172.465 68.833)
		(width 0.187)
		(layer "F.Cu")
		(net 133)
	)
	(segment
		(start 172.132 65.355)
		(end 172.663 65.355)
		(width 0.187)
		(layer "F.Cu")
		(net 134)
	)
	(segment
		(start 172.132 66.818)
		(end 172.132 66.374)
		(width 0.187)
		(layer "F.Cu")
		(net 134)
	)
	(segment
		(start 171.704 67.818)
		(end 172.132 67.39)
		(width 0.187)
		(layer "F.Cu")
		(net 134)
	)
	(segment
		(start 172.894 63.6)
		(end 173.502 62.992)
		(width 0.187)
		(layer "F.Cu")
		(net 134)
	)
	(segment
		(start 172.132 67.39)
		(end 172.132 66.374)
		(width 0.187)
		(layer "F.Cu")
		(net 134)
	)
	(segment
		(start 174.752 62.992)
		(end 175.209 62.535)
		(width 0.187)
		(layer "F.Cu")
		(net 134)
	)
	(segment
		(start 171.172 67.818)
		(end 171.704 67.818)
		(width 0.187)
		(layer "F.Cu")
		(net 134)
	)
	(segment
		(start 175.209 62.535)
		(end 175.209 60.436)
		(width 0.187)
		(layer "F.Cu")
		(net 134)
	)
	(segment
		(start 171.173 66.818)
		(end 172.132 66.818)
		(width 0.187)
		(layer "F.Cu")
		(net 134)
	)
	(segment
		(start 172.663 65.355)
		(end 172.894 65.124)
		(width 0.187)
		(layer "F.Cu")
		(net 134)
	)
	(segment
		(start 172.894 65.124)
		(end 172.894 63.6)
		(width 0.187)
		(layer "F.Cu")
		(net 134)
	)
	(segment
		(start 173.502 62.992)
		(end 174.752 62.992)
		(width 0.187)
		(layer "F.Cu")
		(net 134)
	)
	(segment
		(start 172.132 66.374)
		(end 172.132 65.355)
		(width 0.187)
		(layer "F.Cu")
		(net 134)
	)
	(segment
		(start 175.68 66.418)
		(end 175.858 66.24)
		(width 0.187)
		(layer "F.Cu")
		(net 135)
	)
	(segment
		(start 175.858 66.24)
		(end 175.858 64.735)
		(width 0.187)
		(layer "F.Cu")
		(net 135)
	)
	(segment
		(start 151.61 96.07)
		(end 150.95 95.41)
		(width 0.187)
		(layer "F.Cu")
		(net 140)
	)
	(segment
		(start 150.95 95.41)
		(end 150.876 95.41)
		(width 0.187)
		(layer "F.Cu")
		(net 140)
	)
	(via
		(at 151.61 96.07)
		(size 0.6)
		(drill 0.35)
		(layers "F.Cu" "B.Cu")
		(net 140)
	)
	(segment
		(start 150.8809 95.895897)
		(end 151.435897 95.895897)
		(width 0.187)
		(layer "B.Cu")
		(net 140)
	)
	(segment
		(start 151.435897 95.895897)
		(end 151.61 96.07)
		(width 0.187)
		(layer "B.Cu")
		(net 140)
	)
	(segment
		(start 149.43 95.4)
		(end 149.352 95.4)
		(width 0.187)
		(layer "F.Cu")
		(net 141)
	)
	(segment
		(start 150.09 96.06)
		(end 149.43 95.4)
		(width 0.187)
		(layer "F.Cu")
		(net 141)
	)
	(segment
		(start 150.09 96.07)
		(end 150.09 96.06)
		(width 0.187)
		(layer "F.Cu")
		(net 141)
	)
	(via
		(at 150.09 96.07)
		(size 0.6)
		(drill 0.35)
		(layers "F.Cu" "B.Cu")
		(net 141)
	)
	(segment
		(start 149.33434 95.875897)
		(end 149.895897 95.875897)
		(width 0.187)
		(layer "B.Cu")
		(net 141)
	)
	(segment
		(start 149.895897 95.875897)
		(end 150.09 96.07)
		(width 0.187)
		(layer "B.Cu")
		(net 141)
	)
	(segment
		(start 147.96 95.4)
		(end 147.85 95.4)
		(width 0.187)
		(layer "F.Cu")
		(net 142)
	)
	(segment
		(start 148.56 96)
		(end 147.96 95.4)
		(width 0.187)
		(layer "F.Cu")
		(net 142)
	)
	(segment
		(start 148.56 96.08)
		(end 148.56 96)
		(width 0.187)
		(layer "F.Cu")
		(net 142)
	)
	(via
		(at 148.56 96.08)
		(size 0.6)
		(drill 0.35)
		(layers "F.Cu" "B.Cu")
		(net 142)
	)
	(segment
		(start 148.375897 95.895897)
		(end 148.56 96.08)
		(width 0.187)
		(layer "B.Cu")
		(net 142)
	)
	(segment
		(start 147.867621 95.895897)
		(end 148.375897 95.895897)
		(width 0.187)
		(layer "B.Cu")
		(net 142)
	)
	(segment
		(start 145.55 97.55)
		(end 145.55 96.9)
		(width 0.187)
		(layer "F.Cu")
		(net 143)
	)
	(segment
		(start 145.66 96.79)
		(end 146.3 96.79)
		(width 0.187)
		(layer "F.Cu")
		(net 143)
	)
	(segment
		(start 145.55 96.9)
		(end 145.66 96.79)
		(width 0.187)
		(layer "F.Cu")
		(net 143)
	)
	(via
		(at 142.65 96)
		(size 0.6)
		(drill 0.35)
		(layers "F.Cu" "B.Cu")
		(net 143)
	)
	(via
		(at 145.55 97.55)
		(size 0.6)
		(drill 0.35)
		(layers "F.Cu" "B.Cu")
		(net 143)
	)
	(segment
		(start 134.9 90.85)
		(end 134.9 90.302)
		(width 0.187)
		(layer "B.Cu")
		(net 143)
	)
	(segment
		(start 141.85 95.8)
		(end 142.05 96)
		(width 0.187)
		(layer "B.Cu")
		(net 143)
	)
	(segment
		(start 142.05 96)
		(end 142.65 96)
		(width 0.187)
		(layer "B.Cu")
		(net 143)
	)
	(segment
		(start 139.1 95.05)
		(end 134.9 90.85)
		(width 0.187)
		(layer "B.Cu")
		(net 143)
	)
	(segment
		(start 141.1 95.05)
		(end 139.1 95.05)
		(width 0.187)
		(layer "B.Cu")
		(net 143)
	)
	(segment
		(start 141.85 95.8)
		(end 141.1 95.05)
		(width 0.187)
		(layer "B.Cu")
		(net 143)
	)
	(segment
		(start 142.65 96)
		(end 142.65 96.4)
		(width 0.187)
		(layer "In2.Cu")
		(net 143)
	)
	(segment
		(start 143.5 97.25)
		(end 145.25 97.25)
		(width 0.187)
		(layer "In2.Cu")
		(net 143)
	)
	(segment
		(start 145.25 97.25)
		(end 145.55 97.55)
		(width 0.187)
		(layer "In2.Cu")
		(net 143)
	)
	(segment
		(start 142.65 96.4)
		(end 143.5 97.25)
		(width 0.187)
		(layer "In2.Cu")
		(net 143)
	)
	(segment
		(start 147.05 96.06)
		(end 146.38 95.39)
		(width 0.187)
		(layer "F.Cu")
		(net 144)
	)
	(segment
		(start 146.38 95.39)
		(end 146.3 95.39)
		(width 0.187)
		(layer "F.Cu")
		(net 144)
	)
	(via
		(at 147.05 96.06)
		(size 0.6)
		(drill 0.35)
		(layers "F.Cu" "B.Cu")
		(net 144)
	)
	(segment
		(start 146.865897 95.875897)
		(end 147.05 96.06)
		(width 0.187)
		(layer "B.Cu")
		(net 144)
	)
	(segment
		(start 146.321605 95.875897)
		(end 146.865897 95.875897)
		(width 0.187)
		(layer "B.Cu")
		(net 144)
	)
	(segment
		(start 144.15 96.8)
		(end 144.776 96.8)
		(width 0.187)
		(layer "F.Cu")
		(net 145)
	)
	(segment
		(start 143.89 96.54)
		(end 144.15 96.8)
		(width 0.187)
		(layer "F.Cu")
		(net 145)
	)
	(via
		(at 143.89 96.54)
		(size 0.6)
		(drill 0.35)
		(layers "F.Cu" "B.Cu")
		(net 145)
	)
	(segment
		(start 143.89 95.992)
		(end 138.2 90.302)
		(width 0.187)
		(layer "B.Cu")
		(net 145)
	)
	(segment
		(start 143.89 96.54)
		(end 143.89 95.992)
		(width 0.187)
		(layer "B.Cu")
		(net 145)
	)
	(segment
		(start 138.711 77.824)
		(end 136.398 80.137)
		(width 0.3)
		(layer "F.Cu")
		(net 146)
	)
	(segment
		(start 141 97.6885)
		(end 141.26 97.4285)
		(width 0.187)
		(layer "F.Cu")
		(net 146)
	)
	(segment
		(start 138.538 89.348)
		(end 136.67 87.48)
		(width 0.187)
		(layer "F.Cu")
		(net 146)
	)
	(segment
		(start 135.08 87.48)
		(end 134.65 87.05)
		(width 0.187)
		(layer "F.Cu")
		(net 146)
	)
	(segment
		(start 140.55 93.3)
		(end 140.55 91.351234)
		(width 0.187)
		(layer "F.Cu")
		(net 146)
	)
	(segment
		(start 142.88953 79.719825)
		(end 142.890944 79.719825)
		(width 0.187)
		(layer "F.Cu")
		(net 146)
	)
	(segment
		(start 152.9588 78.232)
		(end 152.692147 78.498653)
		(width 0.187)
		(layer "F.Cu")
		(net 146)
	)
	(segment
		(start 140.55 91.351234)
		(end 138.546766 89.348)
		(width 0.187)
		(layer "F.Cu")
		(net 146)
	)
	(segment
		(start 134.65 84.425)
		(end 135.255 83.82)
		(width 0.187)
		(layer "F.Cu")
		(net 146)
	)
	(segment
		(start 150.241 73.787)
		(end 149.567947 74.460053)
		(width 0.187)
		(layer "F.Cu")
		(net 146)
	)
	(segment
		(start 154.352 77.824)
		(end 153.967339 77.824)
		(width 0.187)
		(layer "F.Cu")
		(net 146)
	)
	(segment
		(start 141.26 94.01)
		(end 140.55 93.3)
		(width 0.187)
		(layer "F.Cu")
		(net 146)
	)
	(segment
		(start 149.567947 74.460053)
		(end 149.567947 75.349053)
		(width 0.187)
		(layer "F.Cu")
		(net 146)
	)
	(segment
		(start 136.398 80.137)
		(end 135.255 81.28)
		(width 0.3)
		(layer "F.Cu")
		(net 146)
	)
	(segment
		(start 136.67 87.48)
		(end 135.08 87.48)
		(width 0.187)
		(layer "F.Cu")
		(net 146)
	)
	(segment
		(start 138.546766 89.348)
		(end 138.538 89.348)
		(width 0.187)
		(layer "F.Cu")
		(net 146)
	)
	(segment
		(start 134.65 87.05)
		(end 134.65 84.425)
		(width 0.187)
		(layer "F.Cu")
		(net 146)
	)
	(segment
		(start 139.914 77.824)
		(end 138.711 77.824)
		(width 0.3)
		(layer "F.Cu")
		(net 146)
	)
	(segment
		(start 153.559339 78.232)
		(end 152.9588 78.232)
		(width 0.187)
		(layer "F.Cu")
		(net 146)
	)
	(segment
		(start 142.331205 79.1615)
		(end 142.88953 79.719825)
		(width 0.187)
		(layer "F.Cu")
		(net 146)
	)
	(segment
		(start 153.967339 77.824)
		(end 153.559339 78.232)
		(width 0.187)
		(layer "F.Cu")
		(net 146)
	)
	(segment
		(start 140.550589 78.460589)
		(end 139.914 77.824)
		(width 0.3)
		(layer "F.Cu")
		(net 146)
	)
	(segment
		(start 135.255 81.28)
		(end 135.255 83.82)
		(width 0.3)
		(layer "F.Cu")
		(net 146)
	)
	(segment
		(start 142.02921 79.1615)
		(end 142.331205 79.1615)
		(width 0.187)
		(layer "F.Cu")
		(net 146)
	)
	(segment
		(start 141.26 97.4285)
		(end 141.26 94.01)
		(width 0.187)
		(layer "F.Cu")
		(net 146)
	)
	(via
		(at 142.02921 79.1615)
		(size 0.6)
		(drill 0.35)
		(layers "F.Cu" "B.Cu")
		(net 146)
	)
	(via
		(at 150.241 73.787)
		(size 0.6)
		(drill 0.35)
		(layers "F.Cu" "B.Cu")
		(net 146)
	)
	(via
		(at 141 97.6885)
		(size 0.6)
		(drill 0.35)
		(layers "F.Cu" "B.Cu")
		(net 146)
	)
	(via
		(at 135.255 83.82)
		(size 0.6)
		(drill 0.35)
		(layers "F.Cu" "B.Cu")
		(net 146)
	)
	(via
		(at 136.398 80.137)
		(size 0.6)
		(drill 0.35)
		(layers "F.Cu" "B.Cu")
		(net 146)
	)
	(via
		(at 154.352 77.824)
		(size 0.6)
		(drill 0.35)
		(layers "F.Cu" "B.Cu")
		(net 146)
	)
	(segment
		(start 136.82848 83.82)
		(end 135.255 83.82)
		(width 0.3)
		(layer "B.Cu")
		(net 146)
	)
	(segment
		(start 141 97.6885)
		(end 141.7385 97.6885)
		(width 0.187)
		(layer "B.Cu")
		(net 146)
	)
	(segment
		(start 141.986 73.406)
		(end 136.398 78.994)
		(width 0.3)
		(layer "B.Cu")
		(net 146)
	)
	(segment
		(start 165 97.15)
		(end 165 96.1)
		(width 0.187)
		(layer "B.Cu")
		(net 146)
	)
	(segment
		(start 135.255 83.82)
		(end 134.343 83.82)
		(width 0.3)
		(layer "B.Cu")
		(net 146)
	)
	(segment
		(start 150.241 73.787)
		(end 150.315 73.787)
		(width 0.3)
		(layer "B.Cu")
		(net 146)
	)
	(segment
		(start 136.398 78.994)
		(end 136.398 80.137)
		(width 0.3)
		(layer "B.Cu")
		(net 146)
	)
	(segment
		(start 164.62 95.72)
		(end 164.1 95.72)
		(width 0.187)
		(layer "B.Cu")
		(net 146)
	)
	(segment
		(start 148.717 72.263)
		(end 145.034 72.263)
		(width 0.3)
		(layer "B.Cu")
		(net 146)
	)
	(segment
		(start 150.241 73.787)
		(end 148.717 72.263)
		(width 0.3)
		(layer "B.Cu")
		(net 146)
	)
	(segment
		(start 150.315 73.787)
		(end 154.352 77.824)
		(width 0.3)
		(layer "B.Cu")
		(net 146)
	)
	(segment
		(start 145.034 72.263)
		(end 143.891 73.406)
		(width 0.3)
		(layer "B.Cu")
		(net 146)
	)
	(segment
		(start 141.7385 97.6885)
		(end 142.9 98.85)
		(width 0.187)
		(layer "B.Cu")
		(net 146)
	)
	(segment
		(start 142.9 98.85)
		(end 163.3 98.85)
		(width 0.187)
		(layer "B.Cu")
		(net 146)
	)
	(segment
		(start 163.3 98.85)
		(end 165 97.15)
		(width 0.187)
		(layer "B.Cu")
		(net 146)
	)
	(segment
		(start 142.02921 79.1615)
		(end 141.48698 79.1615)
		(width 0.3)
		(layer "B.Cu")
		(net 146)
	)
	(segment
		(start 165 96.1)
		(end 164.62 95.72)
		(width 0.187)
		(layer "B.Cu")
		(net 146)
	)
	(segment
		(start 143.891 73.406)
		(end 141.986 73.406)
		(width 0.3)
		(layer "B.Cu")
		(net 146)
	)
	(segment
		(start 141.48698 79.1615)
		(end 136.82848 83.82)
		(width 0.3)
		(layer "B.Cu")
		(net 146)
	)
	(segment
		(start 145.5 96.08)
		(end 145.5 96.02)
		(width 0.187)
		(layer "F.Cu")
		(net 147)
	)
	(segment
		(start 145.5 96.02)
		(end 144.88 95.4)
		(width 0.187)
		(layer "F.Cu")
		(net 147)
	)
	(segment
		(start 144.88 95.4)
		(end 144.776 95.4)
		(width 0.187)
		(layer "F.Cu")
		(net 147)
	)
	(via
		(at 145.5 96.08)
		(size 0.6)
		(drill 0.35)
		(layers "F.Cu" "B.Cu")
		(net 147)
	)
	(segment
		(start 144.766904 95.905897)
		(end 145.325897 95.905897)
		(width 0.187)
		(layer "B.Cu")
		(net 147)
	)
	(segment
		(start 145.325897 95.905897)
		(end 145.5 96.08)
		(width 0.187)
		(layer "B.Cu")
		(net 147)
	)
	(zone
		(net 1)
		(net_name "GND")
		(layer "F.Cu")
		(name "GND")
		(hatch edge 0.508)
		(priority 1)
		(connect_pads yes
			(clearance 0.254)
		)
		(min_thickness 0.254)
		(filled_areas_thickness no)
		(fill yes
			(thermal_gap 0.508)
			(thermal_bridge_width 0.508)
		)
		(polygon
			(pts
				(xy 129.964157 95.122686) (xy 129.964157 94.614686) (xy 130.472157 94.106686) (xy 130.472157 93.344686)
				(xy 130.726157 93.090686) (xy 133.774157 93.090686) (xy 134.028157 93.344686) (xy 134.028157 93.852686)
				(xy 134.028157 94.106686) (xy 132.758157 94.106686) (xy 132.504157 94.360686) (xy 132.504157 95.122686)
				(xy 132.250157 95.376686) (xy 130.218157 95.376686)
			)
		)
	)
	(zone
		(net 5)
		(net_name "+5V")
		(layer "F.Cu")
		(name "+5V")
		(hatch edge 0.508)
		(connect_pads yes
			(clearance 0.254)
		)
		(min_thickness 0.254)
		(filled_areas_thickness no)
		(fill yes
			(thermal_gap 0.508)
			(thermal_bridge_width 0.508)
		)
		(polygon
			(pts
				(xy 124.888 69.696) (xy 125.868 69.888) (xy 126.122 70.142) (xy 126.158 70.712) (xy 126.412 70.966)
				(xy 126.412 71.474) (xy 126.666 71.728) (xy 127.682 71.728) (xy 127.936 71.982) (xy 127.936 74.014)
				(xy 127.682 74.268) (xy 126.666 74.268) (xy 126.412 74.014) (xy 125.396 74.014) (xy 125.142 73.76)
				(xy 125.142 72.744) (xy 124.888 72.49) (xy 116.506 72.49) (xy 116.252 72.236) (xy 116.252 69.696)
				(xy 116.506 69.442) (xy 124.634 69.442)
			)
		)
	)
	(zone
		(net 10)
		(net_name "/Power/OUT_1V8")
		(layer "F.Cu")
		(name "OUT_1V8")
		(hatch edge 0.508)
		(connect_pads yes
			(clearance 0.254)
		)
		(min_thickness 0.254)
		(filled_areas_thickness no)
		(fill yes
			(thermal_gap 0.508)
			(thermal_bridge_width 0.508)
		)
		(polygon
			(pts
				(xy 130.472157 92.836686) (xy 130.472157 92.328686) (xy 131.234157 91.566686) (xy 131.234157 91.058686)
				(xy 131.488157 90.804686) (xy 132.758157 90.804686) (xy 133.012157 90.550686) (xy 133.774157 90.550686)
				(xy 134.028157 90.804686) (xy 134.028157 92.328686) (xy 133.774157 92.582686) (xy 132.758157 92.582686)
				(xy 132.250157 93.090686) (xy 130.726157 93.090686)
			)
		)
	)
	(zone
		(net 7)
		(net_name "/Power/SW_1V8")
		(layer "F.Cu")
		(name "SW_1V9")
		(hatch edge 0.508)
		(connect_pads yes
			(clearance 0.254)
		)
		(min_thickness 0.254)
		(filled_areas_thickness no)
		(fill yes
			(thermal_gap 0.508)
			(thermal_bridge_width 0.508)
		)
		(polygon
			(pts
				(xy 132.758157 94.360686) (xy 133.012157 94.106686) (xy 134.028157 94.106686) (xy 134.282157 93.852686)
				(xy 134.282157 92.074686) (xy 134.790157 91.566686) (xy 134.790157 90.804686) (xy 135.044157 90.550686)
				(xy 136.060157 90.550686) (xy 136.568157 91.058686) (xy 137.076157 91.058686) (xy 138.092157 92.074686)
				(xy 138.092157 92.582686) (xy 137.838157 92.836686) (xy 135.552157 92.836686) (xy 135.298157 93.090686)
				(xy 135.298157 94.106686) (xy 134.282157 95.122686) (xy 133.012157 95.122686) (xy 132.758157 94.868686)
			)
		)
	)
	(zone
		(net 9)
		(net_name "/Power/SW_1V2")
		(layer "F.Cu")
		(name "SW_1V2")
		(hatch edge 0.508)
		(connect_pads yes
			(clearance 0.254)
		)
		(min_thickness 0.254)
		(filled_areas_thickness no)
		(fill yes
			(thermal_gap 0.508)
			(thermal_bridge_width 0.508)
		)
		(polygon
			(pts
				(xy 125.65 84.428) (xy 125.396 84.682) (xy 124.38 84.682) (xy 124.126 84.936) (xy 124.126 86.714)
				(xy 123.618 87.222) (xy 123.618 87.984) (xy 123.364 88.238) (xy 122.348 88.238) (xy 121.84 87.73)
				(xy 121.332 87.73) (xy 120.316 86.714) (xy 120.316 86.206) (xy 120.57 85.952) (xy 122.856 85.952)
				(xy 123.11 85.698) (xy 123.11 84.682) (xy 124.126 83.666) (xy 125.396 83.666) (xy 125.65 83.92)
			)
		)
	)
	(zone
		(net 2)
		(net_name "/Connectors/DC_UNFUSED")
		(layer "F.Cu")
		(name "DC_UNFUSED")
		(hatch edge 0.508)
		(connect_pads yes
			(clearance 0.254)
		)
		(min_thickness 0.254)
		(filled_areas_thickness no)
		(fill yes
			(thermal_gap 0.254)
			(thermal_bridge_width 0.254)
		)
		(polygon
			(pts
				(xy 174.752 47.498) (xy 174.752 50.038) (xy 174.244 50.546) (xy 174.244 52.324) (xy 173.736 52.832)
				(xy 173.736 53.594) (xy 173.482 53.848) (xy 172.974 53.848) (xy 172.72 53.594) (xy 172.72 52.832)
				(xy 172.466 52.578) (xy 170.434 52.578) (xy 170.434001 51.413387) (xy 171.450001 51.413387) (xy 171.704 51.054)
				(xy 171.704 49.53) (xy 172.212 49.022) (xy 172.974 49.022) (xy 173.228 48.768) (xy 173.228 47.498)
				(xy 173.482 47.244) (xy 174.498 47.244)
			)
		)
	)
	(zone
		(net 3)
		(net_name "+1V8")
		(layer "F.Cu")
		(name "+1V8")
		(hatch edge 0.508)
		(priority 1)
		(connect_pads yes
			(clearance 0)
		)
		(min_thickness 0.254)
		(filled_areas_thickness no)
		(fill yes
			(thermal_gap 0.508)
			(thermal_bridge_width 0.508)
		)
		(polygon
			(pts
				(xy 132.588 82.804) (xy 132.588 83.947) (xy 132.207 84.328) (xy 132.207 89.535) (xy 132.207 90.043)
				(xy 132.08 90.17) (xy 131.445 90.17) (xy 131.318 90.043) (xy 131.318 84.328) (xy 131.064 84.074)
				(xy 131.064 82.804) (xy 131.318 82.55) (xy 132.334 82.55)
			)
		)
	)
	(zone
		(net 1)
		(net_name "GND")
		(layer "F.Cu")
		(name "GND")
		(hatch edge 0.508)
		(priority 1)
		(connect_pads yes
			(clearance 0.254)
		)
		(min_thickness 0.254)
		(filled_areas_thickness no)
		(fill yes
			(thermal_gap 0.508)
			(thermal_bridge_width 0.508)
		)
		(polygon
			(pts
				(xy 128.444 83.666) (xy 128.444 84.174) (xy 127.936 84.682) (xy 127.936 85.444) (xy 127.682 85.698)
				(xy 124.634 85.698) (xy 124.38 85.444) (xy 124.38 84.936) (xy 124.38 84.682) (xy 125.65 84.682)
				(xy 125.904 84.428) (xy 125.904 83.666) (xy 126.158 83.412) (xy 128.19 83.412)
			)
		)
	)
	(zone
		(net 73)
		(net_name "+1V2")
		(layer "F.Cu")
		(name "+1V2")
		(hatch edge 0.508)
		(connect_pads yes
			(clearance 0)
		)
		(min_thickness 0.254)
		(filled_areas_thickness no)
		(fill yes
			(thermal_gap 0.508)
			(thermal_bridge_width 0.508)
		)
		(polygon
			(pts
				(xy 131.191 86.233) (xy 131.191 87.63) (xy 129.286 89.281) (xy 126.238 89.281) (xy 126.238 88.646)
				(xy 128.651 88.646) (xy 129.667 87.757) (xy 129.667 86.233) (xy 129.921 85.979) (xy 130.937 85.979)
			)
		)
	)
	(zone
		(net 4)
		(net_name "+12V")
		(layer "F.Cu")
		(name "+12V")
		(hatch edge 0.508)
		(priority 1)
		(connect_pads yes
			(clearance 0.254)
		)
		(min_thickness 0.254)
		(filled_areas_thickness no)
		(fill yes
			(thermal_gap 0.508)
			(thermal_bridge_width 0.508)
		)
		(polygon
			(pts
				(xy 175.387 57.15) (xy 175.387 58.643874) (xy 175.133 58.928) (xy 170.815 58.928) (xy 170.561 58.643874)
				(xy 170.561 57.15) (xy 170.815 56.896) (xy 175.133 56.896)
			)
		)
	)
	(zone
		(net 118)
		(net_name "/Connectors/DC_IN")
		(layer "F.Cu")
		(name "DC_IN")
		(hatch edge 0.508)
		(connect_pads yes
			(clearance 0.254)
		)
		(min_thickness 0.254)
		(filled_areas_thickness no)
		(fill yes
			(thermal_gap 0.254)
			(thermal_bridge_width 0.254)
		)
		(polygon
			(pts
				(xy 176.022 56.388) (xy 173.482 56.388) (xy 171.704 56.388) (xy 171.45 56.134) (xy 171.45 55.626)
				(xy 171.196 55.294986) (xy 170.434 55.294986) (xy 170.434 54.102) (xy 176.022 54.102)
			)
		)
	)
	(zone
		(net 124)
		(net_name "/Power/SW_12V")
		(layer "F.Cu")
		(name "SW_12V")
		(hatch edge 0.508)
		(connect_pads yes
			(clearance 0.254)
		)
		(min_thickness 0.254)
		(filled_areas_thickness no)
		(fill yes
			(thermal_gap 0.508)
			(thermal_bridge_width 0.508)
		)
		(polygon
			(pts
				(xy 125.15 75.542) (xy 127.436 75.542) (xy 127.69 75.796) (xy 127.69 77.574) (xy 126.928 78.336)
				(xy 116.514 78.336) (xy 116.26 78.082) (xy 116.26 75.288) (xy 116.514 75.034) (xy 124.642 75.034)
			)
		)
	)
	(zone
		(net 11)
		(net_name "/Power/OUT_1V2")
		(layer "F.Cu")
		(name "OUT_1V2")
		(hatch edge 0.508)
		(connect_pads yes
			(clearance 0.254)
		)
		(min_thickness 0.254)
		(filled_areas_thickness no)
		(fill yes
			(thermal_gap 0.508)
			(thermal_bridge_width 0.508)
		)
		(polygon
			(pts
				(xy 127.936 85.952) (xy 127.936 86.46) (xy 127.174 87.222) (xy 127.174 87.73) (xy 126.92 87.984)
				(xy 125.65 87.984) (xy 125.396 88.238) (xy 124.634 88.238) (xy 124.38 87.984) (xy 124.38 86.46)
				(xy 124.634 86.206) (xy 125.65 86.206) (xy 126.158 85.698) (xy 127.682 85.698)
			)
		)
	)
	(zone
		(net 1)
		(net_name "GND")
		(layer "F.Cu")
		(name "GND")
		(hatch edge 0.508)
		(priority 1)
		(connect_pads yes
			(clearance 0.254)
		)
		(min_thickness 0.254)
		(filled_areas_thickness no)
		(fill yes
			(thermal_gap 0.508)
			(thermal_bridge_width 0.508)
		)
		(polygon
			(pts
				(xy 130.81 73.66) (xy 130.81 74.168) (xy 130.302 74.168) (xy 130.048 74.422) (xy 130.048 74.776)
				(xy 129.54 75.284) (xy 125.65 75.284) (xy 124.634 74.522) (xy 124.634 74.268) (xy 124.888 74.014)
				(xy 125.142 74.014) (xy 126.412 74.014) (xy 126.746 74.522) (xy 129.286 74.522) (xy 129.714 74.014)
				(xy 130.048 73.66)
			)
		)
	)
	(zone
		(net 0)
		(net_name "")
		(layers "F.Cu" "In1.Cu")
		(name "GND_cutout")
		(hatch edge 0.508)
		(connect_pads yes
			(clearance 0)
		)
		(min_thickness 0.254)
		(filled_areas_thickness no)
		(keepout
			(tracks allowed)
			(vias allowed)
			(pads allowed)
			(copperpour not_allowed)
			(footprints allowed)
		)
		(placement
			(enabled no)
			(sheetname "")
		)
		(fill
			(thermal_gap 0.508)
			(thermal_bridge_width 0.508)
		)
		(polygon
			(pts
				(xy 130.275 44.55) (xy 128.25 44.55) (xy 128.25 39.3) (xy 130.275 39.3)
			)
		)
	)
	(zone
		(net 0)
		(net_name "")
		(layers "F.Cu" "In1.Cu")
		(name "GND_cutout")
		(hatch edge 0.508)
		(connect_pads
			(clearance 0)
		)
		(min_thickness 0.254)
		(filled_areas_thickness no)
		(keepout
			(tracks allowed)
			(vias allowed)
			(pads allowed)
			(copperpour not_allowed)
			(footprints allowed)
		)
		(placement
			(enabled no)
			(sheetname "")
		)
		(fill
			(thermal_gap 0.508)
			(thermal_bridge_width 0.508)
		)
		(polygon
			(pts
				(xy 184.4802 76.581) (xy 183.2864 76.581) (xy 183.2864 76.327) (xy 183.2864 75.7682) (xy 184.4802 75.7682)
			)
		)
	)
	(zone
		(net 0)
		(net_name "")
		(layers "F.Cu" "In1.Cu")
		(name "GND_cutout")
		(hatch edge 0.508)
		(connect_pads yes
			(clearance 0)
		)
		(min_thickness 0.254)
		(filled_areas_thickness no)
		(keepout
			(tracks allowed)
			(vias allowed)
			(pads allowed)
			(copperpour not_allowed)
			(footprints allowed)
		)
		(placement
			(enabled no)
			(sheetname "")
		)
		(fill
			(thermal_gap 0.508)
			(thermal_bridge_width 0.508)
		)
		(polygon
			(pts
				(xy 154.3 75.05) (xy 153.875 75.475) (xy 153.375 74.975) (xy 153.8 74.55)
			)
		)
	)
	(zone
		(net 0)
		(net_name "")
		(layers "F.Cu" "In1.Cu")
		(name "GND_cutout")
		(hatch edge 0.508)
		(connect_pads
			(clearance 0)
		)
		(min_thickness 0.254)
		(filled_areas_thickness no)
		(keepout
			(tracks allowed)
			(vias allowed)
			(pads allowed)
			(copperpour not_allowed)
			(footprints allowed)
		)
		(placement
			(enabled no)
			(sheetname "")
		)
		(fill
			(thermal_gap 0.508)
			(thermal_bridge_width 0.508)
		)
		(polygon
			(pts
				(xy 184.4802 72.0852) (xy 183.2864 72.0852) (xy 183.2864 71.8312) (xy 183.2864 71.2724) (xy 184.4802 71.2724)
			)
		)
	)
	(zone
		(net 0)
		(net_name "")
		(layers "F.Cu" "In1.Cu")
		(name "GND_cutout")
		(hatch edge 0.508)
		(connect_pads yes
			(clearance 0)
		)
		(min_thickness 0.254)
		(filled_areas_thickness no)
		(keepout
			(tracks allowed)
			(vias allowed)
			(pads allowed)
			(copperpour not_allowed)
			(footprints allowed)
		)
		(placement
			(enabled no)
			(sheetname "")
		)
		(fill
			(thermal_gap 0.508)
			(thermal_bridge_width 0.508)
		)
		(polygon
			(pts
				(xy 164.025 54.125) (xy 163.3 54.125) (xy 163.3 53.05) (xy 164.025 53.05)
			)
		)
	)
	(zone
		(net 0)
		(net_name "")
		(layers "F.Cu" "In1.Cu")
		(name "GND_cutout")
		(hatch edge 0.508)
		(connect_pads yes
			(clearance 0)
		)
		(min_thickness 0.254)
		(filled_areas_thickness no)
		(keepout
			(tracks allowed)
			(vias allowed)
			(pads allowed)
			(copperpour not_allowed)
			(footprints allowed)
		)
		(placement
			(enabled no)
			(sheetname "")
		)
		(fill
			(thermal_gap 0.508)
			(thermal_bridge_width 0.508)
		)
		(polygon
			(pts
				(xy 154.225 73.625) (xy 153.8 74.05) (xy 153.3 73.55) (xy 153.725 73.125)
			)
		)
	)
	(zone
		(net 0)
		(net_name "")
		(layers "F.Cu" "In1.Cu")
		(name "GND_cutout")
		(hatch edge 0.508)
		(connect_pads yes
			(clearance 0)
		)
		(min_thickness 0.254)
		(filled_areas_thickness no)
		(keepout
			(tracks allowed)
			(vias allowed)
			(pads allowed)
			(copperpour not_allowed)
			(footprints allowed)
		)
		(placement
			(enabled no)
			(sheetname "")
		)
		(fill
			(thermal_gap 0.508)
			(thermal_bridge_width 0.508)
		)
		(polygon
			(pts
				(xy 150.0375 80.1625) (xy 149.7875 79.9125) (xy 150.4125 79.2875) (xy 150.6625 79.5375)
			)
		)
	)
	(zone
		(net 0)
		(net_name "")
		(layers "F.Cu" "In1.Cu")
		(name "GND_cutout")
		(hatch edge 0.508)
		(connect_pads yes
			(clearance 0)
		)
		(min_thickness 0.254)
		(filled_areas_thickness no)
		(keepout
			(tracks allowed)
			(vias allowed)
			(pads allowed)
			(copperpour not_allowed)
			(footprints allowed)
		)
		(placement
			(enabled no)
			(sheetname "")
		)
		(fill
			(thermal_gap 0.508)
			(thermal_bridge_width 0.508)
		)
		(polygon
			(pts
				(xy 153.55 74.3) (xy 153.125 74.725) (xy 152.625 74.225) (xy 153.05 73.8)
			)
		)
	)
	(zone
		(net 0)
		(net_name "")
		(layers "F.Cu" "In1.Cu")
		(name "GND_cutout")
		(hatch edge 0.508)
		(connect_pads
			(clearance 0)
		)
		(min_thickness 0.254)
		(filled_areas_thickness no)
		(keepout
			(tracks allowed)
			(vias allowed)
			(pads allowed)
			(copperpour not_allowed)
			(footprints allowed)
		)
		(placement
			(enabled no)
			(sheetname "")
		)
		(fill
			(thermal_gap 0.508)
			(thermal_bridge_width 0.508)
		)
		(polygon
			(pts
				(xy 184.4802 74.5998) (xy 183.2864 74.5998) (xy 183.2864 74.3458) (xy 183.2864 73.787) (xy 184.4802 73.787)
			)
		)
	)
	(zone
		(net 0)
		(net_name "")
		(layers "F.Cu" "In1.Cu")
		(name "GND_cutout")
		(hatch edge 0.508)
		(connect_pads
			(clearance 0)
		)
		(min_thickness 0.254)
		(filled_areas_thickness no)
		(keepout
			(tracks allowed)
			(vias allowed)
			(pads allowed)
			(copperpour not_allowed)
			(footprints allowed)
		)
		(placement
			(enabled no)
			(sheetname "")
		)
		(fill
			(thermal_gap 0.508)
			(thermal_bridge_width 0.508)
		)
		(polygon
			(pts
				(xy 149.225 85.1408) (xy 148.6662 85.6996) (xy 148.0312 85.0646) (xy 148.59 84.5058)
			)
		)
	)
	(zone
		(net 0)
		(net_name "")
		(layers "F.Cu" "In1.Cu")
		(name "GND_cutout")
		(hatch edge 0.508)
		(connect_pads yes
			(clearance 0)
		)
		(min_thickness 0.254)
		(filled_areas_thickness no)
		(keepout
			(tracks allowed)
			(vias allowed)
			(pads allowed)
			(copperpour not_allowed)
			(footprints allowed)
		)
		(placement
			(enabled no)
			(sheetname "")
		)
		(fill
			(thermal_gap 0.508)
			(thermal_bridge_width 0.508)
		)
		(polygon
			(pts
				(xy 152.7 75.15) (xy 152.275 75.575) (xy 151.775 75.075) (xy 152.2 74.65)
			)
		)
	)
	(zone
		(net 0)
		(net_name "")
		(layers "F.Cu" "In1.Cu")
		(name "GND_cutout")
		(hatch edge 0.508)
		(connect_pads yes
			(clearance 0)
		)
		(min_thickness 0.254)
		(filled_areas_thickness no)
		(keepout
			(tracks allowed)
			(vias allowed)
			(pads allowed)
			(copperpour not_allowed)
			(footprints allowed)
		)
		(placement
			(enabled no)
			(sheetname "")
		)
		(fill
			(thermal_gap 0.508)
			(thermal_bridge_width 0.508)
		)
		(polygon
			(pts
				(xy 140.2 76.475) (xy 140.625 76.9) (xy 140.125 77.4) (xy 139.7 76.975)
			)
		)
	)
	(zone
		(net 0)
		(net_name "")
		(layers "F.Cu" "In1.Cu")
		(name "GND_cutout")
		(hatch edge 0.508)
		(connect_pads
			(clearance 0)
		)
		(min_thickness 0.254)
		(filled_areas_thickness no)
		(keepout
			(tracks allowed)
			(vias allowed)
			(pads allowed)
			(copperpour not_allowed)
			(footprints allowed)
		)
		(placement
			(enabled no)
			(sheetname "")
		)
		(fill
			(thermal_gap 0.508)
			(thermal_bridge_width 0.508)
		)
		(polygon
			(pts
				(xy 184.4802 82.6008) (xy 183.2864 82.6008) (xy 183.2864 82.3468) (xy 183.2864 81.788) (xy 184.4802 81.788)
			)
		)
	)
	(zone
		(net 0)
		(net_name "")
		(layers "F.Cu" "In1.Cu")
		(name "GND_cutout")
		(hatch edge 0.508)
		(connect_pads
			(clearance 0)
		)
		(min_thickness 0.254)
		(filled_areas_thickness no)
		(keepout
			(tracks allowed)
			(vias allowed)
			(pads allowed)
			(copperpour not_allowed)
			(footprints allowed)
		)
		(placement
			(enabled no)
			(sheetname "")
		)
		(fill
			(thermal_gap 0.508)
			(thermal_bridge_width 0.508)
		)
		(polygon
			(pts
				(xy 143.8021 83.7819) (xy 144.3736 84.3534) (xy 143.7386 84.9884) (xy 143.1671 84.4169)
			)
		)
	)
	(zone
		(net 0)
		(net_name "")
		(layers "F.Cu" "In1.Cu")
		(name "GND_cutout")
		(hatch edge 0.508)
		(connect_pads yes
			(clearance 0)
		)
		(min_thickness 0.254)
		(filled_areas_thickness no)
		(keepout
			(tracks allowed)
			(vias allowed)
			(pads allowed)
			(copperpour not_allowed)
			(footprints allowed)
		)
		(placement
			(enabled no)
			(sheetname "")
		)
		(fill
			(thermal_gap 0.508)
			(thermal_bridge_width 0.508)
		)
		(polygon
			(pts
				(xy 143.675 79.575) (xy 143.45 79.8) (xy 142.825 79.175) (xy 143.05 78.95)
			)
		)
	)
	(zone
		(net 0)
		(net_name "")
		(layers "F.Cu" "In1.Cu")
		(name "GND_cutout")
		(hatch edge 0.508)
		(connect_pads yes
			(clearance 0)
		)
		(min_thickness 0.254)
		(filled_areas_thickness no)
		(keepout
			(tracks allowed)
			(vias allowed)
			(pads allowed)
			(copperpour not_allowed)
			(footprints allowed)
		)
		(placement
			(enabled no)
			(sheetname "")
		)
		(fill
			(thermal_gap 0.508)
			(thermal_bridge_width 0.508)
		)
		(polygon
			(pts
				(xy 140.975 75.7) (xy 141.4 76.125) (xy 140.9 76.625) (xy 140.475 76.2)
			)
		)
	)
	(zone
		(net 0)
		(net_name "")
		(layers "F.Cu" "In1.Cu")
		(name "GND_cutout")
		(hatch edge 0.508)
		(connect_pads yes
			(clearance 0)
		)
		(min_thickness 0.254)
		(filled_areas_thickness no)
		(keepout
			(tracks allowed)
			(vias allowed)
			(pads allowed)
			(copperpour not_allowed)
			(footprints allowed)
		)
		(placement
			(enabled no)
			(sheetname "")
		)
		(fill
			(thermal_gap 0.508)
			(thermal_bridge_width 0.508)
		)
		(polygon
			(pts
				(xy 140.3 75.025) (xy 140.725 75.45) (xy 140.225 75.95) (xy 139.8 75.525)
			)
		)
	)
	(zone
		(net 0)
		(net_name "")
		(layers "F.Cu" "In1.Cu")
		(name "GND_cutout")
		(hatch edge 0.508)
		(connect_pads yes
			(clearance 0)
		)
		(min_thickness 0.254)
		(filled_areas_thickness no)
		(keepout
			(tracks allowed)
			(vias allowed)
			(pads allowed)
			(copperpour not_allowed)
			(footprints allowed)
		)
		(placement
			(enabled no)
			(sheetname "")
		)
		(fill
			(thermal_gap 0.508)
			(thermal_bridge_width 0.508)
		)
		(polygon
			(pts
				(xy 152.025 75.825) (xy 151.6 76.25) (xy 151.1 75.75) (xy 151.525 75.325)
			)
		)
	)
	(zone
		(net 0)
		(net_name "")
		(layers "F.Cu" "In1.Cu")
		(name "GND_cutout")
		(hatch edge 0.508)
		(connect_pads yes
			(clearance 0)
		)
		(min_thickness 0.254)
		(filled_areas_thickness no)
		(keepout
			(tracks allowed)
			(vias allowed)
			(pads allowed)
			(copperpour not_allowed)
			(footprints allowed)
		)
		(placement
			(enabled no)
			(sheetname "")
		)
		(fill
			(thermal_gap 0.508)
			(thermal_bridge_width 0.508)
		)
		(polygon
			(pts
				(xy 149.675 79.8) (xy 149.4375 79.5625) (xy 150.0625 78.9375) (xy 150.3 79.175)
			)
		)
	)
	(zone
		(net 0)
		(net_name "")
		(layers "F.Cu" "In1.Cu")
		(name "GND_cutout")
		(hatch edge 0.508)
		(connect_pads yes
			(clearance 0)
		)
		(min_thickness 0.254)
		(filled_areas_thickness no)
		(keepout
			(tracks allowed)
			(vias allowed)
			(pads allowed)
			(copperpour not_allowed)
			(footprints allowed)
		)
		(placement
			(enabled no)
			(sheetname "")
		)
		(fill
			(thermal_gap 0.508)
			(thermal_bridge_width 0.508)
		)
		(polygon
			(pts
				(xy 144.0375 79.2125) (xy 143.8 79.45) (xy 143.175 78.825) (xy 143.4125 78.5875)
			)
		)
	)
	(zone
		(net 0)
		(net_name "")
		(layers "F.Cu" "In1.Cu")
		(name "GND_cutout")
		(hatch edge 0.508)
		(connect_pads yes
			(clearance 0)
		)
		(min_thickness 0.254)
		(filled_areas_thickness no)
		(keepout
			(tracks allowed)
			(vias allowed)
			(pads allowed)
			(copperpour not_allowed)
			(footprints allowed)
		)
		(placement
			(enabled no)
			(sheetname "")
		)
		(fill
			(thermal_gap 0.508)
			(thermal_bridge_width 0.508)
		)
		(polygon
			(pts
				(xy 153.525 77.325) (xy 153.1 77.75) (xy 152.6 77.25) (xy 153.025 76.825)
			)
		)
	)
	(zone
		(net 0)
		(net_name "")
		(layers "F.Cu" "In1.Cu")
		(name "GND_cutout")
		(hatch edge 0.508)
		(connect_pads
			(clearance 0)
		)
		(min_thickness 0.254)
		(filled_areas_thickness no)
		(keepout
			(tracks allowed)
			(vias allowed)
			(pads allowed)
			(copperpour not_allowed)
			(footprints allowed)
		)
		(placement
			(enabled no)
			(sheetname "")
		)
		(fill
			(thermal_gap 0.508)
			(thermal_bridge_width 0.508)
		)
		(polygon
			(pts
				(xy 151.3586 83.0072) (xy 150.7744 83.5914) (xy 150.1394 82.9564) (xy 150.7236 82.3722)
			)
		)
	)
	(zone
		(net 0)
		(net_name "")
		(layers "F.Cu" "In1.Cu")
		(name "GND_cutout")
		(hatch edge 0.508)
		(connect_pads
			(clearance 0)
		)
		(min_thickness 0.254)
		(filled_areas_thickness no)
		(keepout
			(tracks allowed)
			(vias allowed)
			(pads allowed)
			(copperpour not_allowed)
			(footprints allowed)
		)
		(placement
			(enabled no)
			(sheetname "")
		)
		(fill
			(thermal_gap 0.508)
			(thermal_bridge_width 0.508)
		)
		(polygon
			(pts
				(xy 147.8153 86.5505) (xy 147.2438 87.122) (xy 146.685 86.5632) (xy 146.685 86.4108) (xy 147.1803 85.9155)
			)
		)
	)
	(zone
		(net 0)
		(net_name "")
		(layers "F.Cu" "In1.Cu")
		(name "GND_cutout")
		(hatch edge 0.508)
		(connect_pads yes
			(clearance 0)
		)
		(min_thickness 0.254)
		(filled_areas_thickness no)
		(keepout
			(tracks allowed)
			(vias allowed)
			(pads allowed)
			(copperpour not_allowed)
			(footprints allowed)
		)
		(placement
			(enabled no)
			(sheetname "")
		)
		(fill
			(thermal_gap 0.508)
			(thermal_bridge_width 0.508)
		)
		(polygon
			(pts
				(xy 151.25 75.05) (xy 150.825 75.475) (xy 150.325 74.975) (xy 150.75 74.55)
			)
		)
	)
	(zone
		(net 0)
		(net_name "")
		(layers "F.Cu" "In1.Cu")
		(name "GND_cutout")
		(hatch edge 0.508)
		(connect_pads yes
			(clearance 0)
		)
		(min_thickness 0.254)
		(filled_areas_thickness no)
		(keepout
			(tracks allowed)
			(vias allowed)
			(pads allowed)
			(copperpour not_allowed)
			(footprints allowed)
		)
		(placement
			(enabled no)
			(sheetname "")
		)
		(fill
			(thermal_gap 0.508)
			(thermal_bridge_width 0.508)
		)
		(polygon
			(pts
				(xy 139.45 74.175) (xy 139.875 74.6) (xy 139.375 75.1) (xy 138.95 74.675)
			)
		)
	)
	(zone
		(net 0)
		(net_name "")
		(layers "F.Cu" "In1.Cu")
		(name "GND_cutout")
		(hatch edge 0.508)
		(connect_pads yes
			(clearance 0)
		)
		(min_thickness 0.254)
		(filled_areas_thickness no)
		(keepout
			(tracks allowed)
			(vias allowed)
			(pads allowed)
			(copperpour not_allowed)
			(footprints allowed)
		)
		(placement
			(enabled no)
			(sheetname "")
		)
		(fill
			(thermal_gap 0.508)
			(thermal_bridge_width 0.508)
		)
		(polygon
			(pts
				(xy 129.525 54.125) (xy 128.8 54.125) (xy 128.8 53.05) (xy 129.525 53.05)
			)
		)
	)
	(zone
		(net 0)
		(net_name "")
		(layers "F.Cu" "In1.Cu")
		(name "GND_cutout")
		(hatch edge 0.508)
		(connect_pads yes
			(clearance 0)
		)
		(min_thickness 0.254)
		(filled_areas_thickness no)
		(keepout
			(tracks allowed)
			(vias allowed)
			(pads allowed)
			(copperpour not_allowed)
			(footprints allowed)
		)
		(placement
			(enabled no)
			(sheetname "")
		)
		(fill
			(thermal_gap 0.508)
			(thermal_bridge_width 0.508)
		)
		(polygon
			(pts
				(xy 151.925 74.375) (xy 151.5 74.8) (xy 151 74.3) (xy 151.425 73.875)
			)
		)
	)
	(zone
		(net 0)
		(net_name "")
		(layers "F.Cu" "In1.Cu")
		(name "GND_cutout")
		(hatch edge 0.508)
		(connect_pads yes
			(clearance 0)
		)
		(min_thickness 0.254)
		(filled_areas_thickness no)
		(keepout
			(tracks allowed)
			(vias allowed)
			(pads allowed)
			(copperpour not_allowed)
			(footprints allowed)
		)
		(placement
			(enabled no)
			(sheetname "")
		)
		(fill
			(thermal_gap 0.508)
			(thermal_bridge_width 0.508)
		)
		(polygon
			(pts
				(xy 145.0875 78.1625) (xy 144.8625 78.3875) (xy 144.2375 77.7625) (xy 144.4625 77.5375)
			)
		)
	)
	(zone
		(net 0)
		(net_name "")
		(layers "F.Cu" "In1.Cu")
		(name "GND_cutout")
		(hatch edge 0.508)
		(connect_pads yes
			(clearance 0)
		)
		(min_thickness 0.254)
		(filled_areas_thickness no)
		(keepout
			(tracks allowed)
			(vias allowed)
			(pads allowed)
			(copperpour not_allowed)
			(footprints allowed)
		)
		(placement
			(enabled no)
			(sheetname "")
		)
		(fill
			(thermal_gap 0.508)
			(thermal_bridge_width 0.508)
		)
		(polygon
			(pts
				(xy 141.8 44.492) (xy 139.775 44.492) (xy 139.775 39.242) (xy 141.8 39.242)
			)
		)
	)
	(zone
		(net 0)
		(net_name "")
		(layers "F.Cu" "In1.Cu")
		(name "GND_cutout")
		(hatch edge 0.508)
		(connect_pads yes
			(clearance 0)
		)
		(min_thickness 0.254)
		(filled_areas_thickness no)
		(keepout
			(tracks allowed)
			(vias allowed)
			(pads allowed)
			(copperpour not_allowed)
			(footprints allowed)
		)
		(placement
			(enabled no)
			(sheetname "")
		)
		(fill
			(thermal_gap 0.508)
			(thermal_bridge_width 0.508)
		)
		(polygon
			(pts
				(xy 141.8 73.525) (xy 142.225 73.95) (xy 141.725 74.45) (xy 141.3 74.025)
			)
		)
	)
	(zone
		(net 0)
		(net_name "")
		(layers "F.Cu" "In1.Cu")
		(name "GND_cutout")
		(hatch edge 0.508)
		(connect_pads yes
			(clearance 0)
		)
		(min_thickness 0.254)
		(filled_areas_thickness no)
		(keepout
			(tracks allowed)
			(vias allowed)
			(pads allowed)
			(copperpour not_allowed)
			(footprints allowed)
		)
		(placement
			(enabled no)
			(sheetname "")
		)
		(fill
			(thermal_gap 0.508)
			(thermal_bridge_width 0.508)
		)
		(polygon
			(pts
				(xy 153.3 44.492) (xy 151.275 44.492) (xy 151.275 39.242) (xy 153.3 39.242)
			)
		)
	)
	(zone
		(net 0)
		(net_name "")
		(layers "F.Cu" "In1.Cu")
		(name "GND_cutout")
		(hatch edge 0.508)
		(connect_pads
			(clearance 0)
		)
		(min_thickness 0.254)
		(filled_areas_thickness no)
		(keepout
			(tracks allowed)
			(vias allowed)
			(pads allowed)
			(copperpour not_allowed)
			(footprints allowed)
		)
		(placement
			(enabled no)
			(sheetname "")
		)
		(fill
			(thermal_gap 0.508)
			(thermal_bridge_width 0.508)
		)
		(polygon
			(pts
				(xy 184.4802 85.598) (xy 183.2864 85.598) (xy 183.2864 85.344) (xy 183.2864 84.7852) (xy 184.4802 84.7852)
			)
		)
	)
	(zone
		(net 0)
		(net_name "")
		(layers "F.Cu" "In1.Cu")
		(name "GND_cutout")
		(hatch edge 0.508)
		(connect_pads
			(clearance 0)
		)
		(min_thickness 0.254)
		(filled_areas_thickness no)
		(keepout
			(tracks allowed)
			(vias allowed)
			(pads allowed)
			(copperpour not_allowed)
			(footprints allowed)
		)
		(placement
			(enabled no)
			(sheetname "")
		)
		(fill
			(thermal_gap 0.508)
			(thermal_bridge_width 0.508)
		)
		(polygon
			(pts
				(xy 184.4802 83.5914) (xy 183.2864 83.5914) (xy 183.2864 83.3374) (xy 183.2864 82.7786) (xy 184.4802 82.7786)
			)
		)
	)
	(zone
		(net 0)
		(net_name "")
		(layers "F.Cu" "In1.Cu")
		(name "GND_cutout")
		(hatch edge 0.508)
		(connect_pads
			(clearance 0)
		)
		(min_thickness 0.254)
		(filled_areas_thickness no)
		(keepout
			(tracks allowed)
			(vias allowed)
			(pads allowed)
			(copperpour not_allowed)
			(footprints allowed)
		)
		(placement
			(enabled no)
			(sheetname "")
		)
		(fill
			(thermal_gap 0.508)
			(thermal_bridge_width 0.508)
		)
		(polygon
			(pts
				(xy 184.4802 81.1022) (xy 183.2864 81.1022) (xy 183.2864 80.8482) (xy 183.2864 80.2894) (xy 184.4802 80.2894)
			)
		)
	)
	(zone
		(net 0)
		(net_name "")
		(layers "F.Cu" "In1.Cu")
		(name "GND_cutout")
		(hatch edge 0.508)
		(connect_pads yes
			(clearance 0)
		)
		(min_thickness 0.254)
		(filled_areas_thickness no)
		(keepout
			(tracks allowed)
			(vias allowed)
			(pads allowed)
			(copperpour not_allowed)
			(footprints allowed)
		)
		(placement
			(enabled no)
			(sheetname "")
		)
		(fill
			(thermal_gap 0.508)
			(thermal_bridge_width 0.508)
		)
		(polygon
			(pts
				(xy 152.775 76.575) (xy 152.35 77) (xy 151.85 76.5) (xy 152.275 76.075)
			)
		)
	)
	(zone
		(net 0)
		(net_name "")
		(layers "F.Cu" "In1.Cu")
		(name "GND_cutout")
		(hatch edge 0.508)
		(connect_pads yes
			(clearance 0)
		)
		(min_thickness 0.254)
		(filled_areas_thickness no)
		(keepout
			(tracks allowed)
			(vias allowed)
			(pads allowed)
			(copperpour not_allowed)
			(footprints allowed)
		)
		(placement
			(enabled no)
			(sheetname "")
		)
		(fill
			(thermal_gap 0.508)
			(thermal_bridge_width 0.508)
		)
		(polygon
			(pts
				(xy 141.05 74.275) (xy 141.475 74.7) (xy 140.975 75.2) (xy 140.55 74.775)
			)
		)
	)
	(zone
		(net 0)
		(net_name "")
		(layers "F.Cu" "In1.Cu")
		(name "GND_cutout")
		(hatch edge 0.508)
		(connect_pads
			(clearance 0)
		)
		(min_thickness 0.254)
		(filled_areas_thickness no)
		(keepout
			(tracks allowed)
			(vias allowed)
			(pads allowed)
			(copperpour not_allowed)
			(footprints allowed)
		)
		(placement
			(enabled no)
			(sheetname "")
		)
		(fill
			(thermal_gap 0.508)
			(thermal_bridge_width 0.508)
		)
		(polygon
			(pts
				(xy 145.2245 85.2043) (xy 145.796 85.7758) (xy 145.161 86.4108) (xy 144.5895 85.8393)
			)
		)
	)
	(zone
		(net 0)
		(net_name "")
		(layers "F.Cu" "In1.Cu")
		(name "GND_cutout")
		(hatch edge 0.508)
		(connect_pads yes
			(clearance 0)
		)
		(min_thickness 0.254)
		(filled_areas_thickness no)
		(keepout
			(tracks allowed)
			(vias allowed)
			(pads allowed)
			(copperpour not_allowed)
			(footprints allowed)
		)
		(placement
			(enabled no)
			(sheetname "")
		)
		(fill
			(thermal_gap 0.508)
			(thermal_bridge_width 0.508)
		)
		(polygon
			(pts
				(xy 152.65 54.125) (xy 151.925 54.125) (xy 151.925 53.05) (xy 152.65 53.05)
			)
		)
	)
	(zone
		(net 0)
		(net_name "")
		(layers "F.Cu" "In1.Cu")
		(name "GND_cutout")
		(hatch edge 0.508)
		(connect_pads
			(clearance 0)
		)
		(min_thickness 0.254)
		(filled_areas_thickness no)
		(keepout
			(tracks allowed)
			(vias allowed)
			(pads allowed)
			(copperpour not_allowed)
			(footprints allowed)
		)
		(placement
			(enabled no)
			(sheetname "")
		)
		(fill
			(thermal_gap 0.508)
			(thermal_bridge_width 0.508)
		)
		(polygon
			(pts
				(xy 149.9362 84.4296) (xy 149.3647 85.0011) (xy 148.7297 84.3661) (xy 149.3012 83.7946)
			)
		)
	)
	(zone
		(net 0)
		(net_name "")
		(layers "F.Cu" "In1.Cu")
		(name "GND_cutout")
		(hatch edge 0.508)
		(connect_pads
			(clearance 0)
		)
		(min_thickness 0.254)
		(filled_areas_thickness no)
		(keepout
			(tracks allowed)
			(vias allowed)
			(pads allowed)
			(copperpour not_allowed)
			(footprints allowed)
		)
		(placement
			(enabled no)
			(sheetname "")
		)
		(fill
			(thermal_gap 0.508)
			(thermal_bridge_width 0.508)
		)
		(polygon
			(pts
				(xy 184.4802 73.5838) (xy 183.2864 73.5838) (xy 183.2864 73.3298) (xy 183.2864 72.771) (xy 184.4802 72.771)
			)
		)
	)
	(zone
		(net 0)
		(net_name "")
		(layers "F.Cu" "In1.Cu")
		(name "GND_cutout")
		(hatch edge 0.508)
		(connect_pads yes
			(clearance 0)
		)
		(min_thickness 0.254)
		(filled_areas_thickness no)
		(keepout
			(tracks allowed)
			(vias allowed)
			(pads allowed)
			(copperpour not_allowed)
			(footprints allowed)
		)
		(placement
			(enabled no)
			(sheetname "")
		)
		(fill
			(thermal_gap 0.508)
			(thermal_bridge_width 0.508)
		)
		(polygon
			(pts
				(xy 148.625 78.75) (xy 148.375 78.5) (xy 149 77.875) (xy 149.25 78.125)
			)
		)
	)
	(zone
		(net 0)
		(net_name "")
		(layers "F.Cu" "In1.Cu")
		(name "GND_cutout")
		(hatch edge 0.508)
		(connect_pads yes
			(clearance 0)
		)
		(min_thickness 0.254)
		(filled_areas_thickness no)
		(keepout
			(tracks allowed)
			(vias allowed)
			(pads allowed)
			(copperpour not_allowed)
			(footprints allowed)
		)
		(placement
			(enabled no)
			(sheetname "")
		)
		(fill
			(thermal_gap 0.508)
			(thermal_bridge_width 0.508)
		)
		(polygon
			(pts
				(xy 142.475 74.2) (xy 142.9 74.625) (xy 142.4 75.125) (xy 141.975 74.7)
			)
		)
	)
	(zone
		(net 0)
		(net_name "")
		(layers "F.Cu" "In1.Cu")
		(name "GND_cutout")
		(hatch edge 0.508)
		(connect_pads yes
			(clearance 0)
		)
		(min_thickness 0.254)
		(filled_areas_thickness no)
		(keepout
			(tracks allowed)
			(vias allowed)
			(pads allowed)
			(copperpour not_allowed)
			(footprints allowed)
		)
		(placement
			(enabled no)
			(sheetname "")
		)
		(fill
			(thermal_gap 0.508)
			(thermal_bridge_width 0.508)
		)
		(polygon
			(pts
				(xy 140.2 73.425) (xy 140.625 73.85) (xy 140.125 74.35) (xy 139.7 73.925)
			)
		)
	)
	(zone
		(net 0)
		(net_name "")
		(layers "F.Cu" "In1.Cu")
		(name "GND_cutout")
		(hatch edge 0.508)
		(connect_pads yes
			(clearance 0)
		)
		(min_thickness 0.254)
		(filled_areas_thickness no)
		(keepout
			(tracks allowed)
			(vias allowed)
			(pads allowed)
			(copperpour not_allowed)
			(footprints allowed)
		)
		(placement
			(enabled no)
			(sheetname "")
		)
		(fill
			(thermal_gap 0.508)
			(thermal_bridge_width 0.508)
		)
		(polygon
			(pts
				(xy 154.2 76.65) (xy 153.775 77.075) (xy 153.275 76.575) (xy 153.7 76.15)
			)
		)
	)
	(zone
		(net 0)
		(net_name "")
		(layers "F.Cu" "In1.Cu")
		(name "GND_cutout")
		(hatch edge 0.508)
		(connect_pads yes
			(clearance 0)
		)
		(min_thickness 0.254)
		(filled_areas_thickness no)
		(keepout
			(tracks allowed)
			(vias allowed)
			(pads allowed)
			(copperpour not_allowed)
			(footprints allowed)
		)
		(placement
			(enabled no)
			(sheetname "")
		)
		(fill
			(thermal_gap 0.508)
			(thermal_bridge_width 0.508)
		)
		(polygon
			(pts
				(xy 145.45 77.8) (xy 145.2125 78.0375) (xy 144.5875 77.4125) (xy 144.825 77.175)
			)
		)
	)
	(zone
		(net 0)
		(net_name "")
		(layers "F.Cu" "In1.Cu")
		(name "GND_cutout")
		(hatch edge 0.508)
		(connect_pads yes
			(clearance 0)
		)
		(min_thickness 0.254)
		(filled_areas_thickness no)
		(keepout
			(tracks allowed)
			(vias allowed)
			(pads allowed)
			(copperpour not_allowed)
			(footprints allowed)
		)
		(placement
			(enabled no)
			(sheetname "")
		)
		(fill
			(thermal_gap 0.508)
			(thermal_bridge_width 0.508)
		)
		(polygon
			(pts
				(xy 138.775 73.5) (xy 139.2 73.925) (xy 138.7 74.425) (xy 138.275 74)
			)
		)
	)
	(zone
		(net 0)
		(net_name "")
		(layers "F.Cu" "In1.Cu")
		(name "GND_cutout")
		(hatch edge 0.508)
		(connect_pads
			(clearance 0)
		)
		(min_thickness 0.254)
		(filled_areas_thickness no)
		(keepout
			(tracks allowed)
			(vias allowed)
			(pads allowed)
			(copperpour not_allowed)
			(footprints allowed)
		)
		(placement
			(enabled no)
			(sheetname "")
		)
		(fill
			(thermal_gap 0.508)
			(thermal_bridge_width 0.508)
		)
		(polygon
			(pts
				(xy 145.9357 85.9155) (xy 146.431 86.4108) (xy 146.431 86.5632) (xy 145.8722 87.122) (xy 145.3007 86.5505)
			)
		)
	)
	(zone
		(net 0)
		(net_name "")
		(layers "F.Cu" "In1.Cu")
		(name "GND_cutout")
		(hatch edge 0.508)
		(connect_pads
			(clearance 0)
		)
		(min_thickness 0.254)
		(filled_areas_thickness no)
		(keepout
			(tracks allowed)
			(vias allowed)
			(pads allowed)
			(copperpour not_allowed)
			(footprints allowed)
		)
		(placement
			(enabled no)
			(sheetname "")
		)
		(fill
			(thermal_gap 0.508)
			(thermal_bridge_width 0.508)
		)
		(polygon
			(pts
				(xy 142.408539 82.3849) (xy 142.980039 82.9564) (xy 142.345039 83.5914) (xy 141.773539 83.0199)
			)
		)
	)
	(zone
		(net 0)
		(net_name "")
		(layers "F.Cu" "In1.Cu")
		(name "GND_cutout")
		(hatch edge 0.508)
		(connect_pads yes
			(clearance 0)
		)
		(min_thickness 0.254)
		(filled_areas_thickness no)
		(keepout
			(tracks allowed)
			(vias allowed)
			(pads allowed)
			(copperpour not_allowed)
			(footprints allowed)
		)
		(placement
			(enabled no)
			(sheetname "")
		)
		(fill
			(thermal_gap 0.508)
			(thermal_bridge_width 0.508)
		)
		(polygon
			(pts
				(xy 139.525 72.75) (xy 139.95 73.175) (xy 139.45 73.675) (xy 139.025 73.25)
			)
		)
	)
	(zone
		(net 0)
		(net_name "")
		(layers "F.Cu" "In1.Cu")
		(name "GND_cutout")
		(hatch edge 0.508)
		(connect_pads yes
			(clearance 0)
		)
		(min_thickness 0.254)
		(filled_areas_thickness no)
		(keepout
			(tracks allowed)
			(vias allowed)
			(pads allowed)
			(copperpour not_allowed)
			(footprints allowed)
		)
		(placement
			(enabled no)
			(sheetname "")
		)
		(fill
			(thermal_gap 0.508)
			(thermal_bridge_width 0.508)
		)
		(polygon
			(pts
				(xy 148.2625 78.3875) (xy 148.025 78.15) (xy 148.65 77.525) (xy 148.8875 77.7625)
			)
		)
	)
	(zone
		(net 0)
		(net_name "")
		(layers "F.Cu" "In1.Cu")
		(name "GND_cutout")
		(hatch edge 0.508)
		(connect_pads yes
			(clearance 0)
		)
		(min_thickness 0.254)
		(filled_areas_thickness no)
		(keepout
			(tracks allowed)
			(vias allowed)
			(pads allowed)
			(copperpour not_allowed)
			(footprints allowed)
		)
		(placement
			(enabled no)
			(sheetname "")
		)
		(fill
			(thermal_gap 0.508)
			(thermal_bridge_width 0.508)
		)
		(polygon
			(pts
				(xy 141.175 54.125) (xy 140.45 54.125) (xy 140.45 53.05) (xy 141.175 53.05)
			)
		)
	)
	(zone
		(net 0)
		(net_name "")
		(layers "F.Cu" "In1.Cu")
		(name "GND_cutout")
		(hatch edge 0.508)
		(connect_pads
			(clearance 0)
		)
		(min_thickness 0.254)
		(filled_areas_thickness no)
		(keepout
			(tracks allowed)
			(vias allowed)
			(pads allowed)
			(copperpour not_allowed)
			(footprints allowed)
		)
		(placement
			(enabled no)
			(sheetname "")
		)
		(fill
			(thermal_gap 0.508)
			(thermal_bridge_width 0.508)
		)
		(polygon
			(pts
				(xy 144.5133 84.4931) (xy 145.0848 85.0646) (xy 144.4498 85.6996) (xy 143.8783 85.1281)
			)
		)
	)
	(zone
		(net 0)
		(net_name "")
		(layers "F.Cu" "In1.Cu")
		(name "GND_cutout")
		(hatch edge 0.508)
		(connect_pads yes
			(clearance 0)
		)
		(min_thickness 0.254)
		(filled_areas_thickness no)
		(keepout
			(tracks allowed)
			(vias allowed)
			(pads allowed)
			(copperpour not_allowed)
			(footprints allowed)
		)
		(placement
			(enabled no)
			(sheetname "")
		)
		(fill
			(thermal_gap 0.508)
			(thermal_bridge_width 0.508)
		)
		(polygon
			(pts
				(xy 141.725 74.95) (xy 142.15 75.375) (xy 141.65 75.875) (xy 141.225 75.45)
			)
		)
	)
	(zone
		(net 0)
		(net_name "")
		(layers "F.Cu" "In1.Cu")
		(name "GND_cutout")
		(hatch edge 0.508)
		(connect_pads yes
			(clearance 0)
		)
		(min_thickness 0.254)
		(filled_areas_thickness no)
		(keepout
			(tracks allowed)
			(vias allowed)
			(pads allowed)
			(copperpour not_allowed)
			(footprints allowed)
		)
		(placement
			(enabled no)
			(sheetname "")
		)
		(fill
			(thermal_gap 0.508)
			(thermal_bridge_width 0.508)
		)
		(polygon
			(pts
				(xy 153.45 75.9) (xy 153.025 76.325) (xy 152.525 75.825) (xy 152.95 75.4)
			)
		)
	)
	(zone
		(net 0)
		(net_name "")
		(layers "F.Cu" "In1.Cu")
		(name "GND_cutout")
		(hatch edge 0.508)
		(connect_pads yes
			(clearance 0)
		)
		(min_thickness 0.254)
		(filled_areas_thickness no)
		(keepout
			(tracks allowed)
			(vias allowed)
			(pads allowed)
			(copperpour not_allowed)
			(footprints allowed)
		)
		(placement
			(enabled no)
			(sheetname "")
		)
		(fill
			(thermal_gap 0.508)
			(thermal_bridge_width 0.508)
		)
		(polygon
			(pts
				(xy 154.975 74.375) (xy 154.55 74.8) (xy 154.05 74.3) (xy 154.475 73.875)
			)
		)
	)
	(zone
		(net 0)
		(net_name "")
		(layers "F.Cu" "In1.Cu")
		(name "GND_cutout")
		(hatch edge 0.508)
		(connect_pads
			(clearance 0)
		)
		(min_thickness 0.254)
		(filled_areas_thickness no)
		(keepout
			(tracks allowed)
			(vias allowed)
			(pads allowed)
			(copperpour not_allowed)
			(footprints allowed)
		)
		(placement
			(enabled no)
			(sheetname "")
		)
		(fill
			(thermal_gap 0.508)
			(thermal_bridge_width 0.508)
		)
		(polygon
			(pts
				(xy 184.4802 84.582) (xy 183.2864 84.582) (xy 183.2864 84.328) (xy 183.2864 83.7692) (xy 184.4802 83.7692)
			)
		)
	)
	(zone
		(net 0)
		(net_name "")
		(layers "F.Cu" "In1.Cu")
		(name "GND_cutout")
		(hatch edge 0.508)
		(connect_pads
			(clearance 0)
		)
		(min_thickness 0.254)
		(filled_areas_thickness no)
		(keepout
			(tracks allowed)
			(vias allowed)
			(pads allowed)
			(copperpour not_allowed)
			(footprints allowed)
		)
		(placement
			(enabled no)
			(sheetname "")
		)
		(fill
			(thermal_gap 0.508)
			(thermal_bridge_width 0.508)
		)
		(polygon
			(pts
				(xy 148.5265 85.8393) (xy 147.955 86.4108) (xy 147.32 85.7758) (xy 147.8915 85.2043)
			)
		)
	)
	(zone
		(net 0)
		(net_name "")
		(layers "F.Cu" "In1.Cu")
		(name "GND_cutout")
		(hatch edge 0.508)
		(connect_pads yes
			(clearance 0)
		)
		(min_thickness 0.254)
		(filled_areas_thickness no)
		(keepout
			(tracks allowed)
			(vias allowed)
			(pads allowed)
			(copperpour not_allowed)
			(footprints allowed)
		)
		(placement
			(enabled no)
			(sheetname "")
		)
		(fill
			(thermal_gap 0.508)
			(thermal_bridge_width 0.508)
		)
		(polygon
			(pts
				(xy 164.8 44.542) (xy 162.775 44.542) (xy 162.775 39.242) (xy 164.8 39.242)
			)
		)
	)
	(zone
		(net 0)
		(net_name "")
		(layers "F.Cu" "In1.Cu")
		(name "GND_cutout")
		(hatch edge 0.508)
		(connect_pads yes
			(clearance 0)
		)
		(min_thickness 0.254)
		(filled_areas_thickness no)
		(keepout
			(tracks allowed)
			(vias allowed)
			(pads allowed)
			(copperpour not_allowed)
			(footprints allowed)
		)
		(placement
			(enabled no)
			(sheetname "")
		)
		(fill
			(thermal_gap 0.508)
			(thermal_bridge_width 0.508)
		)
		(polygon
			(pts
				(xy 139.525 75.8) (xy 139.95 76.225) (xy 139.45 76.725) (xy 139.025 76.3)
			)
		)
	)
	(zone
		(net 0)
		(net_name "")
		(layers "F.Cu" "In1.Cu")
		(name "GND_cutout")
		(hatch edge 0.508)
		(connect_pads
			(clearance 0)
		)
		(min_thickness 0.254)
		(filled_areas_thickness no)
		(keepout
			(tracks allowed)
			(vias allowed)
			(pads allowed)
			(copperpour not_allowed)
			(footprints allowed)
		)
		(placement
			(enabled no)
			(sheetname "")
		)
		(fill
			(thermal_gap 0.508)
			(thermal_bridge_width 0.508)
		)
		(polygon
			(pts
				(xy 184.4802 75.5904) (xy 183.2864 75.5904) (xy 183.2864 75.3364) (xy 183.2864 74.7776) (xy 184.4802 74.7776)
			)
		)
	)
	(zone
		(net 0)
		(net_name "")
		(layers "F.Cu" "In1.Cu" "In2.Cu")
		(name "GND_cutout")
		(hatch edge 0.508)
		(connect_pads yes
			(clearance 0)
		)
		(min_thickness 0.254)
		(filled_areas_thickness no)
		(keepout
			(tracks allowed)
			(vias allowed)
			(pads allowed)
			(copperpour not_allowed)
			(footprints allowed)
		)
		(placement
			(enabled no)
			(sheetname "")
		)
		(fill
			(thermal_gap 0.508)
			(thermal_bridge_width 0.508)
		)
		(polygon
			(pts
				(xy 126.97 54.125) (xy 124.975 54.125) (xy 124.975 53.05) (xy 126.97 53.05)
			)
		)
	)
	(zone
		(net 0)
		(net_name "")
		(layers "F.Cu" "In1.Cu" "In2.Cu")
		(name "GND_cutout")
		(hatch edge 0.508)
		(connect_pads yes
			(clearance 0)
		)
		(min_thickness 0.254)
		(filled_areas_thickness no)
		(keepout
			(tracks allowed)
			(vias allowed)
			(pads allowed)
			(copperpour not_allowed)
			(footprints allowed)
		)
		(placement
			(enabled no)
			(sheetname "")
		)
		(fill
			(thermal_gap 0.508)
			(thermal_bridge_width 0.508)
		)
		(polygon
			(pts
				(xy 140.408 54.125) (xy 139.175 54.125) (xy 139.175 53.05) (xy 140.408 53.05)
			)
		)
	)
	(zone
		(net 0)
		(net_name "")
		(layers "F.Cu" "In1.Cu" "In2.Cu")
		(name "GND_cutout")
		(hatch edge 0.508)
		(connect_pads yes
			(clearance 0)
		)
		(min_thickness 0.254)
		(filled_areas_thickness no)
		(keepout
			(tracks allowed)
			(vias allowed)
			(pads allowed)
			(copperpour not_allowed)
			(footprints allowed)
		)
		(placement
			(enabled no)
			(sheetname "")
		)
		(fill
			(thermal_gap 0.508)
			(thermal_bridge_width 0.508)
		)
		(polygon
			(pts
				(xy 161.15 58.3) (xy 158.375 58.3) (xy 158.4 54.975) (xy 161.15 54.975)
			)
		)
	)
	(zone
		(net 0)
		(net_name "")
		(layers "F.Cu" "In1.Cu" "In2.Cu")
		(name "GND_cutout")
		(hatch edge 0.508)
		(connect_pads yes
			(clearance 0)
		)
		(min_thickness 0.254)
		(filled_areas_thickness no)
		(keepout
			(tracks allowed)
			(vias allowed)
			(pads allowed)
			(copperpour not_allowed)
			(footprints allowed)
		)
		(placement
			(enabled no)
			(sheetname "")
		)
		(fill
			(thermal_gap 0.508)
			(thermal_bridge_width 0.508)
		)
		(polygon
			(pts
				(xy 126.35 58.3) (xy 123.575 58.3) (xy 123.6 54.975) (xy 126.35 54.975)
			)
		)
	)
	(zone
		(net 0)
		(net_name "")
		(layers "F.Cu" "In1.Cu" "In2.Cu")
		(name "GND_cutout")
		(hatch edge 0.508)
		(connect_pads yes
			(clearance 0)
		)
		(min_thickness 0.254)
		(filled_areas_thickness no)
		(keepout
			(tracks allowed)
			(vias allowed)
			(pads allowed)
			(copperpour not_allowed)
			(footprints allowed)
		)
		(placement
			(enabled no)
			(sheetname "")
		)
		(fill
			(thermal_gap 0.508)
			(thermal_bridge_width 0.508)
		)
		(polygon
			(pts
				(xy 138.3 58.3) (xy 135.525 58.3) (xy 135.55 54.975) (xy 138.3 54.975)
			)
		)
	)
	(zone
		(net 0)
		(net_name "")
		(layers "F.Cu" "In1.Cu" "In2.Cu")
		(name "GND_cutout")
		(hatch edge 0.508)
		(connect_pads yes
			(clearance 0)
		)
		(min_thickness 0.254)
		(filled_areas_thickness no)
		(keepout
			(tracks allowed)
			(vias allowed)
			(pads allowed)
			(copperpour not_allowed)
			(footprints allowed)
		)
		(placement
			(enabled no)
			(sheetname "")
		)
		(fill
			(thermal_gap 0.508)
			(thermal_bridge_width 0.508)
		)
		(polygon
			(pts
				(xy 149.725 58.3) (xy 146.95 58.3) (xy 146.975 54.975) (xy 149.725 54.975)
			)
		)
	)
	(zone
		(net 0)
		(net_name "")
		(layers "F.Cu" "In1.Cu" "In2.Cu")
		(name "GND_cutout")
		(hatch edge 0.508)
		(connect_pads yes
			(clearance 0)
		)
		(min_thickness 0.254)
		(filled_areas_thickness no)
		(keepout
			(tracks allowed)
			(vias allowed)
			(pads allowed)
			(copperpour not_allowed)
			(footprints allowed)
		)
		(placement
			(enabled no)
			(sheetname "")
		)
		(fill
			(thermal_gap 0.508)
			(thermal_bridge_width 0.508)
		)
		(polygon
			(pts
				(xy 138.67 54.125) (xy 136.675 54.125) (xy 136.675 53.05) (xy 138.67 53.05)
			)
		)
	)
	(zone
		(net 0)
		(net_name "")
		(layers "F.Cu" "In1.Cu" "In2.Cu")
		(name "GND_cutout")
		(hatch edge 0.508)
		(connect_pads yes
			(clearance 0)
		)
		(min_thickness 0.254)
		(filled_areas_thickness no)
		(keepout
			(tracks allowed)
			(vias allowed)
			(pads allowed)
			(copperpour not_allowed)
			(footprints allowed)
		)
		(placement
			(enabled no)
			(sheetname "")
		)
		(fill
			(thermal_gap 0.508)
			(thermal_bridge_width 0.508)
		)
		(polygon
			(pts
				(xy 128.758 54.125) (xy 127.525 54.125) (xy 127.525 53.05) (xy 128.758 53.05)
			)
		)
	)
	(zone
		(net 0)
		(net_name "")
		(layers "F.Cu" "In1.Cu" "In2.Cu")
		(name "GND_cutout")
		(hatch edge 0.508)
		(connect_pads yes
			(clearance 0)
		)
		(min_thickness 0.254)
		(filled_areas_thickness no)
		(keepout
			(tracks allowed)
			(vias allowed)
			(pads allowed)
			(copperpour not_allowed)
			(footprints allowed)
		)
		(placement
			(enabled no)
			(sheetname "")
		)
		(fill
			(thermal_gap 0.508)
			(thermal_bridge_width 0.508)
		)
		(polygon
			(pts
				(xy 163.258 54.125) (xy 162.025 54.125) (xy 162.025 53.05) (xy 163.258 53.05)
			)
		)
	)
	(zone
		(net 0)
		(net_name "")
		(layers "F.Cu" "In1.Cu" "In2.Cu")
		(name "GND_cutout")
		(hatch edge 0.508)
		(connect_pads yes
			(clearance 0)
		)
		(min_thickness 0.254)
		(filled_areas_thickness no)
		(keepout
			(tracks allowed)
			(vias allowed)
			(pads allowed)
			(copperpour not_allowed)
			(footprints allowed)
		)
		(placement
			(enabled no)
			(sheetname "")
		)
		(fill
			(thermal_gap 0.508)
			(thermal_bridge_width 0.508)
		)
		(polygon
			(pts
				(xy 161.52 54.125) (xy 159.525 54.125) (xy 159.525 53.05) (xy 161.52 53.05)
			)
		)
	)
	(zone
		(net 0)
		(net_name "")
		(layers "F.Cu" "In1.Cu" "In2.Cu")
		(name "GND_cutout")
		(hatch edge 0.508)
		(connect_pads yes
			(clearance 0)
		)
		(min_thickness 0.254)
		(filled_areas_thickness no)
		(keepout
			(tracks allowed)
			(vias allowed)
			(pads allowed)
			(copperpour not_allowed)
			(footprints allowed)
		)
		(placement
			(enabled no)
			(sheetname "")
		)
		(fill
			(thermal_gap 0.508)
			(thermal_bridge_width 0.508)
		)
		(polygon
			(pts
				(xy 150.095 54.125) (xy 148.1 54.125) (xy 148.1 53.05) (xy 150.095 53.05)
			)
		)
	)
	(zone
		(net 0)
		(net_name "")
		(layers "F.Cu" "In1.Cu" "In2.Cu")
		(name "GND_cutout")
		(hatch edge 0.508)
		(connect_pads yes
			(clearance 0)
		)
		(min_thickness 0.254)
		(filled_areas_thickness no)
		(keepout
			(tracks allowed)
			(vias allowed)
			(pads allowed)
			(copperpour not_allowed)
			(footprints allowed)
		)
		(placement
			(enabled no)
			(sheetname "")
		)
		(fill
			(thermal_gap 0.508)
			(thermal_bridge_width 0.508)
		)
		(polygon
			(pts
				(xy 151.883 54.125) (xy 150.65 54.125) (xy 150.65 53.05) (xy 151.883 53.05)
			)
		)
	)
	(zone
		(net 1)
		(net_name "GND")
		(layers "In1.Cu" "In2.Cu")
		(name "GND")
		(hatch edge 0.508)
		(connect_pads
			(clearance 0.2)
		)
		(min_thickness 0.254)
		(filled_areas_thickness no)
		(fill yes
			(thermal_gap 0.508)
			(thermal_bridge_width 0.508)
		)
		(polygon
			(pts
				(xy 190.498 99.164) (xy 115.498 99.164) (xy 115.498 39.164) (xy 190.498 39.164)
			)
		)
	)
	(zone
		(net 4)
		(net_name "+12V")
		(layer "In2.Cu")
		(name "+12V")
		(hatch edge 0.508)
		(priority 1)
		(connect_pads
			(clearance 0.254)
		)
		(min_thickness 0.254)
		(filled_areas_thickness no)
		(fill yes
			(thermal_gap 0.508)
			(thermal_bridge_width 0.508)
		)
		(polygon
			(pts
				(xy 181.53 57.023) (xy 181.53 58.52) (xy 180.768 59.028) (xy 166.878 59.028) (xy 163.322 62.484)
				(xy 160.782 62.484) (xy 159.94 63.246) (xy 159.94 66.04) (xy 159.178 66.675) (xy 134.112 66.675)
				(xy 133.477 67.31) (xy 133.477 81.534) (xy 132.842 82.169) (xy 128.905 82.169) (xy 128.27 82.804)
				(xy 128.27 90.805) (xy 128.905 91.44) (xy 139.065 91.44) (xy 139.7 92.075) (xy 139.7 96.774) (xy 139.065 97.409)
				(xy 130.175 97.409) (xy 129.54 96.774) (xy 129.54 93.345) (xy 128.905 92.71) (xy 127.635 92.71)
				(xy 127 92.075) (xy 127 87.63) (xy 125.984 86.36) (xy 118.745 86.36) (xy 118.11 85.725) (xy 118.11 84.328)
				(xy 118.745 83.693) (xy 125.222 83.693) (xy 125.857 83.058) (xy 125.857 80.264) (xy 126.492 79.629)
				(xy 130.81 79.629) (xy 131.445 78.994) (xy 131.445 67.31) (xy 130.81 66.675) (xy 121.158 66.675)
				(xy 120.523 66.04) (xy 120.523 64.262) (xy 121.158 63.754) (xy 155.622 63.754) (xy 156.384 63.246)
				(xy 156.384 59.944) (xy 157.146 59.182) (xy 161.29 59.182) (xy 164.338 56.234) (xy 180.768 56.234)
			)
		)
	)
)
